G04 ================== begin FILE IDENTIFICATION RECORD ==================*
G04 Layout Name:  15126-1b.brd*
G04 Film Name:    L14*
G04 File Format:  Gerber RS274X*
G04 File Origin:  Cadence Allegro 16.6-2015-S079*
G04 Origin Date:  Fri Feb 10 17:23:29 2017*
G04 *
G04 Layer:  VIA CLASS/BOTTOM*
G04 Layer:  PIN/BOTTOM*
G04 Layer:  ETCH/BOTTOM*
G04 Layer:  DRAWING FORMAT/LAYER_PCB_STORY*
G04 Layer:  DRAWING FORMAT/LAYER_L14*
G04 *
G04 Offset:    (0.00 0.00)*
G04 Mirror:    No*
G04 Mode:      Positive*
G04 Rotation:  0*
G04 FullContactRelief:  No*
G04 UndefLineWidth:     6.00*
G04 ================== end FILE IDENTIFICATION RECORD ====================*
%FSLAX35Y35*MOIN*%
%IR0*IPPOS*OFA0.00000B0.00000*MIA0B0*SFA1.00000B1.00000*%
%AMMACRO131*
4,1,40,.011,.007,
.011,-.007,
.010939,-.007695,
.010759,-.008368,
.010464,-.009,
.010064,-.009571,
.009571,-.010064,
.009,-.010464,
.008368,-.010759,
.007695,-.010939,
.007,-.011,
-.007,-.011,
-.007695,-.010939,
-.008368,-.010759,
-.009,-.010464,
-.009571,-.010064,
-.010064,-.009571,
-.010464,-.009,
-.010759,-.008368,
-.010939,-.007695,
-.011,-.007,
-.011,.007,
-.010939,.007695,
-.010759,.008368,
-.010464,.009,
-.010064,.009571,
-.009571,.010064,
-.009,.010464,
-.008368,.010759,
-.007695,.010939,
-.007,.011,
.007,.011,
.007695,.010939,
.008368,.010759,
.009,.010464,
.009571,.010064,
.010064,.009571,
.010464,.009,
.010759,.008368,
.010939,.007695,
.011,.007,
0.0*
%
%ADD131MACRO131*%
%AMMACRO162*
4,1,40,-.017,-.013,
-.017,.013,
-.016939,.013695,
-.016759,.014368,
-.016464,.015,
-.016064,.015571,
-.015571,.016064,
-.015,.016464,
-.014368,.016759,
-.013695,.016939,
-.013,.017,
.013,.017,
.013695,.016939,
.014368,.016759,
.015,.016464,
.015571,.016064,
.016064,.015571,
.016464,.015,
.016759,.014368,
.016939,.013695,
.017,.013,
.017,-.013,
.016939,-.013695,
.016759,-.014368,
.016464,-.015,
.016064,-.015571,
.015571,-.016064,
.015,-.016464,
.014368,-.016759,
.013695,-.016939,
.013,-.017,
-.013,-.017,
-.013695,-.016939,
-.014368,-.016759,
-.015,-.016464,
-.015571,-.016064,
-.016064,-.015571,
-.016464,-.015,
-.016759,-.014368,
-.016939,-.013695,
-.017,-.013,
0.0*
%
%ADD162MACRO162*%
%AMMACRO158*
4,1,40,.013,-.017,
-.013,-.017,
-.013695,-.016939,
-.014368,-.016759,
-.015,-.016464,
-.015571,-.016064,
-.016064,-.015571,
-.016464,-.015,
-.016759,-.014368,
-.016939,-.013695,
-.017,-.013,
-.017,.013,
-.016939,.013695,
-.016759,.014368,
-.016464,.015,
-.016064,.015571,
-.015571,.016064,
-.015,.016464,
-.014368,.016759,
-.013695,.016939,
-.013,.017,
.013,.017,
.013695,.016939,
.014368,.016759,
.015,.016464,
.015571,.016064,
.016064,.015571,
.016464,.015,
.016759,.014368,
.016939,.013695,
.017,.013,
.017,-.013,
.016939,-.013695,
.016759,-.014368,
.016464,-.015,
.016064,-.015571,
.015571,-.016064,
.015,-.016464,
.014368,-.016759,
.013695,-.016939,
.013,-.017,
0.0*
%
%ADD158MACRO158*%
%AMMACRO146*
4,1,40,.0105,.015,
-.0105,.015,
-.011195,.014939,
-.011868,.014759,
-.0125,.014464,
-.013071,.014064,
-.013564,.013571,
-.013964,.013,
-.014259,.012368,
-.014439,.011695,
-.0145,.011,
-.0145,-.011,
-.014439,-.011695,
-.014259,-.012368,
-.013964,-.013,
-.013564,-.013571,
-.013071,-.014064,
-.0125,-.014464,
-.011868,-.014759,
-.011195,-.014939,
-.0105,-.015,
.0105,-.015,
.011195,-.014939,
.011868,-.014759,
.0125,-.014464,
.013071,-.014064,
.013564,-.013571,
.013964,-.013,
.014259,-.012368,
.014439,-.011695,
.0145,-.011,
.0145,.011,
.014439,.011695,
.014259,.012368,
.013964,.013,
.013564,.013571,
.013071,.014064,
.0125,.014464,
.011868,.014759,
.011195,.014939,
.0105,.015,
0.0*
%
%ADD146MACRO146*%
%AMMACRO99*
21,1,.02,.005,0.0,0.0,11.*%
%ADD99MACRO99*%
%AMMACRO100*
21,1,.02,.005,0.0,0.0,12.*%
%ADD100MACRO100*%
%ADD81O,.062X.111*%
%AMMACRO137*
21,1,.004,.02,0.0,0.0,11.32*%
%ADD137MACRO137*%
%AMMACRO147*
21,1,.02,.005,0.0,0.0,16.*%
%ADD147MACRO147*%
%AMMACRO98*
21,1,.02,.005,0.0,0.0,11.5*%
%ADD98MACRO98*%
%ADD80R,.02X.004*%
%AMMACRO57*
4,1,8,.0825,.065,
.0825,-.065,
-.0175,-.065,
-.0175,-.087,
-.0825,-.087,
-.0825,.087,
-.0175,.087,
-.0175,.065,
.0825,.065,
0.0*
%
%ADD57MACRO57*%
%AMMACRO138*
21,1,.02,.005,0.0,0.0,22.5*%
%ADD138MACRO138*%
%AMMACRO123*
4,1,24,-.006,-.00425,
-.005479,-.004296,
-.004974,-.004431,
-.0045,-.004652,
-.004072,-.004952,
-.003702,-.005322,
-.003402,-.00575,
-.003181,-.006224,
-.003046,-.006729,
-.003,-.00725,
-.003,-.00875,
.003,-.00875,
.003,-.00725,
.003046,-.006729,
.003181,-.006224,
.003402,-.00575,
.003702,-.005322,
.004072,-.004952,
.0045,-.004652,
.004974,-.004431,
.005479,-.004296,
.006,-.00425,
.006,.00875,
-.006,.00875,
-.006,-.00425,
0.0*
%
%ADD123MACRO123*%
%ADD95R,.004X.02*%
%AMMACRO78*
4,1,24,.00425,-.006,
.004296,-.005479,
.004431,-.004974,
.004652,-.0045,
.004952,-.004072,
.005322,-.003702,
.00575,-.003402,
.006224,-.003181,
.006729,-.003046,
.00725,-.003,
.00875,-.003,
.00875,.003,
.00725,.003,
.006729,.003046,
.006224,.003181,
.00575,.003402,
.005322,.003702,
.004952,.004072,
.004652,.0045,
.004431,.004974,
.004296,.005479,
.00425,.006,
-.00875,.006,
-.00875,-.006,
.00425,-.006,
0.0*
%
%ADD78MACRO78*%
%ADD68R,.005X.02*%
%AMMACRO58*
21,1,.02,.005,0.0,0.0,45.*%
%ADD58MACRO58*%
%ADD52R,.02X.005*%
%AMMACRO37*
4,1,12,-.0195,-.0325,
-.0195,.0325,
.0195,.0325,
.0195,.0195,
-.0005,.0195,
-.0005,.0065,
.0195,.0065,
.0195,-.0065,
-.0005,-.0065,
-.0005,-.0195,
.0195,-.0195,
.0195,-.0325,
-.0195,-.0325,
0.0*
%
%ADD37MACRO37*%
%ADD36R,.134X.024*%
%ADD21C,.01*%
%ADD14R,.053X.106*%
%ADD12C,.02*%
%ADD221C,.03*%
%ADD212R,.008X.014*%
%ADD165C,.031*%
%ADD24C,.04*%
%ADD10C,.022*%
%ADD197R,.014X.008*%
%ADD118C,.05*%
%AMMACRO39*
4,1,16,.0495,.045,
.0495,-.045,
-.0495,-.045,
-.0495,-.032,
-.0185,-.032,
-.0185,-.01933,
-.0495,-.01933,
-.0495,-.00633,
-.0185,-.00633,
-.0185,.00633,
-.0495,.00633,
-.0495,.01933,
-.0185,.01933,
-.0185,.032,
-.0495,.032,
-.0495,.045,
.0495,.045,
0.0*
%
%ADD39MACRO39*%
%ADD16C,.032*%
%ADD35R,.134X.047*%
%ADD23C,.06*%
%ADD18C,.024*%
%ADD191C,.052*%
%ADD15C,.034*%
%ADD33C,.044*%
%ADD20C,.026*%
%ADD17C,.071*%
%ADD153C,.054*%
%AMMACRO89*
21,1,.02,.005,0.0,0.0,78.302*%
%ADD89MACRO89*%
%ADD76C,.018*%
%ADD53C,.045*%
%ADD217C,.055*%
%ADD127C,.064*%
%AMMACRO94*
21,1,.02,.005,0.0,0.0,79.032*%
%ADD94MACRO94*%
%ADD82C,.019*%
%ADD54C,.028*%
%ADD34C,.046*%
%ADD201C,.047*%
%ADD174R,.031X.031*%
%ADD142C,.056*%
%AMMACRO129*
21,1,.02,.005,0.0,0.0,.657*%
%ADD129MACRO129*%
%ADD49C,.039*%
%ADD45C,.057*%
%AMMACRO112*
21,1,.02,.005,0.0,0.0,88.125*%
%ADD112MACRO112*%
%ADD22R,.06X.06*%
%AMMACRO110*
21,1,.02,.005,0.0,0.0,88.522*%
%ADD110MACRO110*%
%AMMACRO107*
21,1,.02,.005,0.0,0.0,76.651*%
%ADD107MACRO107*%
%AMMACRO102*
21,1,.02,.005,0.0,0.0,50.659*%
%ADD102MACRO102*%
%AMMACRO101*
21,1,.02,.005,0.0,0.0,75.526*%
%ADD101MACRO101*%
%AMMACRO73*
4,1,8,-.0585,-.0835,
-.0585,.0835,
.0585,.0835,
.0585,.04275,
.0185,.04275,
.0185,-.04275,
.0585,-.04275,
.0585,-.0835,
-.0585,-.0835,
0.0*
%
%ADD73MACRO73*%
%ADD195R,.045X.045*%
%ADD179R,.072X.072*%
%AMMACRO172*
21,1,.02,.005,0.0,0.0,90.657*%
%ADD172MACRO172*%
%AMMACRO171*
21,1,.02,.005,0.0,0.0,45.657*%
%ADD171MACRO171*%
%ADD166R,.054X.054*%
%AMMACRO111*
21,1,.02,.005,0.0,0.0,88.245*%
%ADD111MACRO111*%
%ADD218R,.055X.055*%
%ADD139R,.037X.037*%
%ADD128R,.064X.064*%
%AMMACRO114*
21,1,.02,.005,0.0,0.0,87.823*%
%ADD114MACRO114*%
%ADD202R,.047X.047*%
%AMMACRO113*
21,1,.02,.005,0.0,0.0,88.67*%
%ADD113MACRO113*%
%AMMACRO90*
21,1,.02,.005,0.0,0.0,78.329*%
%ADD90MACRO90*%
%AMMACRO88*
21,1,.02,.005,0.0,0.0,78.77*%
%ADD88MACRO88*%
%AMMACRO176*
4,1,40,-.011,-.007,
-.011,.007,
-.010939,.007695,
-.010759,.008368,
-.010464,.009,
-.010064,.009571,
-.009571,.010064,
-.009,.010464,
-.008368,.010759,
-.007695,.010939,
-.007,.011,
.007,.011,
.007695,.010939,
.008368,.010759,
.009,.010464,
.009571,.010064,
.010064,.009571,
.010464,.009,
.010759,.008368,
.010939,.007695,
.011,.007,
.011,-.007,
.010939,-.007695,
.010759,-.008368,
.010464,-.009,
.010064,-.009571,
.009571,-.010064,
.009,-.010464,
.008368,-.010759,
.007695,-.010939,
.007,-.011,
-.007,-.011,
-.007695,-.010939,
-.008368,-.010759,
-.009,-.010464,
-.009571,-.010064,
-.010064,-.009571,
-.010464,-.009,
-.010759,-.008368,
-.010939,-.007695,
-.011,-.007,
0.0*
%
%ADD176MACRO176*%
%AMMACRO108*
21,1,.02,.005,0.0,0.0,88.86*%
%ADD108MACRO108*%
%AMMACRO66*
4,1,40,.007,-.011,
-.007,-.011,
-.007695,-.010939,
-.008368,-.010759,
-.009,-.010464,
-.009571,-.010064,
-.010064,-.009571,
-.010464,-.009,
-.010759,-.008368,
-.010939,-.007695,
-.011,-.007,
-.011,.007,
-.010939,.007695,
-.010759,.008368,
-.010464,.009,
-.010064,.009571,
-.009571,.010064,
-.009,.010464,
-.008368,.010759,
-.007695,.010939,
-.007,.011,
.007,.011,
.007695,.010939,
.008368,.010759,
.009,.010464,
.009571,.010064,
.010064,.009571,
.010464,.009,
.010759,.008368,
.010939,.007695,
.011,.007,
.011,-.007,
.010939,-.007695,
.010759,-.008368,
.010464,-.009,
.010064,-.009571,
.009571,-.010064,
.009,-.010464,
.008368,-.010759,
.007695,-.010939,
.007,-.011,
0.0*
%
%ADD66MACRO66*%
%ADD50R,.039X.039*%
%AMMACRO106*
21,1,.02,.005,0.0,0.0,88.474*%
%ADD106MACRO106*%
%AMMACRO115*
21,1,.02,.005,0.0,0.0,88.493*%
%ADD115MACRO115*%
%AMMACRO28*
4,1,40,-.012,-.008,
-.012,.008,
-.011939,.008695,
-.011759,.009368,
-.011464,.01,
-.011064,.010571,
-.010571,.011064,
-.01,.011464,
-.009368,.011759,
-.008695,.011939,
-.008,.012,
.008,.012,
.008695,.011939,
.009368,.011759,
.01,.011464,
.010571,.011064,
.011064,.010571,
.011464,.01,
.011759,.009368,
.011939,.008695,
.012,.008,
.012,-.008,
.011939,-.008695,
.011759,-.009368,
.011464,-.01,
.011064,-.010571,
.010571,-.011064,
.01,-.011464,
.009368,-.011759,
.008695,-.011939,
.008,-.012,
-.008,-.012,
-.008695,-.011939,
-.009368,-.011759,
-.01,-.011464,
-.010571,-.011064,
-.011064,-.010571,
-.011464,-.01,
-.011759,-.009368,
-.011939,-.008695,
-.012,-.008,
0.0*
%
%ADD28MACRO28*%
%AMMACRO134*
4,1,8,.0034,.0082,
-.0034,.0082,
-.0082,.0034,
-.0082,-.00341,
-.00341,-.0082,
.0034,-.0082,
.0082,-.0034,
.0082,.0034,
.0034,.0082,
0.0*
%
%ADD134MACRO134*%
%AMMACRO69*
4,1,40,-.008,.012,
.008,.012,
.008695,.011939,
.009368,.011759,
.01,.011464,
.010571,.011064,
.011064,.010571,
.011464,.01,
.011759,.009368,
.011939,.008695,
.012,.008,
.012,-.008,
.011939,-.008695,
.011759,-.009368,
.011464,-.01,
.011064,-.010571,
.010571,-.011064,
.01,-.011464,
.009368,-.011759,
.008695,-.011939,
.008,-.012,
-.008,-.012,
-.008695,-.011939,
-.009368,-.011759,
-.01,-.011464,
-.010571,-.011064,
-.011064,-.010571,
-.011464,-.01,
-.011759,-.009368,
-.011939,-.008695,
-.012,-.008,
-.012,.008,
-.011939,.008695,
-.011759,.009368,
-.011464,.01,
-.011064,.010571,
-.010571,.011064,
-.01,.011464,
-.009368,.011759,
-.008695,.011939,
-.008,.012,
0.0*
%
%ADD69MACRO69*%
%AMMACRO155*
4,1,40,-.013,.017,
.013,.017,
.013695,.016939,
.014368,.016759,
.015,.016464,
.015571,.016064,
.016064,.015571,
.016464,.015,
.016759,.014368,
.016939,.013695,
.017,.013,
.017,-.013,
.016939,-.013695,
.016759,-.014368,
.016464,-.015,
.016064,-.015571,
.015571,-.016064,
.015,-.016464,
.014368,-.016759,
.013695,-.016939,
.013,-.017,
-.013,-.017,
-.013695,-.016939,
-.014368,-.016759,
-.015,-.016464,
-.015571,-.016064,
-.016064,-.015571,
-.016464,-.015,
-.016759,-.014368,
-.016939,-.013695,
-.017,-.013,
-.017,.013,
-.016939,.013695,
-.016759,.014368,
-.016464,.015,
-.016064,.015571,
-.015571,.016064,
-.015,.016464,
-.014368,.016759,
-.013695,.016939,
-.013,.017,
0.0*
%
%ADD155MACRO155*%
%AMMACRO136*
4,1,8,.0082,-.0034,
.0082,.0034,
.0034,.0082,
-.00341,.0082,
-.0082,.00341,
-.0082,-.0034,
-.0034,-.0082,
.0034,-.0082,
.0082,-.0034,
0.0*
%
%ADD136MACRO136*%
%AMMACRO159*
4,1,40,.017,.013,
.017,-.013,
.016939,-.013695,
.016759,-.014368,
.016464,-.015,
.016064,-.015571,
.015571,-.016064,
.015,-.016464,
.014368,-.016759,
.013695,-.016939,
.013,-.017,
-.013,-.017,
-.013695,-.016939,
-.014368,-.016759,
-.015,-.016464,
-.015571,-.016064,
-.016064,-.015571,
-.016464,-.015,
-.016759,-.014368,
-.016939,-.013695,
-.017,-.013,
-.017,.013,
-.016939,.013695,
-.016759,.014368,
-.016464,.015,
-.016064,.015571,
-.015571,.016064,
-.015,.016464,
-.014368,.016759,
-.013695,.016939,
-.013,.017,
.013,.017,
.013695,.016939,
.014368,.016759,
.015,.016464,
.015571,.016064,
.016064,.015571,
.016464,.015,
.016759,.014368,
.016939,.013695,
.017,.013,
0.0*
%
%ADD159MACRO159*%
%AMMACRO109*
21,1,.02,.005,0.0,0.0,88.889*%
%ADD109MACRO109*%
%AMMACRO177*
4,1,40,-.011,-.007,
-.011,.007,
-.010939,.007695,
-.010759,.008368,
-.010464,.009,
-.010064,.009571,
-.009571,.010064,
-.009,.010464,
-.008368,.010759,
-.007695,.010939,
-.007,.011,
.007,.011,
.007695,.010939,
.008368,.010759,
.009,.010464,
.009571,.010064,
.010064,.009571,
.010464,.009,
.010759,.008368,
.010939,.007695,
.011,.007,
.011,-.007,
.010939,-.007695,
.010759,-.008368,
.010464,-.009,
.010064,-.009571,
.009571,-.010064,
.009,-.010464,
.008368,-.010759,
.007695,-.010939,
.007,-.011,
-.007,-.011,
-.007695,-.010939,
-.008368,-.010759,
-.009,-.010464,
-.009571,-.010064,
-.010064,-.009571,
-.010464,-.009,
-.010759,-.008368,
-.010939,-.007695,
-.011,-.007,
0.0*
%
%ADD177MACRO177*%
%AMMACRO67*
4,1,40,.007,-.011,
-.007,-.011,
-.007695,-.010939,
-.008368,-.010759,
-.009,-.010464,
-.009571,-.010064,
-.010064,-.009571,
-.010464,-.009,
-.010759,-.008368,
-.010939,-.007695,
-.011,-.007,
-.011,.007,
-.010939,.007695,
-.010759,.008368,
-.010464,.009,
-.010064,.009571,
-.009571,.010064,
-.009,.010464,
-.008368,.010759,
-.007695,.010939,
-.007,.011,
.007,.011,
.007695,.010939,
.008368,.010759,
.009,.010464,
.009571,.010064,
.010064,.009571,
.010464,.009,
.010759,.008368,
.010939,.007695,
.011,.007,
.011,-.007,
.010939,-.007695,
.010759,-.008368,
.010464,-.009,
.010064,-.009571,
.009571,-.010064,
.009,-.010464,
.008368,-.010759,
.007695,-.010939,
.007,-.011,
0.0*
%
%ADD67MACRO67*%
%AMMACRO145*
4,1,40,-.0105,-.015,
.0105,-.015,
.011195,-.014939,
.011868,-.014759,
.0125,-.014464,
.013071,-.014064,
.013564,-.013571,
.013964,-.013,
.014259,-.012368,
.014439,-.011695,
.0145,-.011,
.0145,.011,
.014439,.011695,
.014259,.012368,
.013964,.013,
.013564,.013571,
.013071,.014064,
.0125,.014464,
.011868,.014759,
.011195,.014939,
.0105,.015,
-.0105,.015,
-.011195,.014939,
-.011868,.014759,
-.0125,.014464,
-.013071,.014064,
-.013564,.013571,
-.013964,.013,
-.014259,.012368,
-.014439,.011695,
-.0145,.011,
-.0145,-.011,
-.014439,-.011695,
-.014259,-.012368,
-.013964,-.013,
-.013564,-.013571,
-.013071,-.014064,
-.0125,-.014464,
-.011868,-.014759,
-.011195,-.014939,
-.0105,-.015,
0.0*
%
%ADD145MACRO145*%
%ADD27R,.12X.1*%
%ADD48R,.1X.12*%
%AMMACRO29*
4,1,40,-.012,-.008,
-.012,.008,
-.011939,.008695,
-.011759,.009368,
-.011464,.01,
-.011064,.010571,
-.010571,.011064,
-.01,.011464,
-.009368,.011759,
-.008695,.011939,
-.008,.012,
.008,.012,
.008695,.011939,
.009368,.011759,
.01,.011464,
.010571,.011064,
.011064,.010571,
.011464,.01,
.011759,.009368,
.011939,.008695,
.012,.008,
.012,-.008,
.011939,-.008695,
.011759,-.009368,
.011464,-.01,
.011064,-.010571,
.010571,-.011064,
.01,-.011464,
.009368,-.011759,
.008695,-.011939,
.008,-.012,
-.008,-.012,
-.008695,-.011939,
-.009368,-.011759,
-.01,-.011464,
-.010571,-.011064,
-.011064,-.010571,
-.011464,-.01,
-.011759,-.009368,
-.011939,-.008695,
-.012,-.008,
0.0*
%
%ADD29MACRO29*%
%AMMACRO70*
4,1,40,-.008,.012,
.008,.012,
.008695,.011939,
.009368,.011759,
.01,.011464,
.010571,.011064,
.011064,.010571,
.011464,.01,
.011759,.009368,
.011939,.008695,
.012,.008,
.012,-.008,
.011939,-.008695,
.011759,-.009368,
.011464,-.01,
.011064,-.010571,
.010571,-.011064,
.01,-.011464,
.009368,-.011759,
.008695,-.011939,
.008,-.012,
-.008,-.012,
-.008695,-.011939,
-.009368,-.011759,
-.01,-.011464,
-.010571,-.011064,
-.011064,-.010571,
-.011464,-.01,
-.011759,-.009368,
-.011939,-.008695,
-.012,-.008,
-.012,.008,
-.011939,.008695,
-.011759,.009368,
-.011464,.01,
-.011064,.010571,
-.010571,.011064,
-.01,.011464,
-.009368,.011759,
-.008695,.011939,
-.008,.012,
0.0*
%
%ADD70MACRO70*%
%AMMACRO156*
4,1,40,-.013,.017,
.013,.017,
.013695,.016939,
.014368,.016759,
.015,.016464,
.015571,.016064,
.016064,.015571,
.016464,.015,
.016759,.014368,
.016939,.013695,
.017,.013,
.017,-.013,
.016939,-.013695,
.016759,-.014368,
.016464,-.015,
.016064,-.015571,
.015571,-.016064,
.015,-.016464,
.014368,-.016759,
.013695,-.016939,
.013,-.017,
-.013,-.017,
-.013695,-.016939,
-.014368,-.016759,
-.015,-.016464,
-.015571,-.016064,
-.016064,-.015571,
-.016464,-.015,
-.016759,-.014368,
-.016939,-.013695,
-.017,-.013,
-.017,.013,
-.016939,.013695,
-.016759,.014368,
-.016464,.015,
-.016064,.015571,
-.015571,.016064,
-.015,.016464,
-.014368,.016759,
-.013695,.016939,
-.013,.017,
0.0*
%
%ADD156MACRO156*%
%ADD26R,.02X.02*%
%AMMACRO160*
4,1,40,.017,.013,
.017,-.013,
.016939,-.013695,
.016759,-.014368,
.016464,-.015,
.016064,-.015571,
.015571,-.016064,
.015,-.016464,
.014368,-.016759,
.013695,-.016939,
.013,-.017,
-.013,-.017,
-.013695,-.016939,
-.014368,-.016759,
-.015,-.016464,
-.015571,-.016064,
-.016064,-.015571,
-.016464,-.015,
-.016759,-.014368,
-.016939,-.013695,
-.017,-.013,
-.017,.013,
-.016939,.013695,
-.016759,.014368,
-.016464,.015,
-.016064,.015571,
-.015571,.016064,
-.015,.016464,
-.014368,.016759,
-.013695,.016939,
-.013,.017,
.013,.017,
.013695,.016939,
.014368,.016759,
.015,.016464,
.015571,.016064,
.016064,.015571,
.016464,.015,
.016759,.014368,
.016939,.013695,
.017,.013,
0.0*
%
%ADD160MACRO160*%
%ADD19R,.02X.02*%
%AMMACRO59*
21,1,.02,.005,0.0,0.0,135.*%
%ADD59MACRO59*%
%ADD207O,.041X.06*%
%ADD205R,.06X.01*%
%ADD199R,.05X.02*%
%ADD210R,.022X.04*%
%AMMACRO182*
4,1,21,.015,.006,
-.009,.006,
-.010042,.005909,
-.011052,.005638,
-.012,.005196,
-.012857,.004596,
-.013596,.003857,
-.014196,.003,
-.014638,.002052,
-.014909,.001042,
-.015,0.0,
-.014909,-.001042,
-.014638,-.002052,
-.014196,-.003,
-.013596,-.003857,
-.012857,-.004596,
-.012,-.005196,
-.011052,-.005638,
-.010042,-.005909,
-.009,-.006,
.015,-.006,
.015,.006,
0.0*
%
%ADD182MACRO182*%
%ADD173R,.102X.145*%
%AMMACRO170*
21,1,.02,.005,0.0,0.0,135.11*%
%ADD170MACRO170*%
%AMMACRO141*
21,1,.02,.005,0.0,0.0,164.*%
%ADD141MACRO141*%
%AMMACRO92*
21,1,.02,.005,0.0,0.0,101.243*%
%ADD92MACRO92*%
%AMMACRO91*
21,1,.02,.005,0.0,0.0,101.144*%
%ADD91MACRO91*%
%ADD25R,.04X.05*%
%AMMACRO187*
4,1,21,.006,-.015,
.006,.009,
.005909,.010042,
.005638,.011052,
.005196,.012,
.004596,.012857,
.003857,.013596,
.003,.014196,
.002052,.014638,
.001042,.014909,
0.0,.015,
-.001042,.014909,
-.002052,.014638,
-.003,.014196,
-.003857,.013596,
-.004596,.012857,
-.005196,.012,
-.005638,.011052,
-.005909,.010042,
-.006,.009,
-.006,-.015,
.006,-.015,
0.0*
%
%ADD187MACRO187*%
%ADD184R,.014X.04*%
%ADD143R,.06X.03*%
%AMMACRO96*
21,1,.02,.005,0.0,0.0,160.5*%
%ADD96MACRO96*%
%ADD74R,.02X.071*%
%ADD71R,.05X.04*%
%ADD64R,.015X.04*%
%ADD40R,.04X.06*%
%ADD192R,.012X.026*%
%ADD151R,.06X.014*%
%ADD117R,.04X.015*%
%AMMACRO87*
21,1,.02,.005,0.0,0.0,166.*%
%ADD87MACRO87*%
%ADD62R,.012X.035*%
%ADD61R,.04X.016*%
%ADD60R,.035X.03*%
%ADD51R,.02X.045*%
%AMMACRO211*
4,1,48,.0225,.036,
.026668,.035635,
.030708,.034553,
.0345,.032785,
.037927,.030385,
.040885,.027427,
.043285,.024,
.045053,.020208,
.046135,.016168,
.0465,.012,
.046135,.007832,
.045053,.003792,
.043285,0.0,
.040885,-.003427,
.037927,-.006385,
.0345,-.008785,
.030708,-.010553,
.026668,-.011635,
.0225,-.012,
.0015,-.012,
.001135,-.016168,
.000053,-.020208,
-.001715,-.024,
-.004115,-.027427,
-.007073,-.030385,
-.0105,-.032785,
-.014292,-.034553,
-.018332,-.035635,
-.0225,-.036,
-.026668,-.035635,
-.030708,-.034553,
-.0345,-.032785,
-.037927,-.030385,
-.040885,-.027427,
-.043285,-.024,
-.045053,-.020208,
-.046135,-.016168,
-.0465,-.012,
-.0465,.012,
-.046135,.016168,
-.045053,.020208,
-.043285,.024,
-.040885,.027427,
-.037927,.030385,
-.0345,.032785,
-.030708,.034553,
-.026668,.035635,
-.0225,.036,
.0225,.036,
0.0*
%
%ADD211MACRO211*%
%ADD186R,.02X.055*%
%ADD178O,.032X.036*%
%ADD154R,.04X.016*%
%ADD149R,.016X.04*%
%ADD144R,.014X.06*%
%AMMACRO79*
4,1,24,-.00425,.006,
-.004296,.005479,
-.004431,.004974,
-.004652,.0045,
-.004952,.004072,
-.005322,.003702,
-.00575,.003402,
-.006224,.003181,
-.006729,.003046,
-.00725,.003,
-.00875,.003,
-.00875,-.003,
-.00725,-.003,
-.006729,-.003046,
-.006224,-.003181,
-.00575,-.003402,
-.005322,-.003702,
-.004952,-.004072,
-.004652,-.0045,
-.004431,-.004974,
-.004296,-.005479,
-.00425,-.006,
.00875,-.006,
.00875,.006,
-.00425,.006,
0.0*
%
%ADD79MACRO79*%
%ADD65R,.045X.02*%
%ADD55R,.03X.035*%
%ADD47C,.111*%
%ADD41R,.026X.012*%
%AMMACRO124*
4,1,24,.006,.00425,
.005479,.004296,
.004974,.004431,
.0045,.004652,
.004072,.004952,
.003702,.005322,
.003402,.00575,
.003181,.006224,
.003046,.006729,
.003,.00725,
.003,.00875,
-.003,.00875,
-.003,.00725,
-.003046,.006729,
-.003181,.006224,
-.003402,.00575,
-.003702,.005322,
-.004072,.004952,
-.0045,.004652,
-.004974,.004431,
-.005479,.004296,
-.006,.00425,
-.006,-.00875,
.006,-.00875,
.006,.00425,
0.0*
%
%ADD124MACRO124*%
%AMMACRO103*
21,1,.02,.005,0.0,0.0,159.*%
%ADD103MACRO103*%
%ADD63R,.012X.037*%
%ADD194O,.07X.046*%
%AMMACRO126*
21,1,.02,.005,0.0,0.0,146.5*%
%ADD126MACRO126*%
%ADD56R,.065X.02*%
%ADD31C,.14*%
%ADD44R,.018X.05*%
%ADD196R,.018X.07*%
%AMMACRO97*
21,1,.02,.005,0.0,0.0,148.5*%
%ADD97MACRO97*%
%ADD213R,.016X.037*%
%ADD193R,.063X.035*%
%ADD116R,.07X.018*%
%AMMACRO86*
21,1,.02,.005,0.0,0.0,167.5*%
%ADD86MACRO86*%
%ADD38R,.039X.013*%
%AMMACRO214*
21,1,.02,.005,0.0,0.0,166.601*%
%ADD214MACRO214*%
%ADD206R,.014X.048*%
%ADD198R,.037X.016*%
%ADD150R,.065X.025*%
%AMMACRO93*
21,1,.02,.005,0.0,0.0,100.577*%
%ADD93MACRO93*%
%AMMACRO84*
21,1,.02,.005,0.0,0.0,168.5*%
%ADD84MACRO84*%
%ADD42R,.035X.063*%
%AMMACRO183*
4,1,21,-.006,.015,
-.006,-.009,
-.005909,-.010042,
-.005638,-.011052,
-.005196,-.012,
-.004596,-.012857,
-.003857,-.013596,
-.003,-.014196,
-.002052,-.014638,
-.001042,-.014909,
0.0,-.015,
.001042,-.014909,
.002052,-.014638,
.003,-.014196,
.003857,-.013596,
.004596,-.012857,
.005196,-.012,
.005638,-.011052,
.005909,-.010042,
.006,-.009,
.006,.015,
-.006,.015,
0.0*
%
%ADD183MACRO183*%
%ADD175R,.048X.016*%
%AMMACRO140*
21,1,.02,.005,0.0,0.0,169.5*%
%ADD140MACRO140*%
%AMMACRO83*
21,1,.02,.005,0.0,0.0,145.821*%
%ADD83MACRO83*%
%ADD13R,.045X.055*%
%ADD219R,.039X.035*%
%ADD209R,.038X.063*%
%ADD204R,.025X.076*%
%AMMACRO189*
4,1,21,.015,.006,
-.009,.006,
-.010042,.005909,
-.011052,.005638,
-.012,.005196,
-.012857,.004596,
-.013596,.003857,
-.014196,.003,
-.014638,.002052,
-.014909,.001042,
-.015,0.0,
-.014909,-.001042,
-.014638,-.002052,
-.014196,-.003,
-.013596,-.003857,
-.012857,-.004596,
-.012,-.005196,
-.011052,-.005638,
-.010042,-.005909,
-.009,-.006,
.015,-.006,
.015,.006,
0.0*
%
%ADD189MACRO189*%
%ADD132R,.085X.015*%
%ADD30R,.055X.045*%
%ADD185R,.076X.025*%
%AMMACRO167*
21,1,.02,.005,0.0,0.0,134.753*%
%ADD167MACRO167*%
%AMMACRO119*
4,1,21,-.01,.004,
-.010695,.003939,
-.011368,.003759,
-.012,.003464,
-.012571,.003064,
-.013064,.002571,
-.013464,.002,
-.013759,.001368,
-.013939,.000695,
-.014,0.0,
-.013939,-.000695,
-.013759,-.001368,
-.013464,-.002,
-.013064,-.002571,
-.012571,-.003064,
-.012,-.003464,
-.011368,-.003759,
-.010695,-.003939,
-.01,-.004,
.014,-.004,
.014,.004,
-.01,.004,
0.0*
%
%ADD119MACRO119*%
%ADD77R,.035X.039*%
%ADD32R,.14X.14*%
%ADD220O,.094X.048*%
%ADD11C,.238*%
%ADD200O,.098X.046*%
%ADD164R,.059X.036*%
%ADD163C,.276*%
%AMMACRO181*
4,1,21,.006,-.015,
.006,.009,
.005909,.010042,
.005638,.011052,
.005196,.012,
.004596,.012857,
.003857,.013596,
.003,.014196,
.002052,.014638,
.001042,.014909,
0.0,.015,
-.001042,.014909,
-.002052,.014638,
-.003,.014196,
-.003857,.013596,
-.004596,.012857,
-.005196,.012,
-.005638,.011052,
-.005909,.010042,
-.006,.009,
-.006,-.015,
.006,-.015,
0.0*
%
%ADD181MACRO181*%
%AMMACRO169*
21,1,.02,.005,0.0,0.0,135.657*%
%ADD169MACRO169*%
%AMMACRO188*
4,1,21,-.015,-.006,
.009,-.006,
.010042,-.005909,
.011052,-.005638,
.012,-.005196,
.012857,-.004596,
.013596,-.003857,
.014196,-.003,
.014638,-.002052,
.014909,-.001042,
.015,0.0,
.014909,.001042,
.014638,.002052,
.014196,.003,
.013596,.003857,
.012857,.004596,
.012,.005196,
.011052,.005638,
.010042,.005909,
.009,.006,
-.015,.006,
-.015,-.006,
0.0*
%
%ADD188MACRO188*%
%ADD122R,.145X.145*%
%ADD203O,.099X.048*%
%AMMACRO180*
4,1,21,-.015,-.006,
.009,-.006,
.010042,-.005909,
.011052,-.005638,
.012,-.005196,
.012857,-.004596,
.013596,-.003857,
.014196,-.003,
.014638,-.002052,
.014909,-.001042,
.015,0.0,
.014909,.001042,
.014638,.002052,
.014196,.003,
.013596,.003857,
.012857,.004596,
.012,.005196,
.011052,.005638,
.010042,.005909,
.009,.006,
-.015,.006,
-.015,-.006,
0.0*
%
%ADD180MACRO180*%
%AMMACRO190*
4,1,21,-.006,.015,
-.006,-.009,
-.005909,-.010042,
-.005638,-.011052,
-.005196,-.012,
-.004596,-.012857,
-.003857,-.013596,
-.003,-.014196,
-.002052,-.014638,
-.001042,-.014909,
0.0,-.015,
.001042,-.014909,
.002052,-.014638,
.003,-.014196,
.003857,-.013596,
.004596,-.012857,
.005196,-.012,
.005638,-.011052,
.005909,-.010042,
.006,-.009,
.006,.015,
-.006,.015,
0.0*
%
%ADD190MACRO190*%
%AMMACRO148*
4,1,40,.024,-.012,
.024,.012,
.023878,.013389,
.023518,.014736,
.022928,.016,
.022128,.017142,
.021142,.018128,
.02,.018928,
.018736,.019518,
.017389,.019878,
.016,.02,
-.016,.02,
-.017389,.019878,
-.018736,.019518,
-.02,.018928,
-.021142,.018128,
-.022128,.017142,
-.022928,.016,
-.023518,.014736,
-.023878,.013389,
-.024,.012,
-.024,-.012,
-.023878,-.013389,
-.023518,-.014736,
-.022928,-.016,
-.022128,-.017142,
-.021142,-.018128,
-.02,-.018928,
-.018736,-.019518,
-.017389,-.019878,
-.016,-.02,
.016,-.02,
.017389,-.019878,
.018736,-.019518,
.02,-.018928,
.021142,-.018128,
.022128,-.017142,
.022928,-.016,
.023518,-.014736,
.023878,-.013389,
.024,-.012,
0.0*
%
%ADD148MACRO148*%
%AMMACRO75*
4,1,8,.0585,.0835,
.0585,-.0835,
-.0585,-.0835,
-.0585,-.04275,
-.0185,-.04275,
-.0185,.04275,
-.0585,.04275,
-.0585,.0835,
.0585,.0835,
0.0*
%
%ADD75MACRO75*%
%AMMACRO85*
21,1,.02,.005,0.0,0.0,168.917*%
%ADD85MACRO85*%
%AMMACRO125*
4,1,21,-.004,-.01,
-.003939,-.010695,
-.003759,-.011368,
-.003464,-.012,
-.003064,-.012571,
-.002571,-.013064,
-.002,-.013464,
-.001368,-.013759,
-.000695,-.013939,
0.0,-.014,
.000695,-.013939,
.001368,-.013759,
.002,-.013464,
.002571,-.013064,
.003064,-.012571,
.003464,-.012,
.003759,-.011368,
.003939,-.010695,
.004,-.01,
.004,.014,
-.004,.014,
-.004,-.01,
0.0*
%
%ADD125MACRO125*%
%AMMACRO168*
21,1,.02,.005,0.0,0.0,179.539*%
%ADD168MACRO168*%
%AMMACRO215*
4,1,40,.008,-.012,
-.008,-.012,
-.008695,-.011939,
-.009368,-.011759,
-.01,-.011464,
-.010571,-.011064,
-.011064,-.010571,
-.011464,-.01,
-.011759,-.009368,
-.011939,-.008695,
-.012,-.008,
-.012,.008,
-.011939,.008695,
-.011759,.009368,
-.011464,.01,
-.011064,.010571,
-.010571,.011064,
-.01,.011464,
-.009368,.011759,
-.008695,.011939,
-.008,.012,
.008,.012,
.008695,.011939,
.009368,.011759,
.01,.011464,
.010571,.011064,
.011064,.010571,
.011464,.01,
.011759,.009368,
.011939,.008695,
.012,.008,
.012,-.008,
.011939,-.008695,
.011759,-.009368,
.011464,-.01,
.011064,-.010571,
.010571,-.011064,
.01,-.011464,
.009368,-.011759,
.008695,-.011939,
.008,-.012,
0.0*
%
%ADD215MACRO215*%
%AMMACRO105*
4,1,40,.012,.008,
.012,-.008,
.011939,-.008695,
.011759,-.009368,
.011464,-.01,
.011064,-.010571,
.010571,-.011064,
.01,-.011464,
.009368,-.011759,
.008695,-.011939,
.008,-.012,
-.008,-.012,
-.008695,-.011939,
-.009368,-.011759,
-.01,-.011464,
-.010571,-.011064,
-.011064,-.010571,
-.011464,-.01,
-.011759,-.009368,
-.011939,-.008695,
-.012,-.008,
-.012,.008,
-.011939,.008695,
-.011759,.009368,
-.011464,.01,
-.011064,.010571,
-.010571,.011064,
-.01,.011464,
-.009368,.011759,
-.008695,.011939,
-.008,.012,
.008,.012,
.008695,.011939,
.009368,.011759,
.01,.011464,
.010571,.011064,
.011064,.010571,
.011464,.01,
.011759,.009368,
.011939,.008695,
.012,.008,
0.0*
%
%ADD105MACRO105*%
%AMMACRO72*
4,1,40,-.007,.011,
.007,.011,
.007695,.010939,
.008368,.010759,
.009,.010464,
.009571,.010064,
.010064,.009571,
.010464,.009,
.010759,.008368,
.010939,.007695,
.011,.007,
.011,-.007,
.010939,-.007695,
.010759,-.008368,
.010464,-.009,
.010064,-.009571,
.009571,-.010064,
.009,-.010464,
.008368,-.010759,
.007695,-.010939,
.007,-.011,
-.007,-.011,
-.007695,-.010939,
-.008368,-.010759,
-.009,-.010464,
-.009571,-.010064,
-.010064,-.009571,
-.010464,-.009,
-.010759,-.008368,
-.010939,-.007695,
-.011,-.007,
-.011,.007,
-.010939,.007695,
-.010759,.008368,
-.010464,.009,
-.010064,.009571,
-.009571,.010064,
-.009,.010464,
-.008368,.010759,
-.007695,.010939,
-.007,.011,
0.0*
%
%ADD72MACRO72*%
%AMMACRO152*
4,1,8,-.0082,-.00339,
-.00339,-.0082,
.00339,-.0082,
.00821,-.00339,
.00821,.00339,
.00339,.0082,
-.00339,.0082,
-.0082,.00339,
-.0082,-.00339,
0.0*
%
%ADD152MACRO152*%
%AMMACRO135*
4,1,8,-.0082,.0034,
-.0082,-.0034,
-.0034,-.0082,
.00341,-.0082,
.0082,-.00341,
.0082,.0034,
.0034,.0082,
-.0034,.0082,
-.0082,.0034,
0.0*
%
%ADD135MACRO135*%
%AMMACRO133*
4,1,8,-.0034,-.0082,
.0034,-.0082,
.0082,-.0034,
.0082,.00341,
.00341,.0082,
-.0034,.0082,
-.0082,.0034,
-.0082,-.0034,
-.0034,-.0082,
0.0*
%
%ADD133MACRO133*%
%AMMACRO130*
4,1,40,.011,.007,
.011,-.007,
.010939,-.007695,
.010759,-.008368,
.010464,-.009,
.010064,-.009571,
.009571,-.010064,
.009,-.010464,
.008368,-.010759,
.007695,-.010939,
.007,-.011,
-.007,-.011,
-.007695,-.010939,
-.008368,-.010759,
-.009,-.010464,
-.009571,-.010064,
-.010064,-.009571,
-.010464,-.009,
-.010759,-.008368,
-.010939,-.007695,
-.011,-.007,
-.011,.007,
-.010939,.007695,
-.010759,.008368,
-.010464,.009,
-.010064,.009571,
-.009571,.010064,
-.009,.010464,
-.008368,.010759,
-.007695,.010939,
-.007,.011,
.007,.011,
.007695,.010939,
.008368,.010759,
.009,.010464,
.009571,.010064,
.010064,.009571,
.010464,.009,
.010759,.008368,
.010939,.007695,
.011,.007,
0.0*
%
%ADD130MACRO130*%
%AMMACRO161*
4,1,40,-.017,-.013,
-.017,.013,
-.016939,.013695,
-.016759,.014368,
-.016464,.015,
-.016064,.015571,
-.015571,.016064,
-.015,.016464,
-.014368,.016759,
-.013695,.016939,
-.013,.017,
.013,.017,
.013695,.016939,
.014368,.016759,
.015,.016464,
.015571,.016064,
.016064,.015571,
.016464,.015,
.016759,.014368,
.016939,.013695,
.017,.013,
.017,-.013,
.016939,-.013695,
.016759,-.014368,
.016464,-.015,
.016064,-.015571,
.015571,-.016064,
.015,-.016464,
.014368,-.016759,
.013695,-.016939,
.013,-.017,
-.013,-.017,
-.013695,-.016939,
-.014368,-.016759,
-.015,-.016464,
-.015571,-.016064,
-.016064,-.015571,
-.016464,-.015,
-.016759,-.014368,
-.016939,-.013695,
-.017,-.013,
0.0*
%
%ADD161MACRO161*%
%AMMACRO157*
4,1,40,.013,-.017,
-.013,-.017,
-.013695,-.016939,
-.014368,-.016759,
-.015,-.016464,
-.015571,-.016064,
-.016064,-.015571,
-.016464,-.015,
-.016759,-.014368,
-.016939,-.013695,
-.017,-.013,
-.017,.013,
-.016939,.013695,
-.016759,.014368,
-.016464,.015,
-.016064,.015571,
-.015571,.016064,
-.015,.016464,
-.014368,.016759,
-.013695,.016939,
-.013,.017,
.013,.017,
.013695,.016939,
.014368,.016759,
.015,.016464,
.015571,.016064,
.016064,.015571,
.016464,.015,
.016759,.014368,
.016939,.013695,
.017,.013,
.017,-.013,
.016939,-.013695,
.016759,-.014368,
.016464,-.015,
.016064,-.015571,
.015571,-.016064,
.015,-.016464,
.014368,-.016759,
.013695,-.016939,
.013,-.017,
0.0*
%
%ADD157MACRO157*%
%AMMACRO121*
4,1,21,.004,.01,
.003939,.010695,
.003759,.011368,
.003464,.012,
.003064,.012571,
.002571,.013064,
.002,.013464,
.001368,.013759,
.000695,.013939,
0.0,.014,
-.000695,.013939,
-.001368,.013759,
-.002,.013464,
-.002571,.013064,
-.003064,.012571,
-.003464,.012,
-.003759,.011368,
-.003939,.010695,
-.004,.01,
-.004,-.014,
.004,-.014,
.004,.01,
0.0*
%
%ADD121MACRO121*%
%AMMACRO120*
4,1,21,.01,-.004,
.010695,-.003939,
.011368,-.003759,
.012,-.003464,
.012571,-.003064,
.013064,-.002571,
.013464,-.002,
.013759,-.001368,
.013939,-.000695,
.014,0.0,
.013939,.000695,
.013759,.001368,
.013464,.002,
.013064,.002571,
.012571,.003064,
.012,.003464,
.011368,.003759,
.010695,.003939,
.01,.004,
-.014,.004,
-.014,-.004,
.01,-.004,
0.0*
%
%ADD120MACRO120*%
%AMMACRO216*
4,1,40,.008,-.012,
-.008,-.012,
-.008695,-.011939,
-.009368,-.011759,
-.01,-.011464,
-.010571,-.011064,
-.011064,-.010571,
-.011464,-.01,
-.011759,-.009368,
-.011939,-.008695,
-.012,-.008,
-.012,.008,
-.011939,.008695,
-.011759,.009368,
-.011464,.01,
-.011064,.010571,
-.010571,.011064,
-.01,.011464,
-.009368,.011759,
-.008695,.011939,
-.008,.012,
.008,.012,
.008695,.011939,
.009368,.011759,
.01,.011464,
.010571,.011064,
.011064,.010571,
.011464,.01,
.011759,.009368,
.011939,.008695,
.012,.008,
.012,-.008,
.011939,-.008695,
.011759,-.009368,
.011464,-.01,
.011064,-.010571,
.010571,-.011064,
.01,-.011464,
.009368,-.011759,
.008695,-.011939,
.008,-.012,
0.0*
%
%ADD216MACRO216*%
%AMMACRO104*
4,1,40,.012,.008,
.012,-.008,
.011939,-.008695,
.011759,-.009368,
.011464,-.01,
.011064,-.010571,
.010571,-.011064,
.01,-.011464,
.009368,-.011759,
.008695,-.011939,
.008,-.012,
-.008,-.012,
-.008695,-.011939,
-.009368,-.011759,
-.01,-.011464,
-.010571,-.011064,
-.011064,-.010571,
-.011464,-.01,
-.011759,-.009368,
-.011939,-.008695,
-.012,-.008,
-.012,.008,
-.011939,.008695,
-.011759,.009368,
-.011464,.01,
-.011064,.010571,
-.010571,.011064,
-.01,.011464,
-.009368,.011759,
-.008695,.011939,
-.008,.012,
.008,.012,
.008695,.011939,
.009368,.011759,
.01,.011464,
.010571,.011064,
.011064,.010571,
.011464,.01,
.011759,.009368,
.011939,.008695,
.012,.008,
0.0*
%
%ADD104MACRO104*%
%AMMACRO43*
4,1,40,-.007,.011,
.007,.011,
.007695,.010939,
.008368,.010759,
.009,.010464,
.009571,.010064,
.010064,.009571,
.010464,.009,
.010759,.008368,
.010939,.007695,
.011,.007,
.011,-.007,
.010939,-.007695,
.010759,-.008368,
.010464,-.009,
.010064,-.009571,
.009571,-.010064,
.009,-.010464,
.008368,-.010759,
.007695,-.010939,
.007,-.011,
-.007,-.011,
-.007695,-.010939,
-.008368,-.010759,
-.009,-.010464,
-.009571,-.010064,
-.010064,-.009571,
-.010464,-.009,
-.010759,-.008368,
-.010939,-.007695,
-.011,-.007,
-.011,.007,
-.010939,.007695,
-.010759,.008368,
-.010464,.009,
-.010064,.009571,
-.009571,.010064,
-.009,.010464,
-.008368,.010759,
-.007695,.010939,
-.007,.011,
0.0*
%
%ADD43MACRO43*%
%ADD222C,.012*%
%ADD223C,.013*%
%ADD224C,.014*%
%ADD225C,.015*%
%ADD226C,.016*%
%ADD227C,.004*%
%ADD228C,.00401*%
%ADD229C,.006*%
%ADD230C,.005*%
%ADD231C,.007*%
%ADD232C,.008*%
%ADD233C,.0035*%
%ADD234C,.009*%
%ADD235C,.0045*%
%ADD236C,.0055*%
%ADD237C,.00352*%
%ADD238C,.0065*%
%ADD239C,.00425*%
%ADD240C,.00625*%
%ADD241C,.00395*%
%ADD242C,.00399*%
%ADD266R,.008X.02*%
%ADD272R,.008X.016*%
%ADD248C,.03004*%
%ADD271C,.04004*%
%ADD269C,.04104*%
%ADD263R,.008X.018*%
%ADD249C,.03204*%
%ADD270C,.04204*%
%ADD264C,.03404*%
%ADD245C,.07004*%
%ADD274C,.06204*%
%ADD250C,.03604*%
%ADD260C,.02804*%
%ADD268C,.03804*%
%ADD259C,.02904*%
%ADD243C,.09204*%
%ADD275C,.09304*%
%ADD267C,.03904*%
%ADD273R,.008X.01938*%
%ADD262C,.20004*%
%ADD265C,.12104*%
%ADD247C,.11204*%
%ADD254R,.23X.197*%
%ADD244C,.11404*%
%ADD252R,.251X.197*%
%ADD261R,.008X.008*%
%ADD256R,.252X.197*%
%ADD255R,.234X.197*%
%ADD257R,.237X.197*%
%ADD258R,.229X.197*%
%ADD246C,.1772*%
%ADD253R,.249X.197*%
%ADD251R,.278X.197*%
G75*
%LPD*%
G75*
G36*
G01X1973300Y-60000D02*
X-19810D01*
Y-34500D01*
X1973300D01*
Y-60000D01*
G37*
G36*
G01X-13700Y21100D02*
X-21700D01*
Y75380D01*
X-19510Y77570D01*
X-13450D01*
X-12580Y76700D01*
Y66320D01*
X-12800Y66100D01*
X-15940D01*
X-16920Y65120D01*
Y61330D01*
X-13500Y57910D01*
Y21300D01*
X-13700Y21100D01*
G37*
G36*
G01X498Y295981D02*
G03X2502I1002J-981D01*
G01Y300674D01*
G02X3092Y301026I400J0D01*
G03X4991Y301424I714J1321D01*
G02X5621I315J-246D01*
G03Y303270I1185J923D01*
G02X4991I-315J246D01*
G03X4357Y303744I-1185J-923D01*
G02X4221Y304399I147J372D01*
G01X8166Y308345D01*
G02X8849Y308062I283J-283D01*
G01Y271849D01*
X4900Y267900D01*
Y246700D01*
X6298Y245302D01*
Y240298D01*
X6300D01*
Y237700D01*
X7000Y237000D01*
Y203722D01*
X5600Y202322D01*
Y193356D01*
X7356Y191600D01*
X11284D01*
G02X11475Y190848I1J-400D01*
G03X4796Y182913I6753J-12462D01*
G02X4093Y182805I-379J127D01*
G03X-5289Y171659I-6062J-4419D01*
G02X-5466Y170900I-177J-359D01*
G01X-19300D01*
X-21600Y173200D01*
Y341400D01*
X-19200Y343800D01*
X5300D01*
X8849Y340251D01*
Y311860D01*
X498Y303510D01*
Y295981D01*
G37*
G36*
G01X-15500Y442800D02*
X-16200Y443500D01*
Y454286D01*
X-13786Y456700D01*
X-9400D01*
X-9196Y456496D01*
Y451300D01*
X-8896Y451000D01*
X-8100D01*
X-7700Y450600D01*
Y450152D01*
X-7702D01*
Y448348D01*
X-7700D01*
Y444000D01*
X-8900Y442800D01*
X-15500D01*
G37*
G36*
G01X-20000Y509600D02*
X-21100Y510700D01*
Y524000D01*
X-15100Y530000D01*
X78D01*
G03X1509Y529739I961J1218D01*
G01X1625Y529775D01*
X4300Y527100D01*
X9919D01*
X10144Y526874D01*
X15191D01*
X15416Y527100D01*
X30427D01*
X32968Y524560D01*
Y520348D01*
X32721Y520102D01*
X30598D01*
Y519867D01*
X29287D01*
X29100Y519680D01*
Y517200D01*
X28300Y516400D01*
X23500D01*
X20700Y513600D01*
X2900D01*
X1500Y515000D01*
Y515841D01*
G02X2198Y516108I400J0D01*
G03X4676Y516330I1156J1035D01*
G02X5371Y516305I340J-210D01*
G03X5426Y517834I1377J716D01*
G02X4731Y517859I-340J210D01*
G03X2198Y518178I-1377J-716D01*
G02X1500Y518445I-298J267D01*
G01Y519000D01*
X502Y519998D01*
Y520002D01*
X-1002D01*
X-1500Y520500D01*
Y522500D01*
X-2000Y523000D01*
X-3815D01*
G02X-4153Y523612I1J400D01*
G03X-7207I-1527J958D01*
G02X-7545Y523000I-339J-212D01*
G01X-11595D01*
X-11625Y523010D01*
G03X-12795I-585J-1810D01*
G01X-12825Y523000D01*
X-14100D01*
X-14442Y522658D01*
X-14549D01*
X-16360Y520848D01*
X-16424Y520838D01*
G03X-17300Y518223I238J-1534D01*
G01Y515200D01*
X-16000Y513900D01*
X-14500D01*
X-14100Y513500D01*
Y511200D01*
X-14920Y510380D01*
G02X-15602Y510690I-283J283D01*
G03X-18669Y510160I-1598J110D01*
G02X-19035Y509600I-366J-160D01*
G01X-20000D01*
G37*
G36*
G01X-20412Y637600D02*
G02X-20621Y638189I726J589D01*
G01Y661811D01*
G02X-19685Y662747I936J0D01*
G01X1972600D01*
Y637600D01*
X12918D01*
G03X4168I-4375J-1427D01*
G01X-20412D01*
G37*
G36*
G01X43418Y-6975D02*
X42292Y-8101D01*
X39305D01*
X39026Y-7822D01*
Y-6111D01*
X38886Y-5971D01*
X33519D01*
X32618Y-5070D01*
Y3474D01*
X32140Y3952D01*
Y9305D01*
X32784Y9949D01*
X46193D01*
X47243Y8899D01*
Y-501D01*
X43418Y-4326D01*
Y-6975D01*
G37*
G36*
G01X22568Y20451D02*
X22063Y20956D01*
Y25702D01*
X21848Y25917D01*
G03X21698Y26067I-708J-558D01*
G01X20050Y27715D01*
Y28122D01*
X20052D01*
Y29252D01*
X20100Y29300D01*
Y47610D01*
X19262Y48448D01*
Y50548D01*
X19100Y50710D01*
Y55440D01*
X20400Y56740D01*
Y64172D01*
X20438D01*
Y69174D01*
X20400D01*
Y81417D01*
X20422Y81439D01*
Y86922D01*
X24500Y91000D01*
X32000D01*
X36000Y87000D01*
X50000D01*
X53700Y83300D01*
Y25700D01*
X52750Y24750D01*
X37250D01*
X36300Y23800D01*
X34400D01*
X31051Y20451D01*
X22568D01*
G37*
G36*
G01X-10400Y21200D02*
X-11500Y22300D01*
Y57500D01*
X-15409Y61409D01*
Y65098D01*
X-12385D01*
X-11578Y65905D01*
Y66492D01*
X-11020Y67050D01*
Y74500D01*
X-7820Y77700D01*
X-2435D01*
X2665Y82800D01*
X2667D01*
Y87654D01*
X4304Y89291D01*
X15717D01*
X17434Y87574D01*
Y82176D01*
X17326D01*
Y77172D01*
X17434D01*
Y75676D01*
X17326D01*
Y70672D01*
X17434D01*
Y62704D01*
X17276Y62546D01*
G02X16597Y62771I-283J283D01*
G03X13886Y63423I-1486J-218D01*
G02X13204Y63473I-326J232D01*
G03X13014Y63761I-1341J-678D01*
G02X13027Y64290I306J257D01*
G03X13057Y66298I-1102J1021D01*
G02Y66824I302J263D01*
G03X10793I-1132J987D01*
G02Y66298I-302J-263D01*
G03X10521Y65844I1132J-987D01*
G02X9864Y65703I-374J142D01*
G01X9343Y66224D01*
X4834D01*
X3703Y67355D01*
X3151D01*
G02X2758Y67832I0J400D01*
G03X987Y66755I-1376J268D01*
G02X1157Y66088I-113J-384D01*
G01X931Y65862D01*
X-2538D01*
X-3586Y64814D01*
Y59914D01*
X-3584Y59912D01*
Y59859D01*
X-2496Y58771D01*
X567D01*
G03X892Y58346I1296J655D01*
G02X865Y57729I-267J-297D01*
G03X2819Y57704I961J-1282D01*
G02X2807Y58322I248J314D01*
G03X3159Y58771I-945J1103D01*
G01X5414D01*
X5927Y58258D01*
Y54938D01*
X10248Y50617D01*
X17640D01*
X17758Y50498D01*
Y48348D01*
X17200Y47790D01*
Y47780D01*
X17050Y47630D01*
Y40156D01*
X17048D01*
Y35152D01*
X17050D01*
Y32926D01*
X17048D01*
Y28137D01*
G02X16619Y27738I-400J0D01*
G03X15977Y27716I-219J-2994D01*
G01X15963Y27714D01*
X13221D01*
X13045Y27890D01*
Y33506D01*
X13103Y33564D01*
Y34333D01*
X13045Y34391D01*
Y36033D01*
X13052Y36059D01*
G03Y36829I-1452J385D01*
G01X13045Y36855D01*
Y37230D01*
X11968Y38307D01*
X11542D01*
X10106Y39743D01*
X206D01*
X-2496Y37041D01*
Y22854D01*
X-4150Y21200D01*
X-10400D01*
G37*
G36*
G01X1351Y171659D02*
G03X4093Y173967I-3320J6727D01*
G02X4796Y173859I324J-235D01*
G03X5842Y171494I13432J4527D01*
G02X5492Y170900I-350J-194D01*
G01X1528D01*
G02X1351Y171659I0J400D01*
G37*
G36*
G01X30614Y171494D02*
G03X24981Y190848I-12386J6892D01*
G02X25172Y191600I190J352D01*
G01X48900D01*
X53400Y187100D01*
Y172000D01*
X52300Y170900D01*
X47788D01*
G02X47611Y171659I0J400D01*
G03X40971I-3320J6727D01*
G02X40794Y170900I-177J-359D01*
G01X30964D01*
G02X30614Y171494I0J400D01*
G37*
G36*
G01X46606Y325371D02*
X47998Y323978D01*
Y320799D01*
X47841Y320641D01*
X47820D01*
X41500Y314321D01*
Y281800D01*
X38300Y278600D01*
X33400D01*
X31300Y276500D01*
Y267700D01*
X35568Y263432D01*
Y257532D01*
X22645D01*
X21038Y259138D01*
G03X18562Y256662I-1238J-1238D01*
G01X19207Y256016D01*
G02X19136Y255394I-283J-283D01*
G03X21326Y253869I768J-1232D01*
G01X21359Y254028D01*
X35600D01*
Y247824D01*
X38102Y245322D01*
Y226953D01*
X45854Y219201D01*
X55688D01*
X56004Y218885D01*
Y218604D01*
X55998D01*
Y213600D01*
X56004D01*
Y201604D01*
X51400Y197000D01*
X10800D01*
X10055Y196255D01*
X7355D01*
X7302Y196308D01*
Y198302D01*
X12000Y203000D01*
X12100Y203059D01*
Y231900D01*
X9142Y234858D01*
Y240298D01*
X9302D01*
Y245434D01*
X9900Y246032D01*
Y265100D01*
X13900Y269100D01*
Y336958D01*
X16281Y339339D01*
X43930D01*
X54798Y328471D01*
Y326403D01*
X54386Y325991D01*
X51878D01*
X51055Y325168D01*
X48729Y327494D01*
X48714Y327539D01*
G03X46561Y325386I-1614J-539D01*
G01X46606Y325371D01*
G37*
G36*
G01X73685Y223300D02*
X47414D01*
X42104Y228610D01*
Y246979D01*
X42100Y246983D01*
Y251900D01*
X42500Y252300D01*
X55500D01*
X56369Y253169D01*
X56510Y253038D01*
G03X58372Y255261I990J1062D01*
G02X58329Y255864I240J320D01*
G01X58682Y256218D01*
G03X56290Y258774I-1238J1238D01*
G01X56149Y258651D01*
X56000Y258800D01*
X42500D01*
X42000Y259300D01*
Y263400D01*
X45200Y266600D01*
X74956D01*
X76248Y265308D01*
Y262307D01*
X76198Y262257D01*
Y227043D01*
X76248Y226993D01*
Y225863D01*
X73685Y223300D01*
G37*
G36*
G01X9578Y446878D02*
Y445876D01*
X6901Y443200D01*
X-5700D01*
X-6167Y443667D01*
Y453701D01*
X-6188Y453722D01*
Y456411D01*
X-5914Y456686D01*
X-2507D01*
X-2380Y456812D01*
X-212D01*
X1716Y458739D01*
X1843Y458681D01*
G03X3267Y458800I607J1319D01*
G01X13172D01*
X13385Y458587D01*
Y450685D01*
X9578Y446878D01*
G37*
G36*
G01X29810Y452710D02*
X29000Y451900D01*
X28919Y451866D01*
X19646D01*
X19579Y451800D01*
X15500D01*
X15000Y452300D01*
Y462400D01*
X16100Y463500D01*
X28510D01*
X29810Y462200D01*
Y452710D01*
G37*
G36*
G01X52394Y472194D02*
Y465644D01*
X50526Y463777D01*
X45293D01*
X44138Y464932D01*
Y466100D01*
X44147Y466129D01*
G03Y468359I-3635J1115D01*
G01X44138Y468388D01*
Y477196D01*
X50756Y483814D01*
X54446D01*
X55546Y484914D01*
Y485361D01*
X55901Y485716D01*
X60856D01*
X61249Y485323D01*
Y481050D01*
X61018Y480819D01*
X60869Y480968D01*
X60862Y480976D01*
G03X58692Y479052I-1131J-910D01*
G02X58689Y478489I-286J-280D01*
G01X52394Y472194D01*
G37*
G36*
G01X40150Y473950D02*
X25200D01*
X22650Y476500D01*
Y485150D01*
X23100Y485600D01*
X26400D01*
X26800Y485200D01*
Y479000D01*
X27300Y478500D01*
X36200D01*
X36600Y478900D01*
Y483600D01*
X37100Y484100D01*
X40497D01*
X42000Y482597D01*
Y475800D01*
X40150Y473950D01*
G37*
G36*
G01X29541Y507595D02*
Y510490D01*
X32251Y513200D01*
X33168D01*
X33969Y514000D01*
Y526431D01*
X35100Y527562D01*
X42762D01*
X43425Y526900D01*
Y520229D01*
X42373Y519177D01*
X39834D01*
X39134Y518477D01*
Y511673D01*
X40485Y510322D01*
Y507185D01*
X39400Y506100D01*
X31100D01*
X31068Y506068D01*
X29541Y507595D01*
G37*
G36*
G01X63316Y509600D02*
X63315Y509602D01*
X61462D01*
G03X59138I-1162J-952D01*
G01X54638D01*
X53019Y511220D01*
X53051Y511334D01*
G03X50328Y512534I-1444J413D01*
G01X46244D01*
X46040Y512738D01*
Y519616D01*
X44800Y520856D01*
Y526600D01*
X47500Y529300D01*
X65690D01*
X67685Y527305D01*
Y510785D01*
X66500Y509600D01*
X63316D01*
G37*
G36*
G01X10559Y527876D02*
X10312Y528123D01*
Y561566D01*
X9006Y562872D01*
Y565721D01*
X10000Y566715D01*
Y574400D01*
X10100Y574500D01*
Y574998D01*
X10302D01*
Y580002D01*
X10100D01*
Y581498D01*
X10302D01*
Y586502D01*
X10100D01*
Y587998D01*
X10302D01*
Y593002D01*
X10500Y593200D01*
X21800D01*
X32340Y603740D01*
Y611730D01*
X34480Y613870D01*
X47980D01*
X48410Y613440D01*
Y535000D01*
X45930Y532520D01*
X31180D01*
X27560Y528900D01*
X15800D01*
X14776Y527876D01*
X10559D01*
G37*
G36*
G01X4200Y573400D02*
X3250Y574350D01*
Y580350D01*
X2600Y581000D01*
X-3200D01*
X-5000Y582800D01*
Y586200D01*
X-7300Y588500D01*
Y595300D01*
X-6500Y596100D01*
X-6077D01*
X-6040Y596085D01*
G03X0Y594880I6042J14545D01*
G01X7020D01*
X7300Y594600D01*
Y593002D01*
X7298D01*
Y587998D01*
X7300D01*
Y586502D01*
X7298D01*
Y581498D01*
X7300D01*
Y580002D01*
X7298D01*
Y574998D01*
X7300D01*
Y573800D01*
X6900Y573400D01*
X4200D01*
G37*
G36*
G01X7250Y539950D02*
X7300Y539900D01*
Y538000D01*
X6700Y537400D01*
X4200D01*
X3250Y538350D01*
Y544350D01*
X2600Y545000D01*
X-3200D01*
X-5000Y546800D01*
Y550200D01*
X-7300Y552500D01*
Y559300D01*
X-6500Y560100D01*
X5800D01*
X7250Y558650D01*
Y539950D01*
G37*
G36*
G01X63228Y-16600D02*
X62140Y-15512D01*
X60502D01*
X59920Y-14930D01*
Y-10700D01*
X60484Y-10136D01*
Y-3540D01*
X59920Y-2976D01*
Y-2790D01*
X58500Y-1370D01*
Y2094D01*
X60473Y4067D01*
X80499D01*
X85048Y-482D01*
Y-12652D01*
X82676Y-15024D01*
X78926D01*
X77350Y-16600D01*
X63228D01*
G37*
G36*
G01X67944Y5384D02*
X66300Y7028D01*
Y12884D01*
X66413Y12939D01*
G03X65441Y15555I-613J1261D01*
G01X65330Y15526D01*
X65107Y15749D01*
X65474Y16115D01*
G03X63222Y18902I-1274J1274D01*
G02X62668Y19022I-217J336D01*
G03X60035Y18580I-1222J-784D01*
G02X59363Y18392I-389J94D01*
G01X57500Y20255D01*
Y84500D01*
X59500Y86500D01*
X80000D01*
X85548Y80952D01*
Y6147D01*
X84785Y5384D01*
X67944D01*
G37*
G36*
G01X109100Y-11800D02*
X108700Y-11400D01*
Y-5850D01*
X107650Y-4800D01*
X102492D01*
X101292Y-3600D01*
Y28976D01*
X104275D01*
X104898Y28353D01*
Y27022D01*
X104886Y26989D01*
G03X107514I1314J-489D01*
G01X107502Y27022D01*
Y29476D01*
X108602D01*
Y34480D01*
X106102D01*
Y34980D01*
X101292D01*
Y51200D01*
X100660Y51832D01*
X100649Y51895D01*
G03X95700Y56844I-5966J-1017D01*
G01X95637Y56855D01*
X88914Y63578D01*
Y66199D01*
G02X89647Y66421I400J0D01*
G03X100326Y67590I5036J3357D01*
G02X101098Y67445I372J-145D01*
G01Y66776D01*
X106102D01*
Y67276D01*
X108602D01*
Y72280D01*
X106102D01*
Y72780D01*
X104537D01*
X103504Y73812D01*
X103499Y73888D01*
G03X101098Y72819I-1399J-88D01*
G01Y72111D01*
G02X100326Y71966I-400J0D01*
G03X89647Y73135I-5643J-2188D01*
G02X88914Y73357I-333J222D01*
G01Y81412D01*
X90062Y82560D01*
X97285D01*
X100705Y85980D01*
Y85986D01*
X100807Y86088D01*
Y102378D01*
G02X101364Y102745I400J-1D01*
G03X104443Y103760I963J2255D01*
G02X105134I345J-202D01*
G03Y106240I2115J1240D01*
G02X104443I-345J202D01*
G03X104114Y106681I-2118J-1237D01*
G01X105582Y108149D01*
X119953D01*
X119988Y108135D01*
G03X121078I545J1400D01*
G01X121113Y108149D01*
X122344D01*
X123074Y107419D01*
Y103010D01*
X122782Y102718D01*
X118957D01*
X117892Y101653D01*
Y86590D01*
G03X117522Y83303I2000J-1889D01*
G01Y75321D01*
X117140Y74940D01*
Y72211D01*
G02X116627Y71827I-400J-1D01*
G03X116795Y69008I-427J-1440D01*
G02X117326Y68785I158J-368D01*
G03X117892Y67888I2566J992D01*
G01Y48336D01*
G03X117522Y46957I2381J-1378D01*
G01Y37197D01*
X117140Y36816D01*
Y31978D01*
G03X117892Y30088I2751J0D01*
G01Y10536D01*
G03X117522Y9157I2381J-1378D01*
G01Y-603D01*
X117140Y-984D01*
Y-6000D01*
G03X117892Y-7890I2751J0D01*
G01Y-9600D01*
X115692Y-11800D01*
X109100D01*
G37*
G36*
G01X107700Y141800D02*
X106514Y142986D01*
Y149203D01*
X106000Y149718D01*
Y154600D01*
X118900Y167500D01*
X123300D01*
X127400Y163400D01*
Y162300D01*
X115700Y150600D01*
Y145966D01*
X115699Y145956D01*
G03Y145106I4281J-425D01*
G01X115700Y145096D01*
Y144400D01*
X113100Y141800D01*
X107700D01*
G37*
G36*
G01X60620Y207850D02*
X58946Y209524D01*
Y213600D01*
X59002D01*
Y218617D01*
X59587Y219202D01*
X66126D01*
X66410Y218918D01*
Y209280D01*
X64980Y207850D01*
X60620D01*
G37*
G36*
G01X84300Y208400D02*
X80500Y212200D01*
Y221000D01*
X82000Y222500D01*
X91800D01*
X91998Y222302D01*
Y222298D01*
X92002D01*
X92350Y221950D01*
X99950D01*
X100500Y221400D01*
Y212600D01*
X96300Y208400D01*
X84300D01*
G37*
G36*
G01X99900Y260800D02*
Y244000D01*
X97600Y241700D01*
Y239450D01*
X97875Y239175D01*
X97925D01*
X100200Y236900D01*
Y227000D01*
X99500Y226300D01*
X88100D01*
X86700Y227700D01*
X81200D01*
X80200Y228700D01*
Y260600D01*
X82400Y262800D01*
X97900D01*
X99900Y260800D01*
G37*
G36*
G01X86887Y281400D02*
X82670Y285617D01*
X78229D01*
X74444Y289402D01*
Y290896D01*
X73940Y291400D01*
X73502D01*
Y291502D01*
X71498D01*
Y291400D01*
X70002D01*
Y291502D01*
X67998D01*
Y291400D01*
X66300D01*
X63286Y288386D01*
X47833D01*
X47052Y289167D01*
Y292547D01*
X47889D01*
X48947Y293605D01*
X54859D01*
X55554Y294300D01*
X63338D01*
X64646Y295608D01*
Y299525D01*
X64545Y299626D01*
Y302676D01*
X63872Y303350D01*
Y303842D01*
X64116Y304087D01*
G03X61498Y306705I-1309J1309D01*
G01X60168Y305376D01*
Y304997D01*
G02X59486Y304714I-400J0D01*
G01X57714Y306486D01*
Y307532D01*
X58374Y308191D01*
Y309048D01*
X59624D01*
Y312052D01*
X56908D01*
X54770Y314189D01*
X54819Y314312D01*
G03X54831Y315657I-1719J688D01*
G02X55205Y316198I374J141D01*
G01X56872D01*
G03X57955Y316548I0J1852D01*
G01X59624D01*
Y319552D01*
X57955D01*
G03X56872Y319902I-1083J-1502D01*
G01X52317D01*
X51964Y320254D01*
Y323854D01*
X52762Y324652D01*
X54575D01*
X55800Y325877D01*
Y329700D01*
X54300Y331200D01*
X53485D01*
X50400Y334285D01*
Y335600D01*
X50900Y336100D01*
X52022D01*
G03X54028I1003J1375D01*
G01X57862D01*
X60313Y333648D01*
X60358D01*
X61650Y332357D01*
Y329350D01*
X61700Y329300D01*
Y317400D01*
X62499Y316601D01*
X62498Y316517D01*
G03X62904Y315473I1502J-17D01*
G02Y314927I-292J-273D01*
G03X63471Y312494I1096J-1027D01*
G02X63591Y311816I-140J-374D01*
G03X65204Y312151I1109J-1291D01*
G02X65044Y312820I118J382D01*
G03X65412Y314413I-1044J1080D01*
G02X65787Y314950I376J137D01*
G01X71014D01*
X73916Y317852D01*
X76991D01*
X77639Y318500D01*
X86498D01*
Y318498D01*
X88502D01*
Y318500D01*
X88945D01*
X89491Y317954D01*
Y315045D01*
X88489Y314043D01*
Y311933D01*
X88947Y311475D01*
X90965D01*
X91118Y311322D01*
Y308807D01*
X90851Y308540D01*
X87613D01*
X86039Y310114D01*
Y311421D01*
X84998Y312462D01*
X83551D01*
X82651Y311562D01*
Y311379D01*
X80158Y308886D01*
X78127D01*
X77581Y308340D01*
Y306221D01*
X78106Y305696D01*
X81901D01*
X82600Y304997D01*
Y298300D01*
X84100Y296800D01*
X91500D01*
X92000Y297300D01*
Y297498D01*
X92752D01*
Y299722D01*
X93829Y300800D01*
X95100D01*
X96500Y299400D01*
Y282500D01*
X95400Y281400D01*
X86887D01*
G37*
G36*
G01X127259Y348482D02*
X127165Y348576D01*
Y352245D01*
X126200Y353210D01*
X124236D01*
X122892Y354554D01*
X114606D01*
X105499Y363661D01*
Y386760D01*
X99829Y392430D01*
Y402765D01*
X101302Y406323D01*
X107840Y412861D01*
X108268D01*
X109538Y411591D01*
X109396Y411449D01*
X109395D01*
G03X109081Y409602I1124J-1141D01*
G01X109101Y409560D01*
Y407625D01*
X109089Y407592D01*
G03X109056Y407491I1363J-501D01*
G02X108720Y407407I-192J55D01*
G03X109058Y405696I-1149J-1116D01*
G02X109651Y405881I372J-148D01*
G03X109899Y405750I799J1212D01*
G01X109936Y405734D01*
X113601Y402069D01*
G02X113471Y401417I-283J-282D01*
G03X115564Y399324I613J-1480D01*
G02X116216Y399454I370J-153D01*
G01X116470Y399200D01*
X130728D01*
X131261Y398667D01*
Y380514D01*
X131214Y380467D01*
X127290D01*
X127200Y380557D01*
Y384600D01*
X126068Y385732D01*
X119127D01*
X118511Y386348D01*
X118497D01*
X118357Y386488D01*
X114780D01*
X112928Y384636D01*
Y381372D01*
X117029Y377271D01*
Y371880D01*
X116206Y371057D01*
Y368074D01*
X117337Y366943D01*
X130757D01*
X131200Y366500D01*
Y348646D01*
X131036Y348482D01*
X127259D01*
G37*
G36*
G01X81900Y521851D02*
Y500300D01*
X80200Y498600D01*
X69100D01*
X68302Y497802D01*
X68285D01*
X66398Y495915D01*
Y495899D01*
X66250Y495750D01*
Y490900D01*
X64171Y488821D01*
X55112D01*
X54955Y488664D01*
Y486609D01*
X53947Y485601D01*
X51442D01*
X51336Y485707D01*
Y487357D01*
X51682Y487703D01*
X52498D01*
X53252Y488457D01*
Y490598D01*
X55278Y492624D01*
Y495228D01*
X56550Y496500D01*
X62200D01*
X65750Y500050D01*
Y507550D01*
X66798Y508598D01*
X66915D01*
X68686Y510370D01*
Y524400D01*
X73760D01*
X74285Y523876D01*
X79876D01*
X81900Y521851D01*
G37*
G36*
G01X99400Y497400D02*
X94113Y492113D01*
X77206Y485110D01*
X68322D01*
X68113Y485023D01*
X67400Y485736D01*
Y495500D01*
X68700Y496800D01*
X80800D01*
X85600Y501600D01*
X98500D01*
X99400Y500700D01*
Y497400D01*
G37*
G36*
G01X117274Y528778D02*
X117892Y528159D01*
Y511990D01*
G03X117522Y508703I2000J-1889D01*
G01Y505024D01*
G03X117867Y503689I2751J-1D01*
G01X117892Y503644D01*
Y503196D01*
X107988D01*
X100000Y511185D01*
X100067Y511314D01*
G03X96047Y519975I-5384J2765D01*
G01X95892Y520011D01*
Y527023D01*
X96047Y527059D01*
G03Y538851I-1364J5896D01*
G01X95892Y538887D01*
Y545947D01*
X96047Y545983D01*
G03Y557775I-1364J5896D01*
G01X95892Y557811D01*
Y564823D01*
X96047Y564859D01*
G03Y576651I-1364J5896D01*
G01X95892Y576687D01*
Y583747D01*
X96047Y583783D01*
G03Y595575I-1364J5896D01*
G01X95892Y595611D01*
Y599800D01*
X98192Y602100D01*
X106109D01*
G03X106275I83J2500D01*
G01X117392D01*
X117892Y601600D01*
Y592541D01*
X117398Y592046D01*
X117291Y592070D01*
G03X117481Y589386I-299J-1370D01*
G01X117514Y589398D01*
X117892D01*
Y587662D01*
G03X117472Y584289I2000J-1962D01*
G01Y580624D01*
G03X117892Y579148I2801J-1D01*
G01Y577344D01*
X115650Y575102D01*
X108892D01*
G03X107396Y574668I2J-2801D01*
G02X106785Y574961I-214J338D01*
G03X104078Y574311I-1393J-161D01*
G01X104090Y574278D01*
Y573802D01*
X103890D01*
Y570801D01*
G03X102890Y568800I1502J-2001D01*
G01Y566000D01*
G03X107894I2502J0D01*
G01Y566298D01*
X108892D01*
G03X110234Y566689I-1J2502D01*
G01X110369Y566775D01*
X112418Y564726D01*
G03X115337Y566735I1274J1274D01*
G02X115702Y567298I365J163D01*
G01X117293D01*
X117892Y566699D01*
Y549790D01*
G03X117522Y546503I2000J-1889D01*
G01Y542824D01*
G03X117892Y541445I2751J-1D01*
G01Y538945D01*
X116249Y537302D01*
X109892D01*
G03X108396Y536868I2J-2801D01*
G02X107785Y537161I-214J338D01*
G03X105078Y536511I-1393J-161D01*
G01X105090Y536478D01*
Y536002D01*
X104890D01*
Y533001D01*
G03X103890Y531000I1502J-2001D01*
G01Y527413D01*
G03X108894I2502J0D01*
G01Y528498D01*
X109892D01*
G03X111501Y529085I-1J2502D01*
G01X111642Y529203D01*
X113518Y527326D01*
G03X116591Y528514I1274J1274D01*
G02X117274Y528778I400J-19D01*
G37*
G36*
G01X56237Y497600D02*
G03X53129Y501095I-5037J-1350D01*
G01X52600Y501623D01*
Y507275D01*
X53925Y508600D01*
X58789D01*
X58814Y508429D01*
G03X61786I1486J221D01*
G01X61811Y508600D01*
X62900D01*
X63600Y507900D01*
Y499600D01*
X61600Y497600D01*
X56237D01*
G37*
G36*
G01X81184Y618348D02*
G03X83464Y617954I1275J584D01*
G02X84034Y617958I287J-278D01*
G01X88120Y613872D01*
Y545740D01*
X88115Y545735D01*
Y542115D01*
X80450Y534450D01*
X74150D01*
X70385Y530685D01*
X64690D01*
X60862Y534513D01*
Y617255D01*
X61955Y618348D01*
X81184D01*
G37*
G36*
G01X115657Y139176D02*
X116197Y139716D01*
X118684D01*
Y139717D01*
X123172D01*
X130851Y147396D01*
X159171D01*
X161055Y145512D01*
Y127000D01*
X159146Y125091D01*
X121109D01*
X121046Y125154D01*
X119078D01*
X115657Y128575D01*
Y139176D01*
G37*
G36*
G01X148974Y161692D02*
X147584Y163082D01*
Y191147D01*
X147586D01*
Y192770D01*
X147965Y193149D01*
X149945D01*
G03X150055I55J1701D01*
G01X150755D01*
X151035Y193429D01*
Y193434D01*
X151954Y194353D01*
X156941D01*
X160723Y190571D01*
Y163249D01*
X159166Y161692D01*
X148974D01*
G37*
G36*
G01X136973Y203600D02*
X133121Y207452D01*
Y208532D01*
X133126D01*
Y210552D01*
X134150Y211576D01*
Y211603D01*
X134277Y211730D01*
Y238928D01*
X133309Y239896D01*
Y240332D01*
X133326D01*
Y242334D01*
X133309D01*
Y242919D01*
X134200Y243810D01*
Y252514D01*
X134264D01*
Y257518D01*
X134200D01*
Y259014D01*
X134264D01*
Y264018D01*
X134200D01*
Y265614D01*
X134264D01*
Y270618D01*
X134200D01*
Y270831D01*
X132802Y272230D01*
Y274318D01*
X134242Y275759D01*
Y284514D01*
X134264D01*
Y289518D01*
X134242D01*
Y291014D01*
X134264D01*
Y296018D01*
X134242D01*
Y297614D01*
X134264D01*
Y302618D01*
X134242D01*
Y303379D01*
X133126Y304496D01*
Y306588D01*
X134100Y307562D01*
Y316514D01*
X134264D01*
Y321518D01*
X134100D01*
Y323014D01*
X134264D01*
Y328018D01*
X134100D01*
Y329614D01*
X134264D01*
Y334668D01*
X133103Y335829D01*
Y336532D01*
X133126D01*
Y338598D01*
X134200Y339672D01*
Y348514D01*
X134264D01*
Y353518D01*
X134200D01*
Y355014D01*
X134264D01*
Y360018D01*
X134200D01*
Y361614D01*
X134264D01*
Y366470D01*
X134513Y366719D01*
X170022D01*
X170600Y366141D01*
Y209708D01*
X167492Y206600D01*
X162492D01*
X159492Y203600D01*
X136973D01*
G37*
G36*
G01X129002Y220116D02*
X128971Y220126D01*
G03X128225Y220177I-472J-1426D01*
G01X128122Y220157D01*
X127128Y221151D01*
X127123Y221227D01*
G03X126982Y221774I-1499J-95D01*
G01X126963Y221815D01*
Y222951D01*
X126982Y222992D01*
G03X126171Y225032I-1358J641D01*
G01X126132Y225047D01*
X126063Y225116D01*
X125863D01*
X125848Y225118D01*
G03X125400I-224J-1485D01*
G01X125385Y225116D01*
X124963D01*
X124363Y225716D01*
Y231470D01*
X122613Y233220D01*
X120950D01*
X120285Y233885D01*
Y238285D01*
X121070Y239070D01*
X130300D01*
X130308Y239062D01*
X131005D01*
X131200Y238867D01*
Y221200D01*
X130116Y220116D01*
X129002D01*
G37*
G36*
G01X126924Y256385D02*
G03X126396Y256921I-1300J-752D01*
G01X126375Y256934D01*
X126063Y257246D01*
X125427D01*
X125172Y257502D01*
X124708D01*
X120931Y261278D01*
Y270518D01*
X121613Y271200D01*
X130789D01*
X131262Y270727D01*
Y265614D01*
X131287D01*
Y264018D01*
X131262D01*
Y259014D01*
X131287D01*
Y257518D01*
X131262D01*
Y252460D01*
X131048Y252246D01*
X127144D01*
X126963Y252427D01*
Y252452D01*
G03X126982Y253774I-1339J680D01*
G01X126963Y253815D01*
Y254951D01*
X126982Y254992D01*
G03Y256274I-1358J641D01*
G01X126963Y256315D01*
Y256346D01*
X126924Y256385D01*
G37*
G36*
G01X128607Y316246D02*
X128582Y316253D01*
G03X128191Y316302I-381J-1453D01*
G01X128108Y316301D01*
X127211Y317198D01*
Y321472D01*
X126663Y322020D01*
X125081D01*
X124363Y322738D01*
Y326384D01*
X120698Y330049D01*
Y334417D01*
X121481Y335200D01*
X130600D01*
X131100Y334700D01*
Y316746D01*
X130600Y316246D01*
X128607D01*
G37*
G36*
G01X121036Y302103D02*
X122133Y303200D01*
X130400D01*
X131200Y302400D01*
Y284346D01*
X131100Y284246D01*
X128163D01*
X127238Y285171D01*
Y289567D01*
X126741Y290064D01*
X125146D01*
X124363Y290847D01*
Y294833D01*
X121036Y298160D01*
Y302103D01*
G37*
G36*
G01X133126Y368722D02*
Y370774D01*
X134200Y371848D01*
Y380514D01*
X134264D01*
Y385518D01*
X134200D01*
Y387014D01*
X134264D01*
Y392018D01*
X134200D01*
Y393614D01*
X134264D01*
Y398618D01*
X133482D01*
X132900Y399200D01*
X132464D01*
Y399818D01*
X131682D01*
X131300Y400199D01*
Y403300D01*
X131398Y403398D01*
X146312D01*
X147113Y404200D01*
X151341D01*
G02X151541Y404000I0J-200D01*
G03X153392Y402148I1852J0D01*
G01X155927D01*
X157978Y404200D01*
X161992D01*
X168980Y397212D01*
Y369462D01*
X168240Y368722D01*
X133126D01*
G37*
G36*
G01X173692Y208000D02*
X171700Y209992D01*
Y362000D01*
X171761Y362061D01*
Y363424D01*
X172752Y364415D01*
X189058D01*
X189787Y363686D01*
Y357245D01*
X191243Y355789D01*
X203211D01*
X253659Y305341D01*
X255135D01*
X255136Y305340D01*
X271414D01*
X271417Y305341D01*
X272193D01*
X276276Y307836D01*
G02X276812Y307724I208J-342D01*
G03X279284Y309235I1187J836D01*
G02X279430Y309763I354J186D01*
G01X283409Y312194D01*
X288914Y315340D01*
X290486D01*
G03X292552I1033J1020D01*
G01X297246D01*
G03X299312I1033J1020D01*
G01X304006D01*
G03X306072I1033J1020D01*
G01X310765D01*
G03X312831I1033J1020D01*
G01X313404D01*
G02X313787Y314825I0J-400D01*
G03X316213Y313391I1391J-416D01*
G02X316497Y313392I142J-140D01*
G01X317133Y312756D01*
X317120Y312658D01*
G03X318756Y311022I1438J-198D01*
G01X318854Y311035D01*
X319048Y310841D01*
X319232D01*
X319233Y310840D01*
X320087D01*
G02X320487Y310455I0J-400D01*
G03X323389I1451J54D01*
G02X323789Y310840I400J-15D01*
G01X326847D01*
G02X327247Y310455I0J-400D01*
G03X330149I1451J54D01*
G02X330549Y310840I400J-15D01*
G01X333607D01*
G02X334007Y310455I0J-400D01*
G03X336908Y310590I1451J54D01*
G01X336903Y310679D01*
X337064Y310841D01*
X339148D01*
X339450Y311143D01*
X339479Y311157D01*
G03X340141Y311819I-641J1303D01*
G01X340155Y311848D01*
X341466Y313159D01*
X341593Y313098D01*
G03X343581Y313910I624J1311D01*
G01X343630Y314041D01*
X347048D01*
X348370Y315364D01*
X353526D01*
X354448Y314441D01*
X361448D01*
X363208Y316200D01*
X364068D01*
Y313176D01*
X363992Y313100D01*
Y311100D01*
X364992Y310100D01*
X365035D01*
X365072Y310062D01*
X366484D01*
X366984Y310562D01*
X378718D01*
X379155Y311000D01*
X381201D01*
X382272Y312071D01*
Y315341D01*
X408106D01*
G02X408247Y315000I0J-200D01*
G01X408204Y314956D01*
Y309545D01*
X407576Y308917D01*
Y308418D01*
X407418Y308261D01*
Y304341D01*
X406802D01*
Y304412D01*
X401800D01*
Y304341D01*
X399602D01*
Y304412D01*
X394600D01*
Y304341D01*
X392402D01*
Y304412D01*
X387400D01*
Y304341D01*
X385202D01*
Y304412D01*
X380200D01*
Y304341D01*
X378002D01*
Y304412D01*
X373000D01*
Y304341D01*
X370802D01*
Y304412D01*
X365800D01*
Y304341D01*
X365148D01*
X364792Y303985D01*
Y294200D01*
X364992Y294000D01*
X408292D01*
Y292916D01*
X408090Y292715D01*
Y291998D01*
X407292Y291200D01*
Y287341D01*
X406802D01*
Y287412D01*
X401800D01*
Y287341D01*
X399602D01*
Y287412D01*
X394600D01*
Y287341D01*
X392402D01*
Y287412D01*
X387400D01*
Y287341D01*
X385202D01*
Y287412D01*
X380200D01*
Y287341D01*
X378002D01*
Y287412D01*
X373000D01*
Y287341D01*
X370802D01*
Y287412D01*
X365800D01*
Y287341D01*
X365648D01*
Y284912D01*
X365300D01*
Y279908D01*
X365492D01*
Y277961D01*
X365666Y277788D01*
Y277408D01*
X366046D01*
X367544Y275909D01*
X367602D01*
X367673Y275838D01*
X377054D01*
X377792Y275100D01*
Y270100D01*
X380092Y267800D01*
X386192D01*
X387192Y266800D01*
Y264300D01*
X389192Y262300D01*
X429965D01*
X430993Y263328D01*
G02X431549Y263338I283J-283D01*
G03X431761Y265845I1094J1170D01*
G02X431141Y266179I-220J334D01*
G01Y270020D01*
X431462Y270341D01*
X437400D01*
X437432Y270308D01*
Y268590D01*
X437570D01*
Y264430D01*
X437987Y264013D01*
X437975Y263916D01*
G03X441192Y262600I1789J-217D01*
G01X443700D01*
X443770Y262670D01*
X443901Y262600D01*
G03X446266Y265166I851J1588D01*
G01X446972Y265872D01*
G02X447624Y265743I283J-283D01*
G03X450603Y267667I1664J692D01*
G02X450894Y268341I291J274D01*
G01X452396D01*
X452420Y268335D01*
G03X453310I445J1746D01*
G01X453334Y268341D01*
X455648D01*
X456148Y267841D01*
Y265841D01*
X451648Y263841D01*
X445148Y260341D01*
X431171Y251870D01*
G02X430616Y252014I-207J342D01*
G03X427969Y250861I-1262J-718D01*
G02X427587Y250341I-382J-120D01*
G01X427032D01*
G03X424916I-1058J-994D01*
G01X424361D01*
G02X423979Y250861I0J400D01*
G03X421209I-1385J435D01*
G02X420827Y250341I-382J-120D01*
G01X420272D01*
G03X418158Y248351I-1058J-994D01*
G01X417607Y247800D01*
X417035D01*
X416985Y247927D01*
G03X414283I-1351J-531D01*
G01X414233Y247800D01*
X409556D01*
G02X409156Y248180I0J400D01*
G03X406256I-1450J-71D01*
G02X405856Y247800I-400J20D01*
G01X401631D01*
Y247582D01*
X401252Y247203D01*
G02X400690Y247199I-283J283D01*
G03X398449Y246936I-1014J-1039D01*
G01X397979D01*
G02X397616Y247503I0J400D01*
G03X395119Y247258I-1320J606D01*
G01X395219Y247120D01*
X394875Y246776D01*
G02X394240Y246870I-283J283D01*
G03X391487Y246621I-1324J-710D01*
G02X390823Y246461I-381J123D01*
G01X390662Y246622D01*
G02X390640Y247165I282J283D01*
G03X388467Y247128I-1103J944D01*
G01X388116Y246777D01*
G02X387480Y246870I-284J282D01*
G03X384727Y246621I-1324J-710D01*
G02X384064Y246460I-381J122D01*
G01X383902Y246622D01*
G02X383880Y247165I282J283D01*
G03X381554Y247326I-1103J944D01*
G02X381297Y246719I-337J-215D01*
G01X381007Y246428D01*
X380833Y246603D01*
X380818Y246646D01*
G03X377967Y246621I-1421J-486D01*
G02X377304Y246460I-381J122D01*
G01X377142Y246622D01*
G02X377120Y247165I282J283D01*
G03X374629Y248536I-1103J944D01*
G02X373964Y248371I-382J118D01*
G01X373762Y248573D01*
G02X373740Y249116I282J283D01*
G03X371265Y250536I-1103J944D01*
G02X370605Y250384I-378J131D01*
G01X370287Y250702D01*
G02X370286Y250985I141J142D01*
G03X367820Y251799I-1029J1024D01*
G02X367425Y251341I-396J-58D01*
G01X366661D01*
G03X365137Y251367I-784J-1281D01*
G01X365091Y251341D01*
X364380D01*
G02X363984Y251797I0J400D01*
G03X361010I-1487J212D01*
G02X360614Y251341I-396J-56D01*
G01X359903D01*
X359857Y251367D01*
G03X358572Y251460I-740J-1307D01*
G01X358451Y251412D01*
X356883Y252980D01*
X356878Y252986D01*
G03X356714Y253150I-1141J-977D01*
G01X356708Y253155D01*
X356045Y253818D01*
G02X356203Y254481I283J283D01*
G03X354309Y256375I-466J1428D01*
G02X353646Y256217I-380J125D01*
G01X353521Y256342D01*
G02X353499Y256885I282J283D01*
G03X351382Y259002I-1142J975D01*
G02X350839Y259024I-260J304D01*
G01X350435Y259428D01*
X350454Y259532D01*
G03X348701Y261285I-1476J277D01*
G01X348597Y261266D01*
X346143Y263720D01*
G02X346247Y264361I282J283D01*
G03X344299Y266309I-649J1299D01*
G02X343658Y266205I-358J178D01*
G01X343263Y266600D01*
G03X341341Y268766I-1044J1009D01*
G01X341202Y268661D01*
X340615Y269248D01*
X340627Y269344D01*
G03X339675Y271156I-1789J216D01*
G02Y271864I186J354D01*
G03Y275056I-837J1596D01*
G02Y275764I186J354D01*
G03X337872Y278881I-837J1596D01*
G02X337258Y279236I-214J338D01*
G03X333658I-1800J74D01*
G02X333044Y278881I-400J-17D01*
G03X331112I-966J-1521D01*
G02X330498Y279236I-214J338D01*
G03X326898I-1800J74D01*
G02X326284Y278881I-400J-17D01*
G03X324352I-966J-1521D01*
G02X323738Y279236I-214J338D01*
G03X322904Y277789I-1800J74D01*
G02X323518Y277434I214J-338D01*
G03X323962Y276173I1800J-75D01*
G02X323812Y275841I-150J-132D01*
G01X323331D01*
X323280Y275964D01*
G03X320596I-1342J-555D01*
G01X320545Y275841D01*
X320034D01*
G02X319715Y276483I0J400D01*
G03X317401I-1157J877D01*
G02X317082Y275841I-319J-242D01*
G01X316571D01*
X316520Y275964D01*
G03X313836I-1342J-555D01*
G01X313785Y275841D01*
X313274D01*
G02X312955Y276483I0J400D01*
G03X310641I-1157J877D01*
G02X310322Y275841I-319J-242D01*
G01X309811D01*
X309760Y275964D01*
G03X307076I-1342J-555D01*
G01X307025Y275841D01*
X306515D01*
G02X306196Y276483I0J400D01*
G03X303882I-1157J877D01*
G02X303563Y275841I-319J-242D01*
G01X303052D01*
X303001Y275964D01*
G03X300317I-1342J-555D01*
G01X300266Y275841D01*
X299755D01*
G02X299436Y276483I0J400D01*
G03X297122I-1157J877D01*
G02X296803Y275841I-319J-242D01*
G01X296292D01*
X296241Y275964D01*
G03X293557I-1342J-555D01*
G01X293506Y275841D01*
X292995D01*
G02X292676Y276483I0J400D01*
G03X290362I-1157J877D01*
G02X290043Y275841I-319J-242D01*
G01X289532D01*
X289481Y275964D01*
G03X286797I-1342J-555D01*
G01X286746Y275841D01*
X286235D01*
G02X285916Y276483I0J400D01*
G03X283602I-1157J877D01*
G02X283283Y275841I-319J-242D01*
G01X282772D01*
X282721Y275964D01*
G03X280025Y274886I-1342J-555D01*
G01X280071Y274764D01*
X279937Y274630D01*
G02X279353Y274649I-283J283D01*
G03X276427Y274341I-1354J-1189D01*
G01X276025D01*
G02X275854Y274646I-1J200D01*
G03X273265Y274885I-1235J763D01*
G02X272892Y274341I-373J-144D01*
G01X272393D01*
G03X270085I-1154J-881D01*
G01X265517D01*
G03X262841I-1338J-881D01*
G01X261392D01*
X258651Y271600D01*
X258600D01*
X250400Y263400D01*
Y257900D01*
X250200Y257700D01*
X248100D01*
X248002Y257602D01*
X247998D01*
Y257598D01*
X247500Y257100D01*
Y256902D01*
X247198D01*
Y253298D01*
X247500D01*
Y238208D01*
X217292Y208000D01*
X173692D01*
G37*
G36*
G01X255551Y306341D02*
X196602Y365291D01*
Y365852D01*
X196102D01*
Y367352D01*
X193098D01*
Y365852D01*
X192598D01*
Y365533D01*
X190834D01*
X190832Y365535D01*
X173051D01*
X169970Y368616D01*
Y369036D01*
X169982Y369047D01*
Y397627D01*
X169970Y397638D01*
Y398370D01*
X173300Y401700D01*
X173646D01*
X173682Y401686D01*
G03X175536I927J2323D01*
G01X175572Y401700D01*
X177015D01*
X177040Y401693D01*
G03X178338I649J2416D01*
G01X178363Y401700D01*
X179938D01*
X179970Y401689D01*
G03X180799Y401548I828J2360D01*
G01X193042D01*
X238168Y356422D01*
Y343955D01*
X246764Y335358D01*
X251134D01*
X258051Y328441D01*
G03X260800Y327908I1769J1769D01*
G01X262776D01*
X262811Y327752D01*
G03X265547I1368J308D01*
G01X265582Y327908D01*
X266193D01*
X267068Y328783D01*
X267197Y328717D01*
G03X268414Y328667I663J1292D01*
G01X268537Y328718D01*
X269457Y327798D01*
X269803D01*
X269845Y327654D01*
G03X272633I1394J406D01*
G01X272675Y327798D01*
X272806D01*
X273805Y328797D01*
X273936Y328728D01*
G03X275122Y328647I683J1281D01*
G03X276550Y327974I1636J1619D01*
G03X279428Y327800I1449J86D01*
G01X279457Y327964D01*
X279691D01*
X280291Y328564D01*
X280426Y328480D01*
G03X282462Y328569I953J1529D01*
G01X283067Y327964D01*
X283301D01*
X283330Y327800D01*
G03X286211Y328078I1429J259D01*
G03X287054Y328570I-712J2188D01*
G03X289243Y328585I1085J1439D01*
G01X289864Y327964D01*
X290061D01*
X290090Y327800D01*
G03X292971Y328078I1429J259D01*
G03X293814Y328570I-712J2188D01*
G03X296003Y328585I1085J1439D01*
G01X296624Y327964D01*
X296821D01*
X296850Y327800D01*
G03X299731Y328082I1429J259D01*
G03X300633Y328639I-726J2184D01*
G01X300819Y328824D01*
G03X302150Y328643I839J1185D01*
G01X302270Y328686D01*
X302991Y327964D01*
X303581D01*
X303610Y327800D01*
G03X306491Y328090I1429J260D01*
G03X307368Y328639I-751J2175D01*
G01X307564Y328834D01*
G03X308837Y328619I853J1175D01*
G01X308952Y328653D01*
X310007Y327598D01*
X310415D01*
X310467Y327479D01*
G03X313195Y327664I1331J581D01*
G03X314277Y328273I-546J2236D01*
G01X314654Y328650D01*
X314768Y328616D01*
G03X315584Y328615I410J1393D01*
G01X315697Y328648D01*
X316566Y327779D01*
X316309Y327523D01*
X316173Y327613D01*
G03X316594Y327225I-995J-1502D01*
G02X316751Y327548I157J123D01*
G01X317193D01*
X317248Y327435D01*
G03X319411Y326885I1310J625D01*
G01X320135Y326161D01*
X320136Y326080D01*
G03X323637Y325509I1802J30D01*
G01X323652Y325552D01*
X324114Y326014D01*
X324130D01*
X324717Y326600D01*
X326200D01*
X327700Y328100D01*
X329400D01*
X331400Y326100D01*
X333700D01*
X338234Y330634D01*
X338353Y330592D01*
G03X339353Y330602I486J1368D01*
G03X340768Y329925I1641J1613D01*
G03X343647Y329749I1450J83D01*
G01X343676Y329914D01*
X344158D01*
X344916Y330671D01*
X345040Y330620D01*
G03X346517Y330836I558J1340D01*
G01X346572Y330881D01*
X347187Y330882D01*
G02X347574Y330380I0J-400D01*
G03X350381Y330381I1404J-371D01*
G02X350768Y330884I387J103D01*
G01X351064D01*
X351218Y331038D01*
X351360Y330905D01*
G03X353799Y332132I997J1055D01*
G02X354196Y332579I397J47D01*
G01X354597D01*
X354977Y332198D01*
X362918D01*
G02X363313Y331736I0J-400D01*
G03X366134Y331939I1434J-227D01*
G01X366125Y331968D01*
Y332198D01*
X366528D01*
X366786Y331941D01*
X369248D01*
X369506Y332198D01*
X384948D01*
Y327200D01*
X382692D01*
X380200Y324708D01*
Y321592D01*
X379450Y320842D01*
X375146D01*
Y320841D01*
X373650D01*
Y320842D01*
X368646D01*
Y320841D01*
X365648D01*
X361172Y316365D01*
X359147D01*
G02X358489Y316600I-263J301D01*
G03X355632Y316080I-1432J-240D01*
G01X355636Y316060D01*
Y315841D01*
X355172D01*
X354648Y316365D01*
X347061D01*
X347039Y316540D01*
G03X344230Y315875I-1441J-179D01*
G02X343853Y315341I-377J-134D01*
G01X343331D01*
G03X340989Y315182I-1113J-932D01*
G01X339648Y313841D01*
X339287D01*
X339259Y313850D01*
G03X337398Y312650I-421J-1390D01*
G01X337390Y312583D01*
X336648Y311841D01*
X336037D01*
X336001Y311856D01*
G03X334915I-543J-1347D01*
G01X334879Y311841D01*
X333917D01*
G02X333520Y312288I0J400D01*
G03X330636I-1442J172D01*
G02X330239Y311841I-397J-47D01*
G01X329277D01*
X329241Y311856D01*
G03X328155I-543J-1347D01*
G01X328119Y311841D01*
X327157D01*
G02X326760Y312288I0J400D01*
G03X323876I-1442J172D01*
G02X323479Y311841I-397J-47D01*
G01X322517D01*
X322481Y311856D01*
G03X321395I-543J-1347D01*
G01X321359Y311841D01*
X320397D01*
G02X320000Y312288I0J400D01*
G03X317917Y313763I-1442J172D01*
G01X317789Y313700D01*
X316517Y314972D01*
X316502Y315006D01*
G03X315775Y315733I-1324J-597D01*
G01X315741Y315748D01*
X315148Y316341D01*
X313261D01*
X313241Y316519D01*
G03X310355I-1443J-159D01*
G01X310335Y316341D01*
X306502D01*
X306482Y316519D01*
G03X303596I-1443J-159D01*
G01X303576Y316341D01*
X299742D01*
X299722Y316519D01*
G03X296836I-1443J-159D01*
G01X296816Y316341D01*
X292982D01*
X292962Y316519D01*
G03X290076I-1443J-159D01*
G01X290056Y316341D01*
X288648D01*
X287675Y315785D01*
X287658Y315779D01*
G03X287203Y315519I481J-1370D01*
G01X287189Y315507D01*
X284205Y313802D01*
X284194Y313798D01*
G03X283893Y313626I565J-1338D01*
G01X283884Y313618D01*
X271148Y306341D01*
X255551D01*
G37*
G36*
G01X191700Y356900D02*
X190788Y357812D01*
Y363088D01*
X191600Y363900D01*
X196576D01*
X198700Y361776D01*
Y358000D01*
X197600Y356900D01*
X191700D01*
G37*
G36*
G01X302447Y28236D02*
X302433Y28288D01*
G03X301371Y29350I-1451J-389D01*
G01X301319Y29364D01*
X300000Y30683D01*
Y36600D01*
X300786Y37386D01*
X303914D01*
X303918Y37389D01*
X307612D01*
X308911Y36090D01*
Y29610D01*
G02X308325Y29256I-400J0D01*
G03X306484Y27275I-650J-1242D01*
G02X306144Y26664I-340J-211D01*
G01X304019D01*
X302447Y28236D01*
G37*
G36*
G01X311813Y26500D02*
X310212Y28101D01*
Y29648D01*
X313055D01*
G02X313347Y28975I0J-400D01*
G03X313266Y27147I1021J-961D01*
G02X312952Y26500I-314J-247D01*
G01X311813D01*
G37*
G36*
G01X315470Y27147D02*
G03X314828Y29338I-1102J867D01*
G01X314694Y29385D01*
Y30148D01*
X316194D01*
Y34052D01*
X314694D01*
Y34552D01*
X312635D01*
G02X312296Y35163I0J400D01*
G03X312222Y36860I-1275J795D01*
G02X312541Y37500I320J240D01*
G01X316321D01*
G02X316630Y36846I0J-400D01*
G03X318798I1084J-889D01*
G02X319107Y37500I309J254D01*
G01X323014D01*
G02X323323Y36846I0J-400D01*
G03X323244Y35175I1084J-889D01*
G02X322912Y34552I-332J-223D01*
G01X322390D01*
Y33602D01*
X321334D01*
G03Y30598I0J-1502D01*
G01X322390D01*
Y29648D01*
X323094D01*
G02X323386Y28975I0J-400D01*
G03X323305Y27147I1021J-961D01*
G02X322991Y26500I-314J-247D01*
G01X322477D01*
G02X322163Y27147I0J400D01*
G03X319959I-1102J867D01*
G02X319645Y26500I-314J-247D01*
G01X315784D01*
G02X315470Y27147I0J400D01*
G37*
G36*
G01X325509D02*
G03X325428Y28975I-1102J867D01*
G02X325720Y29648I292J273D01*
G01X326894D01*
Y30148D01*
X328394D01*
Y34052D01*
X326894D01*
Y34698D01*
X327137D01*
X327176Y34680D01*
G03X328838Y36846I578J1277D01*
G02X329147Y37500I309J254D01*
G01X332927D01*
G02X333246Y36860I-1J-400D01*
G03X334876Y34518I1201J-903D01*
G02X335390Y34134I114J-383D01*
G01Y33602D01*
X334292D01*
G03Y30598I0J-1502D01*
G01X335390D01*
Y29648D01*
X339894D01*
Y30148D01*
X341394D01*
Y34052D01*
X339894D01*
Y34552D01*
X339288D01*
G02X338956Y35175I0J400D01*
G03X338877Y36846I-1163J782D01*
G02X339186Y37500I309J254D01*
G01X343093D01*
G02X343402Y36846I0J-400D01*
G03X345570I1084J-889D01*
G02X345879Y37500I309J254D01*
G01X346313D01*
G02X346632Y36860I-1J-400D01*
G03X349034I1201J-903D01*
G02X349353Y37500I320J240D01*
G01X353133D01*
G02X353442Y36846I0J-400D01*
G03X353363Y35175I1084J-889D01*
G02X353031Y34552I-332J-223D01*
G01X351248D01*
Y34052D01*
X349748D01*
Y30148D01*
X351248D01*
Y29619D01*
G02X351065Y29419I-200J-1D01*
G03X350082Y27149I114J-1397D01*
G02X349769Y26500I-313J-249D01*
G01X345896D01*
G02X345583Y27149I0J400D01*
G03X343389I-1097J873D01*
G02X343076Y26500I-313J-249D01*
G01X342550D01*
G02X342237Y27149I0J400D01*
G03X340043I-1097J873D01*
G02X339730Y26500I-313J-249D01*
G01X335862D01*
G02X335548Y27147I0J400D01*
G03X333344I-1102J867D01*
G02X333030Y26500I-314J-247D01*
G01X332516D01*
G02X332202Y27147I0J400D01*
G03X329998I-1102J867D01*
G02X329684Y26500I-314J-247D01*
G01X325823D01*
G02X325509Y27147I0J400D01*
G37*
G36*
G01X312692Y8200D02*
X312348Y8544D01*
Y8659D01*
X312357Y8689D01*
G03X310595Y10450I-1336J425D01*
G01X310479Y10413D01*
X310376Y10516D01*
G02X310659Y11198I283J282D01*
G01X314594D01*
Y11698D01*
X316094D01*
Y14702D01*
X314594D01*
Y15202D01*
X310090D01*
Y14502D01*
X309292D01*
Y16700D01*
X310192Y17600D01*
X312572D01*
G02X312970Y17168I-1J-400D01*
G03X315766I1398J-111D01*
G02X316164Y17600I399J32D01*
G01X319265D01*
G02X319663Y17168I-1J-400D01*
G03X322430Y17357I1398J-111D01*
G01X322426Y17378D01*
Y17600D01*
X323042D01*
Y17378D01*
X323038Y17357D01*
G03X325805Y17168I1369J-300D01*
G02X326203Y17600I399J32D01*
G01X329304D01*
G02X329702Y17168I-1J-400D01*
G03X332469Y17357I1398J-111D01*
G01X332465Y17378D01*
Y17600D01*
X333082D01*
Y17378D01*
X333078Y17357D01*
G03X335845Y17168I1369J-300D01*
G02X336243Y17600I399J32D01*
G01X339344D01*
G02X339742Y17168I-1J-400D01*
G03X342509Y17357I1398J-111D01*
G01X342505Y17378D01*
Y17600D01*
X343121D01*
Y17378D01*
X343117Y17357D01*
G03X345884Y17168I1369J-300D01*
G02X346282Y17600I399J32D01*
G01X349383D01*
G02X349781Y17168I-1J-400D01*
G03X352548Y17357I1398J-111D01*
G01X352544Y17378D01*
Y17600D01*
X353161D01*
Y17378D01*
X353157Y17357D01*
G03X353714Y15914I1369J-300D01*
G02X353765Y15305I-232J-326D01*
G01X353661Y15202D01*
X351248D01*
Y14702D01*
X349748D01*
Y11698D01*
X351248D01*
Y11198D01*
X355752D01*
Y11474D01*
X356102D01*
X356144Y11329D01*
G03X357981Y10400I1348J385D01*
G01X358014Y10412D01*
X359542D01*
G02X359894Y9824I-1J-400D01*
G03X359772Y8708I1324J-709D01*
G02X359387Y8200I-385J-108D01*
G01X355852D01*
Y8667D01*
X355861Y8697D01*
G03X353189I-1336J425D01*
G01X353198Y8667D01*
Y8200D01*
X349160D01*
Y8667D01*
X349169Y8697D01*
G03X346497I-1336J425D01*
G01X346506Y8667D01*
Y8200D01*
X345812D01*
Y8667D01*
X345822Y8697D01*
G03X343150I-1336J425D01*
G01X343160Y8667D01*
Y8200D01*
X339120D01*
Y8659D01*
X339129Y8689D01*
G03X336457I-1336J425D01*
G01X336466Y8659D01*
Y8200D01*
X335774D01*
Y8662D01*
X335783Y8691D01*
G03Y9537I-1337J423D01*
G01X335774Y9566D01*
Y9662D01*
X335706Y9730D01*
X335691Y9758D01*
G03X333111Y8686I-1245J-645D01*
G01X333120Y8656D01*
Y8200D01*
X329080D01*
Y8659D01*
X329090Y8689D01*
G03X326418I-1336J425D01*
G01X326428Y8659D01*
Y8200D01*
X325734D01*
Y8659D01*
X325743Y8689D01*
G03X323071I-1336J425D01*
G01X323080Y8659D01*
Y8200D01*
X319441D01*
G02X319058Y8714I0J400D01*
G03X316370I-1344J400D01*
G02X315987Y8200I-383J-114D01*
G01X312692D01*
G37*
G36*
G01X300982Y67201D02*
X300899D01*
X300000Y68100D01*
Y74300D01*
X300898Y75198D01*
X303802D01*
X303835Y75232D01*
X307529D01*
X308680Y74080D01*
Y69569D01*
G02X308202Y69177I-400J0D01*
G03X308317Y66455I-274J-1375D01*
G02X308828Y66071I111J-384D01*
G01Y65908D01*
X307427Y64507D01*
X303593D01*
X302484Y65616D01*
Y65699D01*
G03X300982Y67201I-1502J0D01*
G37*
G36*
G01X311325Y64500D02*
X310019Y65806D01*
Y67448D01*
X313055D01*
G02X313347Y66775I0J-400D01*
G03X313160Y65103I1021J-961D01*
G02X312815Y64500I-345J-203D01*
G01X311325D01*
G37*
G36*
G01X315921D02*
G02X315576Y65103I0J400D01*
G03X314828Y67138I-1208J711D01*
G01X314694Y67185D01*
Y67900D01*
X315700D01*
X315748Y67948D01*
X316194D01*
Y68394D01*
X316200Y68400D01*
Y71400D01*
X316194Y71406D01*
Y71852D01*
X315749D01*
X315000Y72600D01*
X313500D01*
X312800Y73300D01*
Y74800D01*
X313200Y75200D01*
X316245D01*
G02X316571Y74569I0J-400D01*
G03X318857I1143J-812D01*
G02X319183Y75200I326J231D01*
G01X322938D01*
G02X323264Y74569I0J-400D01*
G03X323244Y72975I1143J-811D01*
G02X322912Y72352I-332J-223D01*
G01X322390D01*
Y71202D01*
X321856D01*
X321823Y71214D01*
G03Y68586I-489J-1314D01*
G01X321856Y68598D01*
X322390D01*
Y67448D01*
X323094D01*
G02X323386Y66775I0J-400D01*
G03X323199Y65103I1021J-961D01*
G02X322854Y64500I-345J-203D01*
G01X322614D01*
G02X322269Y65103I0J400D01*
G03X319853I-1208J711D01*
G02X319508Y64500I-345J-203D01*
G01X315921D01*
G37*
G36*
G01X325960D02*
G02X325615Y65103I0J400D01*
G03X325428Y66775I-1208J711D01*
G02X325720Y67448I292J273D01*
G01X326894D01*
Y67948D01*
X328394D01*
Y71852D01*
X326894D01*
Y72498D01*
X327137D01*
X327176Y72480D01*
G03X328897Y74569I578J1277D01*
G02X329223Y75200I326J231D01*
G01X332978D01*
G02X333304Y74569I0J-400D01*
G03X334870Y72420I1143J-812D01*
G02X335390Y72039I120J-381D01*
G01Y71202D01*
X334814D01*
X334781Y71214D01*
G03Y68586I-489J-1314D01*
G01X334814Y68598D01*
X335390D01*
Y67636D01*
G02X334876Y67253I-400J0D01*
G03X333129Y65092I-430J-1439D01*
G02X332778Y64500I-351J-192D01*
G01X332653D01*
G02X332308Y65103I0J400D01*
G03X329892I-1208J711D01*
G02X329547Y64500I-345J-203D01*
G01X325960D01*
G37*
G36*
G01X336114D02*
G02X335763Y65092I0J400D01*
G03X335589Y66789I-1317J722D01*
G02X335893Y67448I304J259D01*
G01X339894D01*
Y67948D01*
X341394D01*
Y71852D01*
X339894D01*
Y72352D01*
X339288D01*
G02X338956Y72975I0J400D01*
G03X338936Y74569I-1163J783D01*
G02X339262Y75200I326J231D01*
G01X343017D01*
G02X343343Y74569I0J-400D01*
G03X345629I1143J-812D01*
G02X345955Y75200I326J231D01*
G01X346364D01*
G02X346690Y74569I0J-400D01*
G03X348976I1143J-812D01*
G02X349302Y75200I326J231D01*
G01X353057D01*
G02X353383Y74569I0J-400D01*
G03X353363Y72975I1143J-811D01*
G02X353031Y72352I-332J-223D01*
G01X351248D01*
Y71852D01*
X349748D01*
Y67948D01*
X351248D01*
Y67419D01*
G02X351065Y67219I-200J-1D01*
G03X349974Y65105I114J-1397D01*
G02X349631Y64500I-343J-205D01*
G01X346034D01*
G02X345691Y65105I0J400D01*
G03X343281I-1205J717D01*
G02X342938Y64500I-343J-205D01*
G01X342688D01*
G02X342345Y65105I0J400D01*
G03X339935I-1205J717D01*
G02X339592Y64500I-343J-205D01*
G01X336114D01*
G37*
G36*
G01X366742Y26450D02*
X366692Y26500D01*
X366107D01*
G02X365782Y27134I-1J400D01*
G03X365551Y29147I-1217J880D01*
G02X365814Y29848I263J301D01*
G01X366144D01*
Y33752D01*
X364644D01*
Y34433D01*
X364811Y34460D01*
G03X365757Y36857I-246J1482D01*
G02X366074Y37500I317J243D01*
G01X366192D01*
X366792Y38100D01*
Y46117D01*
X366592Y46200D01*
X365892D01*
Y47163D01*
X365525Y47530D01*
X365510Y47558D01*
G03X363196Y47822I-1246J-644D01*
G02X362587I-305J258D01*
G03X360701Y48054I-1069J-908D01*
G01X360563Y47955D01*
X360485Y48033D01*
G02X360404Y47765I-399J-26D01*
G03X360273Y47558I1115J-850D01*
G01X360258Y47530D01*
X359892Y47163D01*
Y46200D01*
X355852D01*
Y46467D01*
X355861Y46497D01*
G03X353189I-1336J425D01*
G01X353198Y46467D01*
Y46200D01*
X349160D01*
Y46467D01*
X349169Y46497D01*
G03X346497I-1336J425D01*
G01X346506Y46467D01*
Y46200D01*
X345812D01*
Y46467D01*
X345822Y46497D01*
G03X343150I-1336J425D01*
G01X343160Y46467D01*
Y46200D01*
X339120D01*
Y46459D01*
X339129Y46489D01*
G03X336457I-1336J425D01*
G01X336466Y46459D01*
Y46200D01*
X335774D01*
Y46462D01*
X335783Y46491D01*
G03Y47337I-1337J423D01*
G01X335774Y47366D01*
Y47462D01*
X335706Y47530D01*
X335691Y47558D01*
G03X333111Y46486I-1245J-645D01*
G01X333120Y46456D01*
Y46200D01*
X329080D01*
Y46459D01*
X329090Y46489D01*
G03X326418I-1336J425D01*
G01X326428Y46459D01*
Y46200D01*
X325734D01*
Y46459D01*
X325743Y46489D01*
G03X323071I-1336J425D01*
G01X323080Y46459D01*
Y46200D01*
X319488D01*
G02X319095Y46670I1J400D01*
G03X316333I-1381J244D01*
G02X315940Y46200I-394J-70D01*
G01X312348D01*
Y46459D01*
X312357Y46489D01*
G03X310468Y48202I-1336J425D01*
G01X310343Y48149D01*
X310176Y48316D01*
G02X310459Y48998I283J282D01*
G01X314594D01*
Y49498D01*
X316094D01*
Y52502D01*
X314594D01*
Y53002D01*
X310090D01*
Y52302D01*
X309092D01*
Y54200D01*
X310692Y55800D01*
X313042D01*
Y55312D01*
X313032Y55282D01*
G03X315704I1336J-425D01*
G01X315694Y55312D01*
Y55800D01*
X319734D01*
Y55312D01*
X319725Y55282D01*
G03X322397I1336J-425D01*
G01X322388Y55312D01*
Y55800D01*
X323080D01*
Y55312D01*
X323071Y55282D01*
G03X325743I1336J-425D01*
G01X325734Y55312D01*
Y55800D01*
X329774D01*
Y55312D01*
X329764Y55282D01*
G03X332436I1336J-425D01*
G01X332426Y55312D01*
Y55800D01*
X333120D01*
Y55312D01*
X333111Y55282D01*
G03X335783I1336J-425D01*
G01X335774Y55312D01*
Y55800D01*
X339814D01*
Y55312D01*
X339804Y55282D01*
G03X342476I1336J-425D01*
G01X342466Y55312D01*
Y55800D01*
X343160D01*
Y55312D01*
X343150Y55282D01*
G03X345822I1336J-425D01*
G01X345812Y55312D01*
Y55800D01*
X349852D01*
Y55312D01*
X349843Y55282D01*
G03X352515I1336J-425D01*
G01X352506Y55312D01*
Y55800D01*
X353198D01*
Y55309D01*
X353189Y55280D01*
G03X353714Y53714I1337J-423D01*
G02X353765Y53105I-232J-326D01*
G01X353661Y53002D01*
X351248D01*
Y52502D01*
X349748D01*
Y49498D01*
X351248D01*
Y48998D01*
X355752D01*
Y51032D01*
X356245D01*
G02X356582Y50416I0J-400D01*
G03X358355Y48389I1180J-757D01*
G01X358396Y48408D01*
X360086D01*
G02X360372Y48287I-1J-400D01*
G01X360826Y48740D01*
X363310D01*
Y49240D01*
X364810D01*
Y52244D01*
X363310D01*
Y52744D01*
X359109D01*
X359058Y52867D01*
G03X357273Y53647I-1296J-534D01*
G01X357240Y53634D01*
X356129D01*
G02X355773Y54217I0J400D01*
G03X355861Y55285I-1247J640D01*
G01X355852Y55315D01*
Y55800D01*
X359892D01*
Y55548D01*
X359871Y55506D01*
G03X362540Y54128I1347J-664D01*
G02X363243I352J-190D01*
G03X365912Y55506I1322J714D01*
G01X365892Y55548D01*
Y55800D01*
X366792D01*
Y63900D01*
X366192Y64500D01*
X356073D01*
G02X355730Y65105I0J400D01*
G03X355777Y66453I-1205J717D01*
G02X356134Y67034I357J181D01*
G01X357250D01*
X357283Y67021D01*
G03X358681Y67268I489J1314D01*
G02X359340Y66963I259J-305D01*
G01Y66948D01*
X363844D01*
Y67448D01*
X365344D01*
Y71352D01*
X363844D01*
Y71852D01*
X360981D01*
X360596Y72236D01*
X358294D01*
X358261Y72249D01*
G03X356458Y70446I-489J-1314D01*
G01X356470Y70413D01*
Y69636D01*
X355752D01*
Y72352D01*
X355581D01*
X355449Y72702D01*
G03X355669Y74569I-923J1055D01*
G02X355995Y75200I326J231D01*
G01X366044D01*
X366910Y76066D01*
Y83439D01*
X366592Y83757D01*
Y83761D01*
X366210D01*
X365406Y84566D01*
Y85796D01*
X365673Y86063D01*
X365717Y86078D01*
G03X364129Y88517I-483J1422D01*
G02X363540I-295J271D01*
G03X361602Y86250I-1105J-1017D01*
G01Y84585D01*
X360778Y83761D01*
X355852D01*
Y86952D01*
X355859Y86979D01*
G03Y87805I-1444J413D01*
G01X355852Y87832D01*
Y87833D01*
X355837Y87875D01*
G03X353198Y86511I-1422J-483D01*
G01Y83761D01*
X349160D01*
Y86686D01*
X349180Y86728D01*
G03X346486I-1347J664D01*
G01X346506Y86686D01*
Y83761D01*
X345812D01*
Y84008D01*
X345833Y84050D01*
G03X343139I-1347J664D01*
G01X343160Y84008D01*
Y83761D01*
X339644D01*
G02X339255Y84253I0J400D01*
G03X336401Y84036I-1462J346D01*
G01X336415Y84000D01*
Y83761D01*
X335774D01*
Y86686D01*
X335794Y86728D01*
G03X333100I-1347J664D01*
G01X333120Y86686D01*
Y83761D01*
X329080D01*
Y86686D01*
X329101Y86728D01*
G03X326407I-1347J664D01*
G01X326428Y86686D01*
Y83761D01*
X325785D01*
Y84000D01*
X325799Y84036D01*
G03X322945Y84253I-1392J563D01*
G02X322556Y83761I-389J-92D01*
G01X319481D01*
G02X319100Y84280I1J400D01*
G03X316328I-1386J434D01*
G02X315947Y83761I-382J-119D01*
G01X313225D01*
X312507Y84479D01*
X312516Y84572D01*
G03X310879Y86209I-1495J142D01*
G01X310786Y86200D01*
X309665Y87321D01*
Y93631D01*
X313042D01*
Y93363D01*
X313021Y93321D01*
G03X315715I1347J-664D01*
G01X315694Y93363D01*
Y93631D01*
X319219D01*
G02X319606Y93131I0J-400D01*
G03X322440Y93352I1455J-374D01*
G01X322424Y93390D01*
Y93631D01*
X323080D01*
Y90670D01*
X323060Y90628D01*
G03X325754I1347J-664D01*
G01X325734Y90670D01*
Y93631D01*
X329774D01*
Y90670D01*
X329753Y90628D01*
G03X332447I1347J-664D01*
G01X332426Y90670D01*
Y93631D01*
X333084D01*
Y93390D01*
X333068Y93352D01*
G03X335902Y93131I1379J-595D01*
G02X336289Y93631I387J100D01*
G01X339298D01*
G02X339685Y93131I0J-400D01*
G03X342519Y93352I1455J-374D01*
G01X342503Y93390D01*
Y93631D01*
X343160D01*
Y90670D01*
X343139Y90628D01*
G03X345833I1347J-664D01*
G01X345812Y90670D01*
Y93631D01*
X349852D01*
Y90670D01*
X349832Y90628D01*
G03X352526I1347J-664D01*
G01X352506Y90670D01*
Y93631D01*
X353052D01*
Y93390D01*
X353036Y93352D01*
G03X355837Y92274I1378J-596D01*
G01X355849Y92309D01*
X355859Y92344D01*
G03Y93170I-1444J413D01*
G01X355852Y93197D01*
Y93631D01*
X359892D01*
Y93525D01*
X361355Y92061D01*
X361370Y92017D01*
G03X363904Y91490I1422J483D01*
G02X364495I296J-269D01*
G03X366592Y93634I1111J1010D01*
G01Y101300D01*
X368992D01*
Y93119D01*
X369348Y92763D01*
Y84791D01*
X368992Y84435D01*
Y76200D01*
X373890Y71302D01*
Y66699D01*
X373592Y66400D01*
X370792D01*
X368892Y64500D01*
Y56510D01*
X371342Y54060D01*
X372890D01*
X373220Y53730D01*
Y48402D01*
X371042D01*
G03X369756Y46124I0J-1502D01*
G01Y44624D01*
X368892Y43760D01*
Y38100D01*
X369392Y37600D01*
X371792D01*
X374592Y34800D01*
Y28700D01*
X372392Y26500D01*
X370292D01*
X370192Y26600D01*
X369392D01*
X369242Y26450D01*
X366742D01*
G37*
G36*
G01X318292Y95600D02*
X317492D01*
X316892Y96200D01*
Y101500D01*
X316192Y102200D01*
X312592D01*
X311992Y101600D01*
Y96100D01*
X311592Y95700D01*
X310192D01*
X309992Y95900D01*
Y104800D01*
X311292Y106100D01*
Y111069D01*
X311729Y111506D01*
X318913D01*
X319539Y110880D01*
Y104698D01*
X318592Y103751D01*
Y95900D01*
X318292Y95600D01*
G37*
G36*
G01X327302Y105621D02*
G03I-700J0D01*
G37*
G36*
G01X307192Y492300D02*
X305635Y493857D01*
G03X304155Y496183I-1243J843D01*
G02X303692Y496578I-63J395D01*
G01Y497800D01*
X306592Y500700D01*
Y502700D01*
X306492Y502800D01*
Y513400D01*
X307192Y514100D01*
X308792D01*
X309092Y513800D01*
Y512272D01*
X309492Y511872D01*
Y511500D01*
X308592Y510600D01*
Y499500D01*
X309492Y498600D01*
Y497552D01*
X309440D01*
Y493648D01*
X309492D01*
Y492600D01*
X309192Y492300D01*
X307192D01*
G37*
G36*
G01X312517Y510263D02*
X312508Y510329D01*
G03X311236Y511601I-1487J-215D01*
G01X311170Y511610D01*
X310093Y512687D01*
Y518186D01*
X310697Y518790D01*
X312495D01*
G02X312889Y518320I0J-400D01*
G03X315847I1479J-263D01*
G02X316241Y518790I394J70D01*
G01X319173D01*
G02X319570Y518341I0J-400D01*
G03X322514Y518539I1491J-183D01*
G01X322507Y518564D01*
Y518790D01*
X323080D01*
Y516070D01*
X323060Y516028D01*
G03X325754I1347J-664D01*
G01X325734Y516070D01*
Y518790D01*
X329774D01*
Y516070D01*
X329753Y516028D01*
G03X332447I1347J-664D01*
G01X332426Y516070D01*
Y518790D01*
X333001D01*
Y518564D01*
X332994Y518539D01*
G03X335938Y518341I1453J-381D01*
G02X336335Y518790I397J49D01*
G01X339252D01*
G02X339649Y518341I0J-400D01*
G03X342593Y518539I1491J-183D01*
G01X342586Y518564D01*
Y518790D01*
X343160D01*
Y516070D01*
X343139Y516028D01*
G03X345833I1347J-664D01*
G01X345812Y516070D01*
Y518790D01*
X349852D01*
Y516070D01*
X349832Y516028D01*
G03X352526I1347J-664D01*
G01X352506Y516070D01*
Y518790D01*
X353080D01*
Y518564D01*
X353073Y518539D01*
G03X356017Y518341I1453J-381D01*
G02X356414Y518790I397J49D01*
G01X359892D01*
Y515075D01*
X360205Y514761D01*
X360220Y514717D01*
G03X362658Y514094I1422J483D01*
G02X363209Y514083I270J-295D01*
G03X365687Y514669I1056J1069D01*
G01X365702Y514713D01*
X365892Y514903D01*
Y518790D01*
X368093D01*
X368753Y518130D01*
Y510159D01*
X368148Y509554D01*
X365892D01*
Y510363D01*
X365702Y510553D01*
X365687Y510597D01*
G03X363180Y511153I-1422J-483D01*
G02X362603I-289J277D01*
G03X360096Y510597I-1085J-1039D01*
G01X360081Y510553D01*
X359892Y510363D01*
Y509554D01*
X355852D01*
Y513123D01*
X355744Y513231D01*
X355729Y513275D01*
G03X353198Y511778I-1422J-484D01*
G01Y509554D01*
X349160D01*
Y512086D01*
X349180Y512128D01*
G03X346486I-1347J664D01*
G01X346506Y512086D01*
Y509554D01*
X345949D01*
Y509775D01*
X345954Y509796D01*
G03X342989Y509988I-1468J318D01*
G02X342591Y509554I-398J-34D01*
G01X339694D01*
G02X339295Y509963I1J400D01*
G03X336307Y509783I-1502J36D01*
G01X336309Y509768D01*
Y509554D01*
X335774D01*
Y512086D01*
X335794Y512128D01*
G03X333100I-1347J664D01*
G01X333120Y512086D01*
Y509554D01*
X329080D01*
Y512086D01*
X329101Y512128D01*
G03X326407I-1347J664D01*
G01X326428Y512086D01*
Y509554D01*
X325891D01*
Y509768D01*
X325893Y509783D01*
G03X322905Y509963I-1486J216D01*
G02X322506Y509554I-400J-9D01*
G01X319559D01*
G02X319161Y509989I0J400D01*
G03X316267I-1447J125D01*
G02X315869Y509554I-398J-35D01*
G01X313226D01*
X312517Y510263D01*
G37*
G36*
G01X311860Y490751D02*
X310851Y491760D01*
Y493648D01*
X311444D01*
Y497552D01*
X310851D01*
Y499875D01*
X311681Y500705D01*
X319499D01*
X320243Y499961D01*
Y496626D01*
X319918D01*
Y492724D01*
X320243D01*
Y491689D01*
X319305Y490751D01*
X311860D01*
G37*
G36*
G01X303366Y565230D02*
X302550Y566046D01*
Y571589D01*
G02X303240Y571865I400J0D01*
G03Y573935I1088J1035D01*
G02X302550Y574211I-290J276D01*
G01Y575039D01*
X303263Y575752D01*
X308206D01*
X308792Y575166D01*
Y568498D01*
G02X308301Y568109I-400J0D01*
G03X306881Y565877I-317J-1366D01*
G02X306567Y565230I-314J-247D01*
G01X303366D01*
G37*
G36*
G01Y527430D02*
X302550Y528246D01*
Y533789D01*
G02X303240Y534065I400J0D01*
G03Y536135I1088J1035D01*
G02X302550Y536411I-290J276D01*
G01Y537239D01*
X303263Y537952D01*
X308206D01*
X308792Y537366D01*
Y530654D01*
G02X308349Y530257I-400J1D01*
G03X307049Y528059I-151J-1394D01*
G02X306722Y527430I-328J-229D01*
G01X303366D01*
G37*
G36*
G01X310804Y527422D02*
X309981Y528245D01*
Y530648D01*
X314694D01*
Y531148D01*
X316194D01*
Y535052D01*
X314694D01*
Y535552D01*
X312516D01*
G02X312184Y536175I0J400D01*
G03X312070Y537887I-1163J782D01*
G02X312370Y538552I300J265D01*
G01X316365D01*
G02X316665Y537887I0J-400D01*
G03X318763I1049J-930D01*
G02X319063Y538552I300J265D01*
G01X323058D01*
G02X323358Y537887I0J-400D01*
G03X323244Y536175I1049J-930D01*
G02X322912Y535552I-332J-223D01*
G01X322390D01*
Y534402D01*
X321856D01*
X321823Y534414D01*
G03Y531786I-489J-1314D01*
G01X321856Y531798D01*
X322390D01*
Y530648D01*
X322960D01*
G02X323264Y529989I0J-400D01*
G03X323237Y528073I1143J-974D01*
G02X322925Y527422I-312J-251D01*
G01X322412D01*
G02X322112Y528087I0J400D01*
G03X320010I-1051J927D01*
G02X319710Y527422I-300J-265D01*
G01X310804D01*
G37*
G36*
G01X325577Y528073D02*
G03X325550Y529989I-1170J942D01*
G02X325854Y530648I304J259D01*
G01X326894D01*
Y531148D01*
X328394D01*
Y535052D01*
X326894D01*
Y535698D01*
X327137D01*
X327176Y535680D01*
G03X328803Y537887I578J1277D01*
G02X329103Y538552I300J265D01*
G01X332967D01*
G02X333279Y537901I0J-400D01*
G03X334876Y535518I1168J-944D01*
G02X335390Y535134I114J-383D01*
G01Y534402D01*
X334814D01*
X334781Y534414D01*
G03Y531786I-489J-1314D01*
G01X334814Y531798D01*
X335390D01*
Y530648D01*
X339894D01*
Y531148D01*
X341394D01*
Y535052D01*
X339894D01*
Y535552D01*
X339288D01*
G02X338956Y536175I0J400D01*
G03X338842Y537887I-1163J782D01*
G02X339142Y538552I300J265D01*
G01X343006D01*
G02X343318Y537901I0J-400D01*
G03X345654I1168J-944D01*
G02X345966Y538552I312J251D01*
G01X346484D01*
G02X346784Y537887I0J-400D01*
G03X348882I1049J-930D01*
G02X349182Y538552I300J265D01*
G01X353177D01*
G02X353477Y537887I0J-400D01*
G03X353363Y536175I1049J-930D01*
G02X353031Y535552I-332J-223D01*
G01X351248D01*
Y535052D01*
X349748D01*
Y531148D01*
X351248D01*
Y530619D01*
G02X351065Y530419I-200J-1D01*
G03X350133Y528088I114J-1397D01*
G02X349835Y527422I-298J-266D01*
G01X345962D01*
G02X345651Y528074I0J400D01*
G03X343321I-1165J948D01*
G02X343010Y527422I-311J-252D01*
G01X342484D01*
G02X342186Y528088I0J400D01*
G03X340094I-1046J934D01*
G02X339796Y527422I-298J-266D01*
G01X335797D01*
G02X335497Y528087I0J400D01*
G03X333395I-1051J927D01*
G02X333095Y527422I-300J-265D01*
G01X332451D01*
G02X332151Y528087I0J400D01*
G03X330049I-1051J927D01*
G02X329749Y527422I-300J-265D01*
G01X325889D01*
G02X325577Y528073I0J400D01*
G37*
G36*
G01X312348Y547009D02*
Y547459D01*
X312357Y547489D01*
G03X310523Y549225I-1336J425D01*
G02X309981Y549598I-142J374D01*
G01Y549998D01*
X314594D01*
Y550498D01*
X316094D01*
Y553502D01*
X314594D01*
Y554002D01*
X309981D01*
Y556038D01*
X310496Y556553D01*
X313042D01*
Y556312D01*
X313032Y556282D01*
G03X315704I1336J-425D01*
G01X315694Y556312D01*
Y556553D01*
X319734D01*
Y556312D01*
X319725Y556282D01*
G03X322397I1336J-425D01*
G01X322388Y556312D01*
Y556553D01*
X323080D01*
Y556312D01*
X323071Y556282D01*
G03X325743I1336J-425D01*
G01X325734Y556312D01*
Y556553D01*
X329774D01*
Y556312D01*
X329764Y556282D01*
G03X332436I1336J-425D01*
G01X332426Y556312D01*
Y556553D01*
X333120D01*
Y556312D01*
X333111Y556282D01*
G03X335783I1336J-425D01*
G01X335774Y556312D01*
Y556553D01*
X339814D01*
Y556312D01*
X339804Y556282D01*
G03X342476I1336J-425D01*
G01X342466Y556312D01*
Y556553D01*
X343160D01*
Y556312D01*
X343150Y556282D01*
G03X345822I1336J-425D01*
G01X345812Y556312D01*
Y556553D01*
X349852D01*
Y556312D01*
X349843Y556282D01*
G03X352515I1336J-425D01*
G01X352506Y556312D01*
Y556553D01*
X353198D01*
Y556309D01*
X353189Y556280D01*
G03X355861Y556285I1337J-423D01*
G01X355852Y556315D01*
Y556553D01*
X359892D01*
Y556307D01*
X359883Y556279D01*
G03X362601Y555058I1437J-437D01*
G02X363284I341J-208D01*
G03X366047Y556088I1281J784D01*
G02X366441Y556553I395J65D01*
G01X368529D01*
X368724Y556358D01*
X368677Y556237D01*
G03X369848Y554216I1403J-537D01*
G01X369912Y554206D01*
X370018Y554100D01*
X371500D01*
X371700Y554300D01*
X372480D01*
X373110Y553670D01*
Y548400D01*
X372110Y547400D01*
X369034D01*
X368643Y547009D01*
X365892D01*
Y548163D01*
X365702Y548353D01*
X365687Y548397D01*
G03X363180Y548953I-1422J-483D01*
G02X362603I-289J277D01*
G03X360096Y548397I-1085J-1039D01*
G01X360081Y548353D01*
X359892Y548163D01*
Y547009D01*
X355852D01*
Y547467D01*
X355861Y547497D01*
G03X355745Y548613I-1336J425D01*
G02X356093Y549210I348J197D01*
G01X357017D01*
X357050Y549197D01*
G03X358758Y549818I489J1314D01*
G01X363122D01*
Y550318D01*
X364622D01*
Y553322D01*
X363122D01*
Y553822D01*
X360638D01*
X360097Y554362D01*
X358173D01*
X358132Y554381D01*
G03X356150Y553299I-593J-1270D01*
G01X356126Y553126D01*
X355752D01*
Y554002D01*
X351248D01*
Y553502D01*
X349748D01*
Y550498D01*
X351248D01*
Y549998D01*
X353661D01*
X353899Y549761D01*
G02X353818Y549133I-283J-283D01*
G03X353189Y547497I707J-1211D01*
G01X353198Y547467D01*
Y547009D01*
X349160D01*
Y547467D01*
X349169Y547497D01*
G03X346497I-1336J425D01*
G01X346506Y547467D01*
Y547009D01*
X345812D01*
Y547467D01*
X345822Y547497D01*
G03X343150I-1336J425D01*
G01X343160Y547467D01*
Y547009D01*
X339120D01*
Y547459D01*
X339129Y547489D01*
G03X336457I-1336J425D01*
G01X336466Y547459D01*
Y547009D01*
X335774D01*
Y547462D01*
X335783Y547491D01*
G03Y548337I-1337J423D01*
G01X335774Y548366D01*
Y548462D01*
X335706Y548530D01*
X335691Y548558D01*
G03X333111Y547486I-1245J-645D01*
G01X333120Y547456D01*
Y547009D01*
X329080D01*
Y547459D01*
X329090Y547489D01*
G03X326418I-1336J425D01*
G01X326428Y547459D01*
Y547009D01*
X325734D01*
Y547459D01*
X325743Y547489D01*
G03X323071I-1336J425D01*
G01X323080Y547459D01*
Y547009D01*
X319444D01*
G02X319060Y547521I0J400D01*
G03X316368I-1346J393D01*
G02X315984Y547009I-384J-112D01*
G01X312348D01*
G37*
G36*
G01X310946Y565080D02*
X309981Y566045D01*
Y568448D01*
X312921D01*
G02X313225Y567789I0J-400D01*
G03X313297Y565761I1143J-975D01*
G02X313012Y565080I-285J-281D01*
G01X310946D01*
G37*
G36*
G01X315439Y565761D02*
G03X314832Y568243I-1071J1053D01*
G01X314694Y568287D01*
Y568948D01*
X316194D01*
Y572852D01*
X314694D01*
Y573352D01*
X312516D01*
G02X312184Y573975I0J400D01*
G03X311941Y575815I-1163J782D01*
G02X312203Y576517I262J302D01*
G01X316532D01*
G02X316794Y575815I0J-400D01*
G03X318634I920J-1058D01*
G02X318896Y576517I262J302D01*
G01X323225D01*
G02X323487Y575815I0J-400D01*
G03X323244Y573975I920J-1058D01*
G02X322912Y573352I-332J-223D01*
G01X322390D01*
Y572302D01*
X321369D01*
G03Y569498I-35J-1402D01*
G01X322390D01*
Y568448D01*
X323094D01*
G02X323386Y567775I0J-400D01*
G03X323464Y565776I1021J-961D01*
G02X323196Y565080I-269J-296D01*
G01X322417D01*
G02X322132Y565761I0J400D01*
G03X319990I-1071J1053D01*
G02X319705Y565080I-285J-281D01*
G01X315724D01*
G02X315439Y565761I0J400D01*
G37*
G36*
G01X325350Y565776D02*
G03X325428Y567775I-943J1038D01*
G02X325720Y568448I292J273D01*
G01X326894D01*
Y568948D01*
X328394D01*
Y572852D01*
X326894D01*
Y573498D01*
X327137D01*
X327176Y573480D01*
G03X328674Y575815I578J1277D01*
G02X328936Y576517I262J302D01*
G01X333265D01*
G02X333527Y575815I0J-400D01*
G03X334870Y573420I920J-1058D01*
G02X335390Y573039I120J-381D01*
G01Y572302D01*
X334327D01*
G03Y569498I-35J-1402D01*
G01X335390D01*
Y568448D01*
X339894D01*
Y568948D01*
X341394D01*
Y572852D01*
X339894D01*
Y573352D01*
X339288D01*
G02X338956Y573975I0J400D01*
G03X338713Y575815I-1163J782D01*
G02X338975Y576517I262J302D01*
G01X343304D01*
G02X343566Y575815I0J-400D01*
G03X345406I920J-1058D01*
G02X345668Y576517I262J302D01*
G01X346651D01*
G02X346913Y575815I0J-400D01*
G03X348753I920J-1058D01*
G02X349015Y576517I262J302D01*
G01X353344D01*
G02X353606Y575815I0J-400D01*
G03X353363Y573975I920J-1058D01*
G02X353031Y573352I-332J-223D01*
G01X351248D01*
Y572852D01*
X349748D01*
Y568948D01*
X351248D01*
Y568419D01*
G02X351065Y568219I-200J-1D01*
G03X350243Y565778I114J-1397D01*
G02X349976Y565080I-267J-298D01*
G01X345834D01*
G02X345550Y565762I0J400D01*
G03X343422I-1064J1060D01*
G02X343138Y565080I-284J-282D01*
G01X342343D01*
G02X342076Y565778I0J400D01*
G03X340204I-936J1044D01*
G02X339937Y565080I-267J-298D01*
G01X335657D01*
G02X335389Y565776I1J400D01*
G03X333503I-943J1038D01*
G02X333235Y565080I-269J-296D01*
G01X332311D01*
G02X332043Y565776I1J400D01*
G03X330157I-943J1038D01*
G02X329889Y565080I-269J-296D01*
G01X325618D01*
G02X325350Y565776I1J400D01*
G37*
G36*
G01X359892Y594323D02*
Y593839D01*
X360527Y593203D01*
X360542Y593159D01*
G03X363412Y593243I1422J483D01*
G01X363426Y593294D01*
X363605Y593472D01*
X363874Y593203D01*
X363889Y593159D01*
G03X366797Y593864I1422J483D01*
G02X367192Y594323I395J59D01*
G01X367594D01*
X369857Y592060D01*
X372130D01*
X372265Y591925D01*
Y587435D01*
X372015Y587185D01*
X369331D01*
X368519Y586373D01*
Y584924D01*
X365892D01*
Y585963D01*
X365702Y586153D01*
X365687Y586197D01*
G03X363180Y586753I-1422J-483D01*
G02X362603I-289J277D01*
G03X360096Y586197I-1085J-1039D01*
G01X360081Y586153D01*
X359892Y585963D01*
Y584924D01*
X355852D01*
Y585267D01*
X355861Y585297D01*
G03X355720Y586455I-1336J425D01*
G02X356061Y587064I341J209D01*
G01X356276D01*
X356309Y587052D01*
G03X358020Y587678I489J1314D01*
G01X362342D01*
Y588178D01*
X363842D01*
Y591182D01*
X362342D01*
Y591682D01*
X359858D01*
X359349Y592190D01*
X357432D01*
X357391Y592209D01*
G03X355693Y591802I-593J-1270D01*
G01X351248D01*
Y591302D01*
X349748D01*
Y588298D01*
X351248D01*
Y587798D01*
X353661D01*
X353899Y587561D01*
G02X353818Y586933I-283J-283D01*
G03X353189Y585297I707J-1211D01*
G01X353198Y585267D01*
Y584924D01*
X349160D01*
Y585267D01*
X349169Y585297D01*
G03X346497I-1336J425D01*
G01X346506Y585267D01*
Y584924D01*
X345812D01*
Y585267D01*
X345822Y585297D01*
G03X343150I-1336J425D01*
G01X343160Y585267D01*
Y584924D01*
X339120D01*
Y585259D01*
X339129Y585289D01*
G03X336457I-1336J425D01*
G01X336466Y585259D01*
Y584924D01*
X335774D01*
Y585262D01*
X335783Y585291D01*
G03Y586137I-1337J423D01*
G01X335774Y586166D01*
Y586262D01*
X335706Y586330D01*
X335691Y586358D01*
G03X333111Y585286I-1245J-645D01*
G01X333120Y585256D01*
Y584924D01*
X329080D01*
Y585259D01*
X329090Y585289D01*
G03X326418I-1336J425D01*
G01X326428Y585259D01*
Y584924D01*
X325734D01*
Y585259D01*
X325743Y585289D01*
G03X323071I-1336J425D01*
G01X323080Y585259D01*
Y584924D01*
X319473D01*
G02X319083Y585411I0J400D01*
G03X316345I-1369J303D01*
G02X315955Y584924I-390J-87D01*
G01X312348D01*
Y585259D01*
X312357Y585289D01*
G03X310523Y587025I-1336J425D01*
G02X309981Y587398I-142J374D01*
G01Y587798D01*
X314594D01*
Y588298D01*
X316094D01*
Y591302D01*
X314594D01*
Y591802D01*
X310822D01*
X310122Y592502D01*
X309981D01*
Y593838D01*
X310496Y594353D01*
X313042D01*
Y594112D01*
X313032Y594082D01*
G03X315704I1336J-425D01*
G01X315694Y594112D01*
Y594353D01*
X319734D01*
Y594112D01*
X319725Y594082D01*
G03X322397I1336J-425D01*
G01X322388Y594112D01*
Y594353D01*
X323080D01*
Y594112D01*
X323071Y594082D01*
G03X325743I1336J-425D01*
G01X325734Y594112D01*
Y594353D01*
X329774D01*
Y594112D01*
X329764Y594082D01*
G03X332436I1336J-425D01*
G01X332426Y594112D01*
Y594353D01*
X333120D01*
Y594112D01*
X333111Y594082D01*
G03X335783I1336J-425D01*
G01X335774Y594112D01*
Y594353D01*
X339814D01*
Y594112D01*
X339804Y594082D01*
G03X342476I1336J-425D01*
G01X342466Y594112D01*
Y594353D01*
X343160D01*
Y594112D01*
X343150Y594082D01*
G03X345822I1336J-425D01*
G01X345812Y594112D01*
Y594353D01*
X348305D01*
X348335Y594323D01*
X349397D01*
G02X349792Y593864I0J-400D01*
G03X352566I1387J-207D01*
G02X352961Y594323I395J59D01*
G01X353193D01*
Y594093D01*
X353185Y594065D01*
G03X355913Y593864I1341J-408D01*
G02X356308Y594323I395J59D01*
G01X359892D01*
G37*
G36*
G01X380150Y23384D02*
X377764Y25770D01*
Y34346D01*
X377926Y34508D01*
X381161D01*
X381238Y34430D01*
Y23384D01*
X380150D01*
G37*
G36*
G01X355622Y27149D02*
G03X355552Y28976I-1097J873D01*
G02X355752Y29637I293J272D01*
G01Y29828D01*
G02X356434Y30111I400J0D01*
G01X357111Y29434D01*
X358070D01*
X358103Y29422D01*
G03X359486Y29656I489J1314D01*
G02X360140Y29347I254J-309D01*
G01Y28914D01*
X360100Y28860D01*
G03X360116Y27147I1118J-846D01*
G02X359802Y26500I-314J-247D01*
G01X355935D01*
G02X355622Y27149I0J400D01*
G37*
G36*
G01X401092Y-10600D02*
X400692Y-10200D01*
Y-6518D01*
X400995Y-6214D01*
X401889D01*
X403589Y-7914D01*
X405995D01*
X406136Y-7773D01*
G02X406766Y-7857I283J-283D01*
G03X409436Y-7727I1302J749D01*
G02X410084Y-7609I365J-165D01*
G01X410289Y-7814D01*
X413095D01*
X413268Y-7642D01*
X413429Y-7804D01*
X413443Y-7829D01*
G03X416050Y-7879I1318J721D01*
G02X416676Y-7802I343J-206D01*
G01X416689Y-7814D01*
X419395D01*
X419492Y-7718D01*
G02X420128Y-7813I283J-283D01*
G03X422776Y-7821I1326J705D01*
G02X423411Y-7728I352J-190D01*
G01X423541Y-7859D01*
G03X423751Y-8027I859J859D01*
G02X423803Y-8664I-214J-338D01*
G03X423335Y-10113I998J-1122D01*
G02X422945Y-10600I-390J-87D01*
G01X406600D01*
G02X406205Y-10137I0J400D01*
G03X403239I-1483J236D01*
G02X402844Y-10600I-395J-63D01*
G01X401092D01*
G37*
G36*
G01X427300Y21100D02*
X426900Y21500D01*
Y26700D01*
X426600Y27000D01*
G02X426224Y27528I3J400D01*
G03X423378I-1423J479D01*
G02X422999Y27000I-379J-128D01*
G01X422831D01*
G02X422659Y27303I0J200D01*
G03X420140Y27538I-1203J719D01*
G02X419765Y27000I-375J-138D01*
G01X416560D01*
G02X416182Y27531I0J400D01*
G03X415909Y28990I-1420J489D01*
G02X416215Y29648I306J258D01*
G01X419402D01*
Y30798D01*
X420846D01*
X420879Y30786D01*
G03Y33414I489J1314D01*
G01X420846Y33402D01*
X419402D01*
Y34552D01*
X416258D01*
G02X415926Y35175I0J400D01*
G03X415698Y37002I-1163J783D01*
G02X415964Y37700I267J298D01*
G01X426948D01*
G02X427214Y37002I-1J-400D01*
G03X427755Y34612I935J-1045D01*
G01X427898Y34569D01*
Y34052D01*
X426398D01*
Y30148D01*
X427898D01*
Y29648D01*
X430053D01*
G02X430356Y28987I0J-400D01*
G03X430071Y27528I1138J-980D01*
G02X429700Y27000I-379J-128D01*
G01X429300Y26600D01*
Y21400D01*
X429000Y21100D01*
X427300D01*
G37*
G36*
G01X399831Y27000D02*
G02X399452Y27528I0J400D01*
G03X396571Y27646I-1423J479D01*
G01X396598Y27536D01*
X396377Y27315D01*
X396092Y27600D01*
Y36800D01*
X396992Y37700D01*
X400176D01*
G02X400442Y37002I-1J-400D01*
G03X401899Y34656I935J-1045D01*
G02X402448Y34285I149J-371D01*
G01Y34052D01*
X400948D01*
Y30148D01*
X402448D01*
Y29648D01*
X403403D01*
G02X403696Y28976I0J-400D01*
G03X403407Y27538I1027J-954D01*
G02X403032Y27000I-375J-138D01*
G01X399831D01*
G37*
G36*
G01X405926Y27303D02*
G03X405750Y28976I-1203J719D01*
G02X406043Y29648I293J272D01*
G01X406952D01*
Y30798D01*
X407662D01*
X407695Y30786D01*
G03Y33414I489J1314D01*
G01X407662Y33402D01*
X406952D01*
Y34552D01*
X406337D01*
G02X405998Y35163I0J400D01*
G03X405787Y37018I-1275J794D01*
G02X406070Y37700I283J282D01*
G01X406500D01*
X406800Y38000D01*
Y42400D01*
X407300Y42900D01*
X408700D01*
X409300Y42300D01*
Y38200D01*
X409800Y37700D01*
X410109D01*
G02X410399Y37024I0J-400D01*
G03X412431I1016J-966D01*
G02X412721Y37700I290J276D01*
G01X413562D01*
G02X413828Y37002I-1J-400D01*
G03X414707Y34556I935J-1045D01*
G02X414898Y34356I-9J-200D01*
G01Y34052D01*
X413398D01*
Y30148D01*
X414898D01*
Y29722D01*
G02X414706Y29522I-200J0D01*
G03X413342Y27531I56J-1501D01*
G02X412964Y27000I-378J-131D01*
G01X409871D01*
G02X409492Y27528I0J400D01*
G03X406646I-1423J479D01*
G02X406267Y27000I-379J-128D01*
G01X406098D01*
G02X405926Y27303I0J200D01*
G37*
G36*
G01X366396Y8200D02*
G02X366011Y8708I0J400D01*
G03X363243Y9828I-1446J407D01*
G02X362540I-351J190D01*
G03X361160Y10615I-1322J-714D01*
G01X361073Y10611D01*
X360869Y10815D01*
X361131Y11076D01*
X363294D01*
Y11576D01*
X364794D01*
Y14580D01*
X363294D01*
Y15080D01*
X358667D01*
G03X357003Y15628I-1175J-766D01*
G01X356970Y15616D01*
X355996D01*
G02X355670Y16247I0J400D01*
G03X355924Y17168I-1144J811D01*
G02X356322Y17600I399J32D01*
G01X360480D01*
X360677Y17123D01*
X361225Y16575D01*
X361240Y16531D01*
G03X363719Y15947I1422J483D01*
G02X364276Y15953I282J-284D01*
G03X366808Y17164I1035J1089D01*
G02X367207Y17596I399J32D01*
G01X369680D01*
X371577Y15698D01*
X373290D01*
Y10500D01*
X370900D01*
X369292Y8892D01*
Y8800D01*
X368692Y8200D01*
X366396D01*
G37*
G36*
G01X442721Y10829D02*
Y9029D01*
X441992Y8300D01*
X439514D01*
Y8665D01*
X439523Y8695D01*
G03X436851I-1336J425D01*
G01X436860Y8665D01*
Y8300D01*
X436166D01*
Y8665D01*
X436176Y8695D01*
G03X433504I-1336J425D01*
G01X433514Y8665D01*
Y8300D01*
X429474D01*
Y8665D01*
X429483Y8695D01*
G03X426811I-1336J425D01*
G01X426820Y8665D01*
Y8300D01*
X423207D01*
G02X422818Y8793I0J400D01*
G03X420092I-1363J328D01*
G02X419703Y8300I-389J-93D01*
G01X416088D01*
Y8664D01*
X416098Y8694D01*
G03X413518Y9766I-1335J427D01*
G01X413503Y9738D01*
X413436Y9670D01*
Y9574D01*
X413426Y9545D01*
G03Y8699I1337J-423D01*
G01X413436Y8670D01*
Y8300D01*
X413168D01*
G02X412779Y8794I0J400D01*
G03X410053I-1363J328D01*
G02X409664Y8300I-389J-94D01*
G01X406048D01*
Y8666D01*
X406058Y8696D01*
G03X403386I-1336J425D01*
G01X403396Y8666D01*
Y8300D01*
X402702D01*
Y8666D01*
X402712Y8696D01*
G03X400040I-1336J425D01*
G01X400050Y8666D01*
Y8300D01*
X396628D01*
Y11600D01*
X399428Y14400D01*
Y16956D01*
G03Y17128I-1399J86D01*
G01Y17300D01*
X400114Y17986D01*
Y22814D01*
X400500Y23200D01*
X402100D01*
X402628Y22672D01*
Y18100D01*
X402928Y17800D01*
X403396D01*
Y17509D01*
X403386Y17480D01*
G03Y16634I1337J-423D01*
G01X403396Y16605D01*
Y16509D01*
X403463Y16441D01*
X403478Y16413D01*
G03X406058Y17485I1245J645D01*
G01X406048Y17515D01*
Y17800D01*
X406742D01*
Y17497D01*
X406733Y17467D01*
G03X409405I1336J-425D01*
G01X409396Y17497D01*
Y17800D01*
X413436D01*
Y17513D01*
X413426Y17483D01*
G03X416098I1336J-425D01*
G01X416088Y17513D01*
Y17800D01*
X419687D01*
G02X420080Y17324I0J-400D01*
G03X422832I1376J-267D01*
G02X423225Y17800I393J76D01*
G01X423474D01*
Y17497D01*
X423465Y17467D01*
G03X426137I1336J-425D01*
G01X426128Y17497D01*
Y17800D01*
X430168D01*
Y17497D01*
X430158Y17467D01*
G03X432830I1336J-425D01*
G01X432820Y17497D01*
Y17800D01*
X436860D01*
Y17514D01*
X436851Y17484D01*
G03X439523I1336J-425D01*
G01X439514Y17514D01*
Y17800D01*
X441592D01*
X442500Y16892D01*
Y15500D01*
X442201Y15202D01*
X440256D01*
Y15200D01*
X439250D01*
X438750Y14700D01*
Y11700D01*
X439250Y11200D01*
X440256D01*
Y11198D01*
X442352D01*
X442721Y10829D01*
G37*
G36*
G01X381588Y-12543D02*
Y-13887D01*
X377587Y-17888D01*
X370138D01*
X368504Y-16254D01*
Y-11111D01*
G03Y-8461I-593J1325D01*
G01Y-3564D01*
X368625Y-3512D01*
G03X369712Y-1858I-715J1654D01*
G01Y-100D01*
X369892D01*
Y7392D01*
X370700Y8200D01*
X373000D01*
X373700Y7500D01*
Y5900D01*
X375100Y4500D01*
X379500D01*
X380500Y5500D01*
Y10076D01*
X380794D01*
Y16080D01*
X380500D01*
Y16700D01*
X371992D01*
X369892Y18800D01*
Y24800D01*
X370590Y25498D01*
X372807D01*
X372808Y25500D01*
X376192D01*
X379792Y21900D01*
X381588D01*
Y424D01*
G02X380981Y83I-400J1D01*
G03X378698Y-1200I-781J-1283D01*
G01Y-2808D01*
X377090D01*
Y-2900D01*
X375100D01*
X374692Y-3308D01*
X374590D01*
Y-8312D01*
X374600D01*
Y-9645D01*
G02X374400Y-9845I-200J0D01*
G03X373838Y-12738I1J-1501D01*
G01X373876Y-12753D01*
X374090Y-12968D01*
Y-13700D01*
G03X376862Y-14502I1502J0D01*
G01X377294D01*
Y-12679D01*
G02X377671Y-12280I400J0D01*
G03X378031Y-12212I-78J1400D01*
G01X378061Y-12202D01*
X379483D01*
G03X380987Y-12198I749J1302D01*
G02X381588Y-12543I201J-345D01*
G37*
G36*
G01X373880Y78355D02*
X375296D01*
X380986Y72666D01*
Y66180D01*
X378532D01*
X378456Y66256D01*
X376894D01*
Y71602D01*
X376040D01*
Y72611D01*
X374204D01*
X373314Y73501D01*
Y77789D01*
X373880Y78355D01*
G37*
G36*
G01X357023Y33203D02*
X356825Y33402D01*
X355752D01*
Y34552D01*
X355581D01*
X355449Y34902D01*
G03X355610Y36846I-923J1055D01*
G02X355919Y37500I309J254D01*
G01X359709D01*
G02X360026Y36857I0J-400D01*
G03X359894Y35232I1192J-915D01*
G02X359542Y34644I-353J-188D01*
G01X359141D01*
X359108Y34656D01*
G03X357223Y33468I-489J-1314D01*
G01X357216Y33396D01*
X357023Y33203D01*
G37*
G36*
G01X412811Y84314D02*
G03X410019I-1396J400D01*
G02X409635Y83804I-384J-110D01*
G01X406582D01*
G02X406191Y84287I0J400D01*
G03X403315Y84074I-1469J312D01*
G01X403327Y84040D01*
Y83804D01*
X402702D01*
Y86688D01*
X402723Y86730D01*
G03X400029Y86726I-1348J662D01*
G01X400050Y86684D01*
Y83804D01*
X396724D01*
X396628Y83900D01*
Y87200D01*
X397894Y88466D01*
X397980Y88463D01*
G03X399440Y90479I49J1501D01*
G01X399428Y90512D01*
Y92900D01*
X400074Y93546D01*
X403396D01*
Y90670D01*
X403375Y90628D01*
G03X406069I1347J-664D01*
G01X406048Y90670D01*
Y93546D01*
X406671D01*
Y93310D01*
X406659Y93277D01*
G03X409538Y93064I1409J-520D01*
G02X409929Y93546I392J82D01*
G01X412900D01*
G02X413291Y93064I-1J-400D01*
G03X416231I1470J-307D01*
G02X416622Y93546I392J82D01*
G01X419593D01*
G02X419984Y93064I-1J-400D01*
G03X422863Y93277I1470J-307D01*
G01X422851Y93310D01*
Y93546D01*
X423474D01*
Y90670D01*
X423454Y90628D01*
G03X426148I1347J-664D01*
G01X426128Y90670D01*
Y93546D01*
X430168D01*
Y90670D01*
X430147Y90628D01*
G03X432841I1347J-664D01*
G01X432820Y90670D01*
Y93546D01*
X436860D01*
Y90670D01*
X436840Y90628D01*
G03X439534I1347J-664D01*
G01X439514Y90670D01*
Y93546D01*
X442446D01*
X443554Y92438D01*
Y90670D01*
X443533Y90628D01*
G03X444185Y88633I1347J-664D01*
G01X444292Y88577D01*
Y86101D01*
X444185Y86045D01*
G03X443509Y84100I695J-1331D01*
G01X443554Y84002D01*
Y83962D01*
X443396Y83804D01*
X440019D01*
G02X439634Y84311I0J400D01*
G03X436822Y84087I-1447J403D01*
G01X436840Y84048D01*
Y83804D01*
X436166D01*
Y86686D01*
X436187Y86728D01*
G03X433493I-1347J664D01*
G01X433514Y86686D01*
Y83804D01*
X429474D01*
Y86686D01*
X429494Y86728D01*
G03X426800I-1347J664D01*
G01X426820Y86686D01*
Y83804D01*
X416088D01*
Y86686D01*
X416108Y86728D01*
G03X413414I-1347J664D01*
G01X413434Y86686D01*
Y83804D01*
X413195D01*
G02X412811Y84314I0J400D01*
G37*
G36*
G01X409481Y50467D02*
G03X409515Y51442I-1297J533D01*
G02X409894Y51968I379J126D01*
G01X413398D01*
Y49914D01*
X409850D01*
G02X409481Y50467I1J400D01*
G37*
G36*
G01X427400Y58900D02*
X426800Y59500D01*
Y64400D01*
X426400Y64800D01*
X426299D01*
G02X426123Y65095I0J200D01*
G03X423378Y65328I-1322J712D01*
G02X422999Y64800I-379J-128D01*
G01X422831D01*
G02X422659Y65103I0J200D01*
G03X420140Y65338I-1203J719D01*
G02X419765Y64800I-375J-138D01*
G01X416454D01*
G02X416079Y65338I0J400D01*
G03X415790Y66776I-1316J484D01*
G02X416083Y67448I293J272D01*
G01X419402D01*
Y68598D01*
X420846D01*
X420879Y68586D01*
G03Y71214I489J1314D01*
G01X420846Y71202D01*
X419402D01*
Y72352D01*
X416258D01*
G02X415926Y72975I0J400D01*
G03X415958Y74491I-1163J783D01*
G02X416299Y75100I341J209D01*
G01X420240D01*
Y74457D01*
X420217Y74414D01*
G03X422693Y74417I1239J-657D01*
G01X422670Y74461D01*
Y75100D01*
X426613D01*
G02X426954Y74491I0J-400D01*
G03X427755Y72412I1195J-733D01*
G01X427898Y72369D01*
Y71852D01*
X426398D01*
Y67948D01*
X427898D01*
Y67448D01*
X430053D01*
G02X430356Y66787I0J-400D01*
G03X430071Y65328I1138J-980D01*
G02X429700Y64800I-379J-128D01*
G01X429500Y64600D01*
Y59300D01*
X429100Y58900D01*
X427400D01*
G37*
G36*
G01X399831Y64800D02*
G02X399452Y65328I0J400D01*
G03X397052Y66948I-1423J479D01*
G02X396392Y67252I-260J304D01*
G01Y74300D01*
X397192Y75100D01*
X399841D01*
G02X400182Y74491I0J-400D01*
G03X401899Y72456I1195J-734D01*
G02X402448Y72085I149J-371D01*
G01Y71852D01*
X400948D01*
Y67948D01*
X402448D01*
Y67448D01*
X403403D01*
G02X403696Y66776I0J-400D01*
G03X403407Y65338I1027J-954D01*
G02X403032Y64800I-375J-138D01*
G01X399831D01*
G37*
G36*
G01X405926Y65103D02*
G03X405750Y66776I-1203J719D01*
G02X406043Y67448I293J272D01*
G01X406952D01*
Y68598D01*
X407662D01*
X407695Y68586D01*
G03Y71214I489J1314D01*
G01X407662Y71202D01*
X406952D01*
Y72352D01*
X406218D01*
G02X405886Y72975I0J400D01*
G03X405918Y74491I-1163J783D01*
G02X406259Y75100I341J209D01*
G01X409880D01*
G02X410221Y74491I0J-400D01*
G03X412611I1195J-734D01*
G02X412952Y75100I341J209D01*
G01X413227D01*
G02X413568Y74491I0J-400D01*
G03X414707Y72356I1195J-734D01*
G02X414898Y72156I-9J-200D01*
G01Y71852D01*
X413398D01*
Y67948D01*
X414898D01*
Y67423D01*
G02X414707Y67223I-200J0D01*
G03X413447Y65338I56J-1401D01*
G02X413072Y64800I-375J-138D01*
G01X409871D01*
G02X409492Y65328I0J400D01*
G03X406646I-1423J479D01*
G02X406267Y64800I-379J-128D01*
G01X406098D01*
G02X405926Y65103I0J200D01*
G37*
G36*
G01X382668Y63317D02*
Y58523D01*
X381714Y57569D01*
X381577Y57661D01*
G03X381132Y55140I-785J-1161D01*
G02X381628Y54752I96J-388D01*
G01Y45617D01*
X383188Y44057D01*
Y38773D01*
X381588Y37173D01*
Y35510D01*
X377511D01*
X377402Y35400D01*
X375892D01*
X372692Y38600D01*
X372208D01*
X372207Y38602D01*
X370890D01*
X369894Y39598D01*
Y43345D01*
X371947Y45398D01*
X375156D01*
X377934Y48176D01*
X380814D01*
Y54180D01*
X375810D01*
Y53680D01*
X374410D01*
Y53720D01*
X374222Y53909D01*
Y54145D01*
X373305Y55062D01*
X371757D01*
X369894Y56925D01*
Y63602D01*
X370692Y64400D01*
X379710D01*
X380090Y64780D01*
Y65178D01*
X381628D01*
Y64357D01*
X382668Y63317D01*
G37*
G36*
G01X381628Y77517D02*
Y74405D01*
G02X380946Y74122I-400J0D01*
G01X375711Y79356D01*
X373465D01*
X372312Y78204D01*
Y78020D01*
X372192Y77900D01*
Y76500D01*
X371792Y76100D01*
X370692D01*
X370292Y76500D01*
Y84319D01*
X370350Y84376D01*
Y93178D01*
X370292Y93235D01*
Y113892D01*
X370500Y114100D01*
X376700D01*
X377092Y113708D01*
Y104400D01*
X377490Y104002D01*
Y103998D01*
X377493D01*
X378590Y102902D01*
Y102885D01*
X380601Y100875D01*
Y84031D01*
X380518Y83948D01*
Y78627D01*
X381628Y77517D01*
G37*
G36*
G01X389278Y108500D02*
Y99973D01*
X387637Y98332D01*
X384627D01*
X384375Y98080D01*
G02X383692Y98362I-283J283D01*
G01Y99200D01*
X379592Y103300D01*
Y103998D01*
X380494D01*
Y108500D01*
X389278D01*
G37*
G36*
G01X411292Y95400D02*
X410292Y96400D01*
Y103100D01*
X409092Y104300D01*
X409052D01*
X409000Y104337D01*
G03X407202Y104300I-874J-1221D01*
G01X402299D01*
G03X400501Y104337I-924J-1184D01*
G01X400449Y104300D01*
X400392D01*
X398992Y102900D01*
X396153D01*
X395389Y103664D01*
Y107104D01*
X401829Y113544D01*
X432052D01*
X432670Y114162D01*
Y114180D01*
X434890Y116400D01*
X439376D01*
Y116378D01*
X441001D01*
X441750Y115630D01*
Y110758D01*
X441192Y110200D01*
Y104800D01*
X442592Y103400D01*
Y96200D01*
X441792Y95400D01*
X441092D01*
X440592Y95900D01*
Y101600D01*
X439992Y102200D01*
X436292D01*
X435792Y101700D01*
Y96600D01*
X435192Y96000D01*
X434292D01*
X433992Y96300D01*
Y101100D01*
X430783Y104309D01*
X428587D01*
G03X426805I-891J-1209D01*
G01X422425D01*
G03X420599I-913J-1193D01*
G01X419999D01*
X419092Y103402D01*
Y95900D01*
X418692Y95500D01*
X417792D01*
X417092Y96200D01*
Y103200D01*
X415792Y104500D01*
X415404D01*
X415369Y104514D01*
G03X414269I-550J-1398D01*
G01X414234Y104500D01*
X413092D01*
X412292Y103700D01*
Y95900D01*
X411792Y95400D01*
X411292D01*
G37*
G36*
G01X386382Y270103D02*
X385799Y269520D01*
X380639D01*
X379641Y270518D01*
Y274841D01*
X377643Y276839D01*
X368088D01*
X366685Y278242D01*
Y278403D01*
X366667Y278421D01*
Y284341D01*
X428451D01*
X428466Y284326D01*
X442951D01*
X443803Y283474D01*
Y277342D01*
X442146D01*
Y272027D01*
X442135Y272016D01*
X438518D01*
X437148Y273386D01*
Y273341D01*
X436602D01*
Y273412D01*
X431600D01*
Y273341D01*
X429402D01*
Y273412D01*
X424400D01*
Y273341D01*
X422202D01*
Y273412D01*
X417200D01*
Y273341D01*
X415002D01*
Y273412D01*
X410000D01*
Y273341D01*
X407802D01*
Y273412D01*
X402800D01*
Y273341D01*
X400550D01*
Y273442D01*
X395900D01*
X395495Y273847D01*
Y275097D01*
X394164Y276428D01*
X387881D01*
X386382Y274929D01*
Y270103D01*
G37*
G36*
G01X389648Y263341D02*
X389148Y263841D01*
Y269540D01*
X389450D01*
Y274841D01*
X393891D01*
X394297Y274435D01*
Y271590D01*
X395493Y270394D01*
X429386D01*
X429457Y270323D01*
Y266504D01*
X428901Y265948D01*
G03X428626Y265673I880J-1155D01*
G01X427716Y264763D01*
Y263876D01*
X427181Y263341D01*
X389648D01*
G37*
G36*
G01X365487Y311064D02*
X365070Y311481D01*
Y315642D01*
X367692Y318264D01*
X368646D01*
Y317840D01*
X373650D01*
Y318264D01*
X375146D01*
Y317840D01*
X380259D01*
Y313520D01*
X378303Y311564D01*
X366569D01*
X366069Y311064D01*
X365487D01*
G37*
G36*
G01X452735Y319561D02*
X451589Y318415D01*
X381835D01*
X381692Y318558D01*
Y324200D01*
X383592Y326100D01*
X385792D01*
X386900Y327208D01*
X387958D01*
Y331566D01*
X388592Y332200D01*
X391992D01*
X393846Y330346D01*
Y329940D01*
X394252D01*
X394292Y329900D01*
X435048D01*
X437648Y327300D01*
X437692D01*
Y327288D01*
X442696D01*
Y327290D01*
X442810D01*
X445235Y324865D01*
X458675D01*
X459311Y324229D01*
Y320701D01*
X458959Y320349D01*
X452944D01*
X452735Y320140D01*
Y319561D01*
G37*
G36*
G01X455072Y294000D02*
X454654Y294419D01*
X454641Y294439D01*
G03X452610Y294904I-1241J-753D01*
G01X444204D01*
X444007Y295102D01*
X431077D01*
X430977Y295002D01*
X410377D01*
X410280Y294904D01*
X409294D01*
Y295002D01*
X366466D01*
X366148Y295320D01*
Y301341D01*
X445146D01*
Y301340D01*
X450150D01*
Y301341D01*
X452646D01*
Y300840D01*
X455650D01*
Y301341D01*
X456041D01*
X456900Y302200D01*
Y311900D01*
X457839Y312839D01*
X458788D01*
X459412Y313463D01*
Y315377D01*
X459836Y315802D01*
X462502D01*
Y316126D01*
X463199D01*
X463657Y315668D01*
Y312590D01*
X463032Y311965D01*
X459828D01*
X459204Y311341D01*
Y311200D01*
X459006Y311002D01*
X458998D01*
Y308998D01*
X459000D01*
Y308002D01*
X458998D01*
Y305998D01*
X459000D01*
Y305002D01*
X458998D01*
Y302998D01*
X459000D01*
Y302002D01*
X458998D01*
Y299998D01*
X459000D01*
Y299002D01*
X458998D01*
Y296998D01*
X459000D01*
Y296002D01*
X458998D01*
Y294098D01*
X458900Y294000D01*
X455072D01*
G37*
G36*
G01X354592Y334000D02*
X358912Y338320D01*
X359004Y338312D01*
G03X360565Y339873I113J1448D01*
G01X360557Y339965D01*
X361232Y340640D01*
G02X361509Y340645I141J-142D01*
G03X363561Y342697I988J1064D01*
G02X363566Y342974I147J136D01*
G01X364092Y343500D01*
X364425D01*
X364460Y343344D01*
G03X367294I1417J316D01*
G01X367329Y343500D01*
X369392D01*
X372098Y346206D01*
X372213Y346171D01*
G03X373930Y346900I424J1389D01*
G01X374393D01*
G02X374744Y346308I0J-400D01*
G03X377469Y345601I1273J-699D01*
G01X377470Y345800D01*
X381192D01*
X382992Y347600D01*
X384592D01*
X385492Y348500D01*
X403592D01*
X405692Y350600D01*
X409916D01*
G03X412256I1170J860D01*
G01X445392D01*
X453492Y342500D01*
Y340400D01*
X451092Y338000D01*
X447200D01*
X444700Y335500D01*
Y332100D01*
X442892Y330292D01*
X437508D01*
X436343Y331457D01*
Y338671D01*
X434111Y340903D01*
X394046D01*
X386343Y333200D01*
X355392D01*
X354592Y334000D01*
G37*
G36*
G01X398850Y332841D02*
Y332942D01*
X393846D01*
X393648Y333140D01*
Y338933D01*
X394594Y339879D01*
X402267D01*
X402285Y339897D01*
X433569D01*
X435142Y338324D01*
Y333002D01*
X435052Y332912D01*
X430100D01*
Y332841D01*
X427902D01*
Y332912D01*
X422900D01*
Y332841D01*
X420702D01*
Y332912D01*
X415700D01*
Y332841D01*
X413502D01*
Y332912D01*
X408500D01*
Y332841D01*
X406250D01*
Y332942D01*
X401246D01*
Y332841D01*
X398850D01*
G37*
G36*
G01X414002Y303800D02*
Y304412D01*
X409000D01*
Y304406D01*
G02X408658Y304265I-200J0D01*
G01X408577Y304346D01*
Y308502D01*
X409205Y309130D01*
Y314541D01*
X409964Y315300D01*
X439300D01*
Y315290D01*
X444302D01*
Y315300D01*
X450892D01*
X451292Y314900D01*
Y312000D01*
X450792Y311500D01*
X444892D01*
X443892Y310500D01*
Y308900D01*
X444392Y308400D01*
X446614D01*
X446639Y308394D01*
G03X447361I361J1406D01*
G01X447386Y308400D01*
X448892D01*
X449892Y307400D01*
Y304500D01*
X449734Y304342D01*
X445146D01*
Y303800D01*
X442802D01*
Y304412D01*
X437800D01*
Y303800D01*
X435602D01*
Y304412D01*
X430600D01*
Y303800D01*
X428402D01*
Y304412D01*
X423400D01*
Y303800D01*
X421202D01*
Y304412D01*
X416200D01*
Y303800D01*
X414002D01*
G37*
G36*
G01Y287300D02*
Y287412D01*
X409180D01*
X409092Y287500D01*
Y292300D01*
X410792Y294000D01*
X431392D01*
X431492Y294100D01*
X443592D01*
X444292Y293400D01*
Y288700D01*
X443004Y287412D01*
X437800D01*
Y287300D01*
X435602D01*
Y287412D01*
X430600D01*
Y287300D01*
X428402D01*
Y287412D01*
X423400D01*
Y287300D01*
X421202D01*
Y287412D01*
X416200D01*
Y287300D01*
X414002D01*
G37*
G36*
G01X412056Y514282D02*
X411428D01*
X410690Y515020D01*
Y518974D01*
X412905D01*
G02X413296Y518486I1J-400D01*
G03X416226I1465J-329D01*
G02X416617Y518974I390J88D01*
G01X419598D01*
G02X419989Y518486I1J-400D01*
G03X422854Y518702I1465J-329D01*
G01X422840Y518736D01*
Y518974D01*
X423474D01*
Y516070D01*
X423454Y516028D01*
G03X426148I1347J-664D01*
G01X426128Y516070D01*
Y518974D01*
X430168D01*
Y516070D01*
X430147Y516028D01*
G03X432841I1347J-664D01*
G01X432820Y516070D01*
Y518974D01*
X436860D01*
Y516070D01*
X436840Y516028D01*
G03X439534I1347J-664D01*
G01X439514Y516070D01*
Y518974D01*
X442524D01*
X443554Y517944D01*
Y516070D01*
X443533Y516028D01*
G03X443899Y514227I1347J-664D01*
G01Y511251D01*
G03X443380Y510195I981J-1138D01*
G01X443376Y510118D01*
X442605Y509347D01*
X440053D01*
G02X439661Y509824I0J400D01*
G03X436771Y509614I-1474J290D01*
G01X436782Y509581D01*
Y509347D01*
X436166D01*
Y512086D01*
X436187Y512128D01*
G03X433493I-1347J664D01*
G01X433514Y512086D01*
Y509347D01*
X429474D01*
Y512086D01*
X429494Y512128D01*
G03X426800I-1347J664D01*
G01X426820Y512086D01*
Y509347D01*
X423108D01*
X422700Y509755D01*
Y512200D01*
X420780Y514120D01*
X417890D01*
X416295Y515714D01*
X413489D01*
X412056Y514282D01*
G37*
G36*
G01X448368Y492492D02*
Y489647D01*
G02X447890Y489255I-400J0D01*
G01X443198Y490194D01*
X441322Y492070D01*
X433816D01*
X431285Y492576D01*
X428754Y492070D01*
X414690D01*
X412020Y489400D01*
X400292D01*
X399092Y490600D01*
Y496500D01*
X396892Y498700D01*
Y510800D01*
X397292Y511200D01*
X398592D01*
X399192Y510600D01*
Y501300D01*
X400092Y500400D01*
X406592D01*
X406992Y500800D01*
Y513082D01*
X407495Y513586D01*
X408606D01*
X409092Y513100D01*
Y501100D01*
X409892Y500300D01*
X416592D01*
X417092Y500800D01*
Y510600D01*
X417792Y511300D01*
X418392D01*
X418992Y510700D01*
Y501100D01*
X419592Y500500D01*
X423392D01*
X423792Y500900D01*
Y511000D01*
X424492Y511700D01*
X425492D01*
X426392Y510800D01*
Y500317D01*
X433362D01*
G02X433747Y499808I0J-400D01*
G03X436693Y499461I1445J-408D01*
G02X437092Y499877I400J16D01*
G01X442603D01*
X443060Y499420D01*
Y495060D01*
X443248Y494872D01*
Y493888D01*
X444232D01*
X445250Y492870D01*
X447990D01*
X448368Y492492D01*
G37*
G36*
G01X370885Y495140D02*
X369955Y496070D01*
Y527913D01*
X371653Y529611D01*
X379551D01*
X379642Y529702D01*
X380269D01*
X380543Y529976D01*
X380764D01*
Y530197D01*
X381126Y530559D01*
Y539639D01*
X380807Y539957D01*
Y539997D01*
X378086Y542718D01*
X375902D01*
X375892Y542708D01*
X375386D01*
Y542202D01*
X374810Y541626D01*
Y538106D01*
X373515Y536811D01*
X371735D01*
X369955Y538591D01*
Y546398D01*
X372302D01*
X374300Y544400D01*
X378400D01*
X380430Y546430D01*
Y548358D01*
X380622D01*
Y554362D01*
X380288D01*
X379850Y554800D01*
X373396D01*
X372895Y555302D01*
X371932D01*
G02X371532Y555701I0J400D01*
G03X370146Y557151I-1452J-1D01*
G02X369955Y557350I9J200D01*
G01Y565373D01*
X371081Y566499D01*
X378969D01*
X380286Y567816D01*
X380734D01*
Y573820D01*
X380487D01*
Y578043D01*
X378750Y579780D01*
X376196D01*
X376028Y579612D01*
X375935D01*
X374738Y578415D01*
Y578322D01*
X372982Y576566D01*
X371380D01*
X370428Y577518D01*
X370175D01*
Y583696D01*
X369680Y584192D01*
Y586118D01*
X369746Y586184D01*
X372430D01*
X372696Y586450D01*
X379565D01*
X379764Y586648D01*
X379842D01*
Y592652D01*
X379188D01*
X379120Y592720D01*
X377606D01*
Y593615D01*
G03X376169Y595052I-1402J35D01*
G01X374034D01*
X373993Y595070D01*
G03X372023Y593537I-593J-1270D01*
G02X371630Y593062I-393J-75D01*
G01X370272D01*
X369712Y593621D01*
Y604614D01*
G03X367440Y606353I-1802J0D01*
G01X367415Y606346D01*
X365406D01*
X361582Y610170D01*
G02X361728Y610829I282J283D01*
G03X362540Y611528I-510J1413D01*
G02X363243I352J-190D01*
G03X365430Y611014I1322J714D01*
G02X365986Y610918I230J-327D01*
G03X366366Y612968I1184J841D01*
G02X365813Y613079I-221J333D01*
G03X363243Y612956I-1248J-837D01*
G02X362540I-351J190D01*
G03X359733Y612469I-1322J-714D01*
G01X359723Y612404D01*
X359536Y612216D01*
X359312Y612440D01*
X359301Y612502D01*
G03X358920Y613247I-1429J-261D01*
G01Y620530D01*
X359926Y621536D01*
X362300D01*
X362700Y621136D01*
Y615800D01*
X362704Y615796D01*
Y615626D01*
X362874D01*
X363300Y615200D01*
X365204D01*
Y615126D01*
X370208D01*
Y615200D01*
X371700D01*
X372190Y614710D01*
Y610225D01*
X373493Y608922D01*
X374989D01*
X375867Y609800D01*
Y615718D01*
X377762D01*
Y620698D01*
X381132D01*
X381607Y620223D01*
Y614127D01*
X381628Y614106D01*
Y508842D01*
X382607Y507863D01*
Y507561D01*
X382664Y507504D01*
Y503340D01*
X379900Y500576D01*
Y499722D01*
X379828D01*
Y495848D01*
X379120Y495140D01*
X370885D01*
G37*
G36*
G01X376388Y541707D02*
X377640D01*
X380124Y539224D01*
Y530974D01*
X379854Y530704D01*
X377965D01*
X377277Y531392D01*
Y535842D01*
X375821Y537298D01*
Y541140D01*
X376388Y541707D01*
G37*
G36*
G01X379156Y568606D02*
X376414D01*
X376290Y568730D01*
Y573600D01*
X375740Y574150D01*
Y578000D01*
X376350Y578610D01*
X378450D01*
X379461Y577599D01*
Y568911D01*
X379156Y568606D01*
G37*
G36*
G01X399714Y565524D02*
G02X399359Y566110I-1J400D01*
G03X397034Y567932I-1330J697D01*
G02X396369Y568232I-265J300D01*
G01Y574648D01*
X397554Y575833D01*
X399707D01*
G02X400077Y575283I-1J-400D01*
G03X401899Y573456I1300J-526D01*
G02X402448Y573085I149J-371D01*
G01Y572852D01*
X400948D01*
Y568948D01*
X402448D01*
Y568448D01*
X403403D01*
G02X403696Y567776I0J-400D01*
G03X403508Y566123I1027J-954D01*
G02X403161Y565524I-347J-199D01*
G01X399714D01*
G37*
G36*
G01X406285D02*
G02X405938Y566123I0J400D01*
G03X405750Y567776I-1215J699D01*
G02X406043Y568448I293J272D01*
G01X406952D01*
Y569498D01*
X408149D01*
G03Y572302I35J1402D01*
G01X406952D01*
Y573352D01*
X406218D01*
G02X405886Y573975I0J400D01*
G03X406023Y575283I-1163J783D01*
G02X406393Y575833I371J150D01*
G01X409746D01*
G02X410116Y575283I-1J-400D01*
G03X412716I1300J-526D01*
G02X413086Y575833I371J150D01*
G01X413093D01*
G02X413463Y575283I-1J-400D01*
G03X414707Y573356I1300J-526D01*
G02X414898Y573156I-9J-200D01*
G01Y572852D01*
X413398D01*
Y568948D01*
X414898D01*
Y568523D01*
G02X414706Y568323I-200J0D01*
G03X413439Y566113I57J-1501D01*
G02X413086Y565524I-353J-189D01*
G01X409754D01*
G02X409399Y566110I-1J400D01*
G03X406739I-1330J697D01*
G02X406384Y565524I-354J-186D01*
G01X406285D01*
G37*
G36*
G01X416440D02*
G02X416087Y566113I0J400D01*
G03X415911Y567791I-1324J709D01*
G02X416217Y568448I306J257D01*
G01X419402D01*
Y569498D01*
X421333D01*
G03Y572302I35J1402D01*
G01X419402D01*
Y573352D01*
X416258D01*
G02X415926Y573975I0J400D01*
G03X416063Y575283I-1163J783D01*
G02X416433Y575833I371J150D01*
G01X426479D01*
G02X426849Y575283I-1J-400D01*
G03X427755Y573412I1300J-525D01*
G01X427898Y573369D01*
Y572852D01*
X426398D01*
Y568948D01*
X427898D01*
Y568448D01*
X430053D01*
G02X430356Y567787I0J-400D01*
G03X430164Y566110I1138J-980D01*
G02X429809Y565524I-354J-186D01*
G01X426486D01*
G02X426131Y566110I-1J400D01*
G03X423471I-1330J697D01*
G02X423116Y565524I-354J-186D01*
G01X423018D01*
G02X422671Y566123I0J400D01*
G03X420241I-1215J699D01*
G02X419894Y565524I-347J-199D01*
G01X416440D01*
G37*
G36*
G01X421862Y550688D02*
G03X420879Y553314I-494J1312D01*
G01X420846Y553302D01*
X419402D01*
Y554002D01*
X414898D01*
Y553502D01*
X413398D01*
Y550914D01*
X409850D01*
G02X409481Y551467I1J400D01*
G03X407695Y553314I-1297J533D01*
G01X407662Y553302D01*
X406952D01*
Y554002D01*
X402448D01*
Y553502D01*
X400948D01*
Y550914D01*
X397714D01*
Y552503D01*
X396369Y553849D01*
Y554554D01*
G02X397049Y554840I400J0D01*
G03X399365Y556267I980J1002D01*
G01X399356Y556297D01*
Y556643D01*
X403396D01*
Y556309D01*
X403386Y556280D01*
G03Y555434I1337J-423D01*
G01X403396Y555405D01*
Y555309D01*
X403463Y555241D01*
X403478Y555213D01*
G03X406058Y556285I1245J645D01*
G01X406048Y556315D01*
Y556643D01*
X406742D01*
Y556297D01*
X406733Y556267D01*
G03X409405I1336J-425D01*
G01X409396Y556297D01*
Y556643D01*
X413436D01*
Y556309D01*
X413426Y556280D01*
G03Y555434I1337J-423D01*
G01X413436Y555405D01*
Y555309D01*
X413503Y555241D01*
X413518Y555213D01*
G03X416098Y556285I1245J645D01*
G01X416088Y556315D01*
Y556643D01*
X419696D01*
G02X420087Y556157I0J-400D01*
G03X422825I1369J-300D01*
G02X423216Y556643I391J86D01*
G01X423474D01*
Y556297D01*
X423465Y556267D01*
G03X426137I1336J-425D01*
G01X426128Y556297D01*
Y556643D01*
X430168D01*
Y556297D01*
X430158Y556267D01*
G03X432830I1336J-425D01*
G01X432820Y556297D01*
Y556643D01*
X436860D01*
Y556314D01*
X436851Y556284D01*
G03X439523I1336J-425D01*
G01X439514Y556314D01*
Y556643D01*
X442229D01*
X443026Y555846D01*
Y554002D01*
X440256D01*
Y553502D01*
X438756D01*
Y550498D01*
X440256D01*
Y549998D01*
X443026D01*
Y547361D01*
X442733Y547068D01*
X439514D01*
Y547461D01*
X439523Y547491D01*
G03X436944Y548566I-1334J430D01*
G01X436929Y548538D01*
X436860Y548469D01*
Y548371D01*
X436851Y548342D01*
G03Y547502I1338J-420D01*
G01X436860Y547473D01*
Y547068D01*
X436166D01*
Y547461D01*
X436176Y547491D01*
G03X433597Y548566I-1334J430D01*
G01X433582Y548538D01*
X433514Y548469D01*
Y548371D01*
X433504Y548342D01*
G03Y547502I1338J-420D01*
G01X433514Y547473D01*
Y547068D01*
X429474D01*
Y547461D01*
X429483Y547491D01*
G03X426904Y548566I-1334J430D01*
G01X426889Y548538D01*
X426820Y548469D01*
Y548371D01*
X426811Y548342D01*
G03Y547502I1338J-420D01*
G01X426820Y547473D01*
Y547068D01*
X423485D01*
X423131Y547422D01*
Y548620D01*
X421720Y550031D01*
G02X421862Y550688I283J283D01*
G37*
G36*
G01X399714Y527724D02*
G02X399359Y528310I-1J400D01*
G03X397034Y530132I-1330J697D01*
G02X396369Y530432I-265J300D01*
G01Y536848D01*
X397554Y538033D01*
X399599D01*
G02X399973Y537491I0J-400D01*
G03X400102Y536163I1404J-534D01*
G02X399763Y535552I-339J-211D01*
G01X399698D01*
Y535052D01*
X398198D01*
Y531148D01*
X399698D01*
Y530648D01*
X403403D01*
G02X403696Y529976I0J-400D01*
G03X403508Y528323I1027J-954D01*
G02X403161Y527724I-347J-199D01*
G01X399714D01*
G37*
G36*
G01X406285D02*
G02X405938Y528323I0J400D01*
G03X404628Y530421I-1215J699D01*
G02X404202Y530820I-26J399D01*
G01Y531698D01*
X408149D01*
G03Y534502I35J1402D01*
G01X404202D01*
Y535159D01*
G02X404628Y535558I400J0D01*
G03X406023Y537483I95J1399D01*
G02X406393Y538033I371J150D01*
G01X409746D01*
G02X410116Y537483I-1J-400D01*
G03X412716I1300J-526D01*
G02X413086Y538033I371J150D01*
G01X413304D01*
G02X413475Y537730I0J-200D01*
G03X414706Y535456I1288J-773D01*
G02X414898Y535256I-8J-200D01*
G01Y535052D01*
X413398D01*
Y531148D01*
X414898D01*
Y530648D01*
X419402D01*
Y531698D01*
X421333D01*
G03Y534502I35J1402D01*
G01X419402D01*
Y535552D01*
X416377D01*
G02X416038Y536163I0J400D01*
G03X416167Y537491I-1275J794D01*
G02X416541Y538033I374J142D01*
G01X426479D01*
G02X426849Y537483I-1J-400D01*
G03X427755Y535612I1300J-525D01*
G01X427898Y535569D01*
Y535052D01*
X426398D01*
Y531148D01*
X427898D01*
Y530648D01*
X432402D01*
Y531698D01*
X433677D01*
X433722Y531674D01*
G03X435361Y533920I673J1230D01*
G01X435359Y533922D01*
X434780Y534502D01*
X432402D01*
Y535552D01*
X429644D01*
G02X429312Y536175I0J400D01*
G03X429449Y537483I-1163J783D01*
G02X429819Y538033I371J150D01*
G01X433064D01*
G02X433438Y537491I0J-400D01*
G03X436246I1404J-534D01*
G02X436620Y538033I374J142D01*
G01X436848D01*
G02X437015Y537724I0J-200D01*
G03X439489Y537483I1174J-767D01*
G02X439859Y538033I371J150D01*
G01X442229D01*
X443026Y537236D01*
Y535552D01*
X441756D01*
Y535052D01*
X440256D01*
Y531148D01*
X441756D01*
Y530648D01*
X443026D01*
Y528465D01*
X442285Y527724D01*
X423133D01*
G02X422780Y528313I0J400D01*
G03X420132I-1324J709D01*
G02X419779Y527724I-353J-189D01*
G01X409754D01*
G02X409399Y528310I-1J400D01*
G03X406739I-1330J697D01*
G02X406384Y527724I-354J-186D01*
G01X406285D01*
G37*
G36*
G01X355690Y528074D02*
G03X355879Y529672I-1165J948D01*
G02X356240Y530244I361J172D01*
G01X357139D01*
X357172Y530232D01*
G03X358390Y530348I489J1314D01*
G01X359982D01*
X362289Y528042D01*
X363126D01*
X363167Y528023D01*
G03X364507Y530479I593J1270D01*
G01X364414Y530538D01*
Y530848D01*
X364714D01*
Y534752D01*
X363214D01*
Y535252D01*
X358295D01*
X358254Y535270D01*
G03X356347Y533511I-593J-1270D01*
G01X356360Y533478D01*
Y533100D01*
G02X356018Y532958I-200J0D01*
G01X355751Y533225D01*
Y535552D01*
X355581D01*
X355449Y535902D01*
G03X355575Y537887I-923J1055D01*
G02X355875Y538552I300J265D01*
G01X367164D01*
X370037Y535679D01*
X372650D01*
X373250Y535079D01*
Y531203D01*
X372670Y530623D01*
X370765D01*
X369269Y529127D01*
Y528965D01*
X367726Y527422D01*
X356001D01*
G02X355690Y528074I0J400D01*
G37*
G36*
G01X355461Y565778D02*
G03X355716Y567562I-936J1044D01*
G02X356056Y568172I340J210D01*
G01X357202D01*
X357235Y568160D01*
G03X358430Y568263I489J1314D01*
G02X358730Y568090I100J-173D01*
G01Y568008D01*
X359490D01*
G02X359853Y567441I0J-400D01*
G03X360147Y565761I1365J-627D01*
G02X359862Y565080I-285J-281D01*
G01X355728D01*
G02X355461Y565778I0J400D01*
G37*
G36*
G01X366298Y565630D02*
G02X365933Y566195I0J400D01*
G03X364890Y568280I-1368J619D01*
G01X364733Y568315D01*
Y572412D01*
X363234D01*
Y572912D01*
X362471D01*
G02X362208Y573612I1J400D01*
G03X362540Y574028I-990J1130D01*
G02X363243I352J-190D01*
G03X365603Y575828I1321J715D01*
G02X365879Y576517I276J289D01*
G01X370013D01*
X372500Y574030D01*
Y568358D01*
X371898Y567756D01*
X370199D01*
X368073Y565630D01*
X366298D01*
G37*
G36*
G01X355752Y570776D02*
Y573352D01*
X355581D01*
X355449Y573702D01*
G03X355446Y575815I-923J1055D01*
G02X355708Y576517I262J302D01*
G01X359904D01*
G02X360180Y575828I0J-400D01*
G03X359975Y573899I1038J-1086D01*
G02X359644Y573274I-331J-225D01*
G01X358246D01*
X358213Y573287D01*
G03X356410Y571484I-489J-1314D01*
G01X356422Y571451D01*
Y570776D01*
X355752D01*
G37*
G36*
G01X415395Y610514D02*
X415266Y610643D01*
G02X415383Y611290I283J283D01*
G03X413394Y613279I-622J1367D01*
G02X412805Y613114I-364J166D01*
G01X409889D01*
X408589Y611814D01*
X407895D01*
X406899Y612810D01*
X402879D01*
X402845Y612969D01*
G03X402534Y613614I-1469J-311D01*
G01X402418Y613754D01*
X403918Y615254D01*
X404826D01*
Y620236D01*
X405047Y620458D01*
X410822D01*
Y614754D01*
X415826D01*
Y615254D01*
X418326D01*
Y620458D01*
X424822D01*
Y614754D01*
X429826D01*
Y615254D01*
X432326D01*
Y620458D01*
X439300D01*
X439342Y620500D01*
X440000D01*
X440581Y619919D01*
Y616881D01*
X443026Y614436D01*
Y604065D01*
X442285Y603324D01*
X439868D01*
G02X439514Y603911I0J400D01*
G03X436860I-1327J703D01*
G02X436506Y603324I-354J-187D01*
G01X433231D01*
G02X432866Y603887I0J400D01*
G03X430122I-1372J612D01*
G02X429757Y603324I-365J-163D01*
G01X426482D01*
G02X426128Y603911I0J400D01*
G03X423474I-1327J703D01*
G02X423120Y603324I-354J-187D01*
G01X406459D01*
G02X406094Y603887I0J400D01*
G03X403350I-1372J612D01*
G02X402985Y603324I-365J-163D01*
G01X399766D01*
G02X399401Y603887I0J400D01*
G03X397034Y605624I-1372J612D01*
G02X396369Y605924I-265J300D01*
G01Y609159D01*
X397795Y610586D01*
X399297D01*
X400147Y609736D01*
X402656D01*
G02X403265Y609499I221J-334D01*
G03X406130Y609342I1457J365D01*
G02X406788Y609486I375J-139D01*
G01X406889Y609386D01*
X409595D01*
X409844Y609635D01*
X410020Y609460D01*
X410035Y609414D01*
G03X412658Y609114I1380J450D01*
G02X413284Y609191I343J-206D01*
G01X413629Y608846D01*
G02X413644Y608296I-283J-283D01*
G03X416020Y606472I1118J-1004D01*
G02X416638Y606537I335J-218D01*
G01X416689Y606486D01*
X419395D01*
X419527Y606618D01*
G02X420156Y606536I283J-283D01*
G03X422210Y608590I1298J756D01*
G02X422128Y609219I201J346D01*
G01X422668Y609759D01*
Y611676D01*
G03X420239I-1215J884D01*
G01Y610765D01*
X418389Y608914D01*
X417695D01*
X416095Y610514D01*
X415395D01*
G37*
G36*
G01X423700Y584700D02*
X423100Y585300D01*
Y586200D01*
X421309Y587991D01*
G02X421379Y588613I283J283D01*
G03X420145Y591114I-746J1187D01*
G01X420112Y591102D01*
X419402D01*
Y591802D01*
X415987D01*
G02X415730Y592508I0J400D01*
G03X416234Y593962I-967J1149D01*
G02X416625Y594443I392J81D01*
G01X419696D01*
G02X420087Y593957I0J-400D01*
G03X422825I1369J-300D01*
G02X423216Y594443I391J86D01*
G01X423474D01*
Y594097D01*
X423465Y594067D01*
G03X426137I1336J-425D01*
G01X426128Y594097D01*
Y594443D01*
X430168D01*
Y594097D01*
X430158Y594067D01*
G03X432830I1336J-425D01*
G01X432820Y594097D01*
Y594443D01*
X436324D01*
G02X436716Y593962I0J-400D01*
G03X439658I1471J-303D01*
G02X440050Y594443I392J81D01*
G01X442229D01*
X443026Y593646D01*
Y591802D01*
X440256D01*
Y591302D01*
X438756D01*
Y588298D01*
X440256D01*
Y587798D01*
X443026D01*
Y585326D01*
X442400Y584700D01*
X439402D01*
Y585016D01*
X439425Y585061D01*
G03X436949Y585067I-1236J661D01*
G01X436972Y585023D01*
Y584700D01*
X436166D01*
Y585261D01*
X436176Y585291D01*
G03X433597Y586366I-1334J430D01*
G01X433582Y586338D01*
X433514Y586269D01*
Y586171D01*
X433504Y586142D01*
G03Y585302I1338J-420D01*
G01X433514Y585273D01*
Y584700D01*
X429474D01*
Y585261D01*
X429483Y585291D01*
G03X426904Y586366I-1334J430D01*
G01X426889Y586338D01*
X426820Y586269D01*
Y586171D01*
X426811Y586142D01*
G03Y585302I1338J-420D01*
G01X426820Y585273D01*
Y584700D01*
X423700D01*
G37*
G36*
G01X397614Y588614D02*
Y591304D01*
X396369Y592550D01*
Y593183D01*
X396698D01*
X396751Y593065D01*
G03X399365Y594067I1278J576D01*
G01X399356Y594097D01*
Y594443D01*
X403396D01*
Y594109D01*
X403386Y594080D01*
G03Y593234I1337J-423D01*
G01X403396Y593205D01*
Y593109D01*
X403463Y593041D01*
X403478Y593013D01*
G03X406058Y594085I1245J645D01*
G01X406048Y594115D01*
Y594443D01*
X406742D01*
Y594097D01*
X406733Y594067D01*
G03X409405I1336J-425D01*
G01X409396Y594097D01*
Y594443D01*
X412901D01*
G02X413292Y593962I-1J-400D01*
G03X414706Y592156I1471J-305D01*
G02X414898Y591956I-8J-200D01*
G01Y591302D01*
X413398D01*
Y588614D01*
X409806D01*
G02X409446Y589189I0J400D01*
G03X407695Y591114I-1262J611D01*
G01X407662Y591102D01*
X406952D01*
Y591802D01*
X402448D01*
Y591302D01*
X400948D01*
Y588614D01*
X397614D01*
G37*
G36*
G01X446807Y37706D02*
X452233D01*
X453342Y36597D01*
Y34615D01*
G03Y32785I1191J-915D01*
G01Y31750D01*
X454650D01*
X455800Y30600D01*
Y29800D01*
X454303Y28303D01*
X453342D01*
X453189Y28150D01*
X453014Y28325D01*
X452999Y28370D01*
G03X450123Y27507I-1426J-472D01*
G02X449737Y27003I-386J-104D01*
G01X447025D01*
X446262Y27766D01*
X446273Y27862D01*
G03X445711Y29151I-1393J160D01*
G01Y34704D01*
G03X446127Y36797I-829J1253D01*
G01X446035Y36934D01*
X446807Y37706D01*
G37*
G36*
G01X429703Y-3986D02*
X426697D01*
X424900Y-5782D01*
X423814Y-4697D01*
Y-2460D01*
X422938Y-1583D01*
G03X422934Y-1558I-1485J-225D01*
G01X423792Y-700D01*
X426357D01*
G02X426733Y-1235I0J-400D01*
G03X429561I1414J-508D01*
G02X429937Y-700I376J135D01*
G01X433050D01*
G02X433426Y-1235I0J-400D01*
G03X434853Y-3245I1414J-508D01*
G01X434937Y-3244D01*
X435138Y-3445D01*
X434797Y-3786D01*
X433697D01*
X432197Y-5286D01*
X431003D01*
X429703Y-3986D01*
G37*
G36*
G01X440003Y-1486D02*
X437097D01*
X436978Y-1605D01*
G02X436305Y-1411I-283J283D01*
G03X436254Y-1235I-1466J-329D01*
G02X436630Y-700I376J135D01*
G01X442192D01*
X443192Y-1700D01*
Y-3709D01*
G02X442509Y-3992I-400J0D01*
G01X440003Y-1486D01*
G37*
G36*
G01X440500Y-10700D02*
Y-10600D01*
X440043D01*
G02X439653Y-10113I0J400D01*
G03X436721I-1466J327D01*
G02X436331Y-10600I-390J-87D01*
G01X433372D01*
G02X432977Y-10137I0J400D01*
G03X430011I-1483J236D01*
G02X429616Y-10600I-395J-63D01*
G01X426657D01*
G02X426267Y-10113I0J400D01*
G03X425690Y-8576I-1466J326D01*
G01X425609Y-8516D01*
Y-8214D01*
X425903D01*
X427703Y-6414D01*
X428697D01*
X429997Y-7714D01*
X433203D01*
X434703Y-6214D01*
X435803D01*
X436491Y-5526D01*
G02X437071Y-5541I283J-283D01*
G03X439534Y-5200I1116J1005D01*
G02X440176Y-5094I359J-176D01*
G01X442597Y-7514D01*
X443390D01*
Y-9596D01*
X443389Y-9608D01*
G03X443380Y-9858I1491J-179D01*
G01X443384Y-9946D01*
X442630Y-10700D01*
X440500D01*
G37*
G36*
G01X433296Y27000D02*
G02X432917Y27528I0J400D01*
G03X432293Y29279I-1423J479D01*
G01X432199Y29338D01*
Y29648D01*
X432402D01*
Y30798D01*
X432986D01*
X433019Y30786D01*
G03Y33414I489J1314D01*
G01X432986Y33402D01*
X432402D01*
Y34552D01*
X429644D01*
G02X429312Y35175I0J400D01*
G03X429084Y37002I-1163J783D01*
G02X429350Y37700I267J298D01*
G01X433641D01*
G02X433907Y37002I-1J-400D01*
G03X435777I935J-1045D01*
G02X436043Y37700I267J298D01*
G01X436988D01*
G02X437254Y37002I-1J-400D01*
G03X439124I935J-1045D01*
G02X439390Y37700I267J298D01*
G01X439700D01*
X440200Y38200D01*
Y42400D01*
X440700Y42900D01*
X442500D01*
X442992Y42408D01*
Y34552D01*
X440256D01*
Y34052D01*
X438756D01*
Y30148D01*
X440256D01*
Y29648D01*
X442992D01*
Y28300D01*
X441692Y27000D01*
X439986D01*
G02X439608Y27531I0J400D01*
G03X436770I-1419J491D01*
G02X436392Y27000I-378J-131D01*
G01X433296D01*
G37*
G36*
G01X454677Y65827D02*
X453079D01*
X453047Y65988D01*
G03X450117Y65329I-1474J-289D01*
G02X449730Y64831I-388J-98D01*
G01X447210D01*
X446283Y65758D01*
X446282Y65839D01*
G03X445896Y66788I-1402J-17D01*
G01Y73882D01*
X447119Y75105D01*
X452431D01*
X453527Y74009D01*
Y72615D01*
G03Y70385I1006J-1115D01*
G01Y69521D01*
X453577Y69500D01*
X454800D01*
X456000Y68300D01*
Y67150D01*
X454677Y65827D01*
G37*
G36*
G01X439514Y55851D02*
X442181D01*
X442909Y55123D01*
Y53002D01*
X440256D01*
Y52502D01*
X438756D01*
Y49498D01*
X440256D01*
Y48998D01*
X442909D01*
Y46952D01*
X442100Y46143D01*
X439951D01*
G02X439560Y46627I0J400D01*
G03X436818I-1371J295D01*
G02X436427Y46143I-391J-84D01*
G01X436166D01*
Y46461D01*
X436176Y46491D01*
G03X433597Y47566I-1334J430D01*
G01X433582Y47538D01*
X433514Y47469D01*
Y47371D01*
X433504Y47342D01*
G03Y46502I1338J-420D01*
G01X433514Y46473D01*
Y46143D01*
X429474D01*
Y46461D01*
X429483Y46491D01*
G03X426904Y47566I-1334J430D01*
G01X426889Y47538D01*
X426820Y47469D01*
Y47371D01*
X426811Y47342D01*
G03Y46502I1338J-420D01*
G01X426820Y46473D01*
Y46143D01*
X424463D01*
X421612Y48994D01*
G02X421778Y49659I283J283D01*
G03X420879Y52314I-410J1341D01*
G01X420846Y52302D01*
X419402D01*
Y53002D01*
X417604D01*
X417263Y53343D01*
Y55770D01*
X417344Y55851D01*
X420240D01*
Y55557D01*
X420217Y55514D01*
G03X422693Y55517I1239J-657D01*
G01X422670Y55561D01*
Y55851D01*
X423474D01*
Y55297D01*
X423465Y55267D01*
G03X426137I1336J-425D01*
G01X426128Y55297D01*
Y55851D01*
X430168D01*
Y55297D01*
X430158Y55267D01*
G03X432830I1336J-425D01*
G01X432820Y55297D01*
Y55851D01*
X436860D01*
Y55314D01*
X436851Y55284D01*
G03X439523I1336J-425D01*
G01X439514Y55314D01*
Y55851D01*
G37*
G36*
G01X433296Y64800D02*
G02X432917Y65328I0J400D01*
G03X432293Y67079I-1423J479D01*
G01X432199Y67138D01*
Y67448D01*
X432402D01*
Y68598D01*
X432986D01*
X433019Y68586D01*
G03Y71214I489J1314D01*
G01X432986Y71202D01*
X432402D01*
Y72352D01*
X429644D01*
G02X429312Y72975I0J400D01*
G03X429344Y74491I-1163J783D01*
G02X429685Y75100I341J209D01*
G01X433190D01*
G02X433538Y74502I0J-400D01*
G03X436146I1304J-745D01*
G02X436494Y75100I348J198D01*
G01X436653D01*
G02X436994Y74491I0J-400D01*
G03X439384I1195J-734D01*
G02X439725Y75100I341J209D01*
G01X442692D01*
X443792Y74000D01*
Y72352D01*
X440256D01*
Y71852D01*
X438756D01*
Y67948D01*
X440256D01*
Y67448D01*
X443792D01*
Y66706D01*
G03X443498Y66058I1088J-884D01*
G01X443487Y65995D01*
X442292Y64800D01*
X439880D01*
G02X439505Y65338I0J400D01*
G03X436873I-1316J484D01*
G02X436498Y64800I-375J-138D01*
G01X433296D01*
G37*
G36*
G01X454192Y95300D02*
X453792Y95700D01*
Y102500D01*
X453092Y103200D01*
X449592D01*
X449092Y102700D01*
Y95800D01*
X448692Y95400D01*
X447392D01*
X447292Y95500D01*
Y100800D01*
X446382Y101710D01*
Y101784D01*
X446308D01*
X444392Y103700D01*
Y104998D01*
X444394D01*
Y110002D01*
X443770D01*
Y111758D01*
X443802D01*
Y115821D01*
X444050Y116070D01*
X449960D01*
X455892Y110138D01*
Y96100D01*
X455092Y95300D01*
X454192D01*
G37*
G36*
G01X450678Y272278D02*
X445150D01*
Y277342D01*
X445148D01*
Y283841D01*
X445604Y284296D01*
X455600D01*
Y281000D01*
X455100Y280500D01*
X454300D01*
X453404Y279604D01*
Y279496D01*
X453348Y279441D01*
Y277441D01*
X454648Y276141D01*
Y275341D01*
X451648Y272341D01*
X450678D01*
Y272278D01*
G37*
G36*
G01X457582Y281837D02*
X457124Y282295D01*
Y285748D01*
X456374Y286498D01*
X455650D01*
Y286592D01*
X452646D01*
Y286498D01*
X450150D01*
Y287342D01*
X445252D01*
X445139Y287455D01*
Y288131D01*
X445294Y288285D01*
Y293476D01*
X445639Y293822D01*
X451942D01*
X451949Y293630D01*
G03X454656Y292957I1451J56D01*
G01X455201D01*
X456125Y292033D01*
X458579D01*
X458900Y291712D01*
Y290002D01*
X458898D01*
Y287998D01*
X458900D01*
Y287002D01*
X458898D01*
Y284998D01*
X458900D01*
Y284002D01*
X458898D01*
Y282136D01*
X458600Y281837D01*
X457582D01*
G37*
G36*
G01X451551Y303341D02*
X450894Y303998D01*
Y307815D01*
X450892Y307816D01*
Y309235D01*
X450905Y309269D01*
G03X450993Y309639I-1405J530D01*
G01X451001Y309709D01*
X452600Y311308D01*
Y316792D01*
X453147Y317340D01*
X458150D01*
Y318326D01*
X459998D01*
Y318302D01*
X461896D01*
X462162Y318036D01*
Y317128D01*
X459746D01*
X458410Y315792D01*
Y314480D01*
X458148Y314217D01*
Y313841D01*
X457148D01*
X455118Y311811D01*
X455148Y311782D01*
Y308341D01*
X455648Y307841D01*
Y303341D01*
X451551D01*
G37*
G36*
G01X447686Y527669D02*
X446871Y528484D01*
Y537197D01*
X447661Y537987D01*
X454820D01*
X455686Y537121D01*
Y536447D01*
G02X455128Y536079I-400J-1D01*
G03Y533321I-595J-1379D01*
G02X455686Y532953I158J-367D01*
G01Y528636D01*
X454719Y527669D01*
X453284D01*
G02X452924Y528244I0J400D01*
G03X450222I-1351J655D01*
G02X449862Y527669I-360J-175D01*
G01X447686D01*
G37*
G36*
G01X454679Y575834D02*
X455545Y574968D01*
Y574301D01*
G02X455016Y573922I-400J0D01*
G03Y571078I-483J-1422D01*
G02X455545Y570699I129J-379D01*
G01Y566483D01*
X454578Y565516D01*
X453306D01*
G02X452942Y566081I0J400D01*
G03X450204I-1369J618D01*
G02X449840Y565516I-364J-165D01*
G01X447545D01*
X446730Y566331D01*
Y575044D01*
X447520Y575834D01*
X454679D01*
G37*
G36*
G01X433179Y565524D02*
G02X432824Y566110I-1J400D01*
G03X432293Y568079I-1330J697D01*
G01X432199Y568138D01*
Y568448D01*
X432402D01*
Y569498D01*
X433473D01*
G03Y572302I35J1402D01*
G01X432402D01*
Y573352D01*
X429644D01*
G02X429312Y573975I0J400D01*
G03X429449Y575283I-1163J783D01*
G02X429819Y575833I371J150D01*
G01X433172D01*
G02X433542Y575283I-1J-400D01*
G03X436142I1300J-526D01*
G02X436512Y575833I371J150D01*
G01X436519D01*
G02X436889Y575283I-1J-400D01*
G03X439489I1300J-526D01*
G02X439859Y575833I371J150D01*
G01X442229D01*
X443026Y575036D01*
Y573352D01*
X440256D01*
Y572852D01*
X438756D01*
Y568948D01*
X440256D01*
Y568448D01*
X443026D01*
Y566265D01*
X442285Y565524D01*
X439751D01*
G02X439404Y566123I0J400D01*
G03X436974I-1215J699D01*
G02X436627Y565524I-347J-199D01*
G01X433179D01*
G37*
G36*
G01X517500Y255000D02*
X514932Y257568D01*
Y259548D01*
X514900D01*
Y259868D01*
X514950Y259925D01*
G03X515282Y261158I-1093J956D01*
G01X515262Y261262D01*
X517662Y263662D01*
X517786Y263610D01*
G03X519804Y264924I566J1337D01*
G01X519805Y265005D01*
X520687Y265887D01*
G03X523183Y266900I1044J1009D01*
G01Y266983D01*
X523800Y267600D01*
X524365D01*
X524410Y267575D01*
G03X526508Y269244I701J1272D01*
G01X526500Y269271D01*
Y272323D01*
X526508Y272350D01*
G03Y273144I-1397J397D01*
G01X526500Y273171D01*
Y276222D01*
X526508Y276249D01*
G03Y277043I-1397J397D01*
G01X526500Y277070D01*
Y280123D01*
X526508Y280150D01*
G03Y280944I-1397J397D01*
G01X526500Y280971D01*
Y281500D01*
X526666Y281666D01*
G02X527273Y281617I283J-283D01*
G03X529714Y283368I1218J879D01*
G02X530040Y284000I326J232D01*
G01X530483D01*
X530535Y283878D01*
G03X533207I1336J569D01*
G01X533259Y284000D01*
X533702D01*
G02X534028Y283368I0J-400D01*
G03X536474I1223J-872D01*
G02X536800Y284000I326J232D01*
G01X537243D01*
X537295Y283878D01*
G03X539967I1336J569D01*
G01X540019Y284000D01*
X540462D01*
G02X540788Y283368I0J-400D01*
G03X543234I1223J-872D01*
G02X543560Y284000I326J232D01*
G01X544003D01*
X544055Y283878D01*
G03X546727I1336J569D01*
G01X546779Y284000D01*
X549500D01*
X550000Y283500D01*
Y282019D01*
G03X549547Y280428I2151J-1472D01*
G02X549066Y280018I-399J-19D01*
G03X547686Y277631I-295J-1422D01*
G02X547571Y277010I-299J-266D01*
G03X546167Y274578I1200J-2314D01*
G02X545686Y274169I-399J-18D01*
G03X545947Y271406I-295J-1422D01*
G02X546500Y271036I153J-370D01*
G01Y270558D01*
G02X545947Y270188I-400J0D01*
G03Y267506I-556J-1341D01*
G02X546500Y267136I153J-370D01*
G01Y266658D01*
G02X545947Y266288I-400J0D01*
G03Y263606I-556J-1341D01*
G02X546500Y263236I153J-370D01*
G01Y263000D01*
X546000Y262500D01*
X543911D01*
G02X543511Y262920I-1J400D01*
G03X540511I-1500J76D01*
G02X540111Y262500I-399J-20D01*
G01X537151D01*
G02X536751Y262920I-1J400D01*
G03X533751I-1500J76D01*
G02X533351Y262500I-399J-20D01*
G01X532000D01*
X531996Y262496D01*
X531910Y262498D01*
G03X530420Y261008I-39J-1451D01*
G01X530422Y260922D01*
X530000Y260500D01*
X529623D01*
X529569Y260540D01*
G03X526729Y259474I-1078J-1444D01*
G01X526717Y259417D01*
X525755Y258455D01*
X525634Y258502D01*
G03X523659Y257142I-523J-1355D01*
G01Y257059D01*
X522900Y256300D01*
X522677D01*
X522622Y256342D01*
G03X520327Y255565I-891J-1146D01*
G01X520313Y255513D01*
X519800Y255000D01*
X517500D01*
G37*
G36*
G01X606500Y-13750D02*
X604660Y-11910D01*
Y-11697D01*
G02X605157Y-11309I400J0D01*
G03Y-8493I353J1408D01*
G02X604660Y-8105I-97J388D01*
G01Y-7770D01*
X603800Y-6910D01*
Y-5500D01*
X603752Y-5452D01*
Y-5198D01*
X603498D01*
X600213Y-1913D01*
X600217Y-1824D01*
G03X599318Y-442I-1400J73D01*
G01X599190Y-393D01*
Y-28D01*
X600318D01*
Y8074D01*
X600118D01*
Y8635D01*
X600131Y8668D01*
G03X599318Y10466I-1314J489D01*
G01X599190Y10515D01*
Y15595D01*
X599323Y15643D01*
G03X598315Y18473I-506J1414D01*
G01X598282Y18461D01*
X598018D01*
X597637Y18842D01*
Y25209D01*
X598928Y26500D01*
X598995Y26508D01*
G03X600092Y27315I-178J1391D01*
G01X600107Y27348D01*
X600302Y27543D01*
Y29998D01*
X601252D01*
Y30498D01*
X602752D01*
Y33502D01*
X601252D01*
Y34002D01*
X600302D01*
Y36405D01*
X600118Y36588D01*
Y37772D01*
X600318D01*
Y45874D01*
X600118D01*
Y46435D01*
X600131Y46468D01*
G03X599318Y48266I-1314J489D01*
G01X599190Y48315D01*
Y52600D01*
X597800Y53990D01*
Y63500D01*
X598609Y64309D01*
X598702Y64302D01*
G03X600131Y66188I115J1397D01*
G01X600118Y66221D01*
Y67998D01*
X601252D01*
Y68498D01*
X602752D01*
Y71502D01*
X601252D01*
Y72002D01*
X600302D01*
Y74205D01*
X600118Y74388D01*
Y75572D01*
X600318D01*
Y83674D01*
X600118D01*
Y84235D01*
X600131Y84268D01*
G03X599318Y86066I-1314J489D01*
G01X599190Y86115D01*
Y89270D01*
X601360Y91440D01*
X601491Y91368D01*
G03X603565Y92582I672J1231D01*
G01X603567Y92780D01*
X604056D01*
X604058Y92582D01*
G03X606962Y92608I1452J17D01*
G01X606961Y92691D01*
X607850Y93580D01*
Y101300D01*
X608050Y101500D01*
X608527D01*
G03X608673I73J1500D01*
G01X613000D01*
X613200Y101300D01*
Y93680D01*
X614105Y92775D01*
X614100Y92685D01*
G03X617001Y92582I1449J-86D01*
G01X617003Y92780D01*
X629920D01*
X631650Y91050D01*
Y86250D01*
X635350Y82550D01*
X641850D01*
X643850Y84550D01*
Y92800D01*
X644450Y93400D01*
X646100D01*
X652831Y91876D01*
X653957Y90750D01*
Y88886D01*
X655190Y87652D01*
Y85792D01*
X657397Y83586D01*
X659258D01*
X662000Y80843D01*
Y70500D01*
X659500Y68000D01*
Y62502D01*
X659498D01*
Y57498D01*
X659500D01*
Y54502D01*
X659498D01*
Y49498D01*
X659500D01*
Y36740D01*
X648980D01*
X646340Y34100D01*
X643461D01*
G03X634392Y26972I-5668J-2122D01*
G01Y18084D01*
G03Y8072I3401J-5006D01*
G01Y-816D01*
G03X634307Y-10769I3401J-5006D01*
G01X634392Y-10829D01*
Y-11938D01*
X632580Y-13750D01*
X606500D01*
G37*
G36*
G01X561623Y490374D02*
X580605D01*
X587211Y483768D01*
Y455291D01*
X589987Y452515D01*
Y446246D01*
X585509Y441768D01*
X568584D01*
X558235Y452117D01*
Y486986D01*
X561623Y490374D01*
G37*
G36*
G01X595500Y473000D02*
X590500Y478000D01*
Y488500D01*
X603242D01*
G02X603629Y487996I1J-400D01*
G03X605607Y486038I1547J-415D01*
G02X606115Y485653I108J-385D01*
G01Y481440D01*
X606695Y480860D01*
Y473195D01*
X606500Y473000D01*
X595500D01*
G37*
G36*
G01X623323Y487100D02*
X621087Y489336D01*
Y491639D01*
X619750Y492976D01*
X619690D01*
X619635Y493021D01*
G03X617225I-1205J-1471D01*
G01X617170Y492976D01*
X616473D01*
G03X613267I-1603J-823D01*
G01X601626D01*
X597467Y497135D01*
Y500972D01*
X600318D01*
Y509076D01*
X600118D01*
Y509635D01*
X600131Y509668D01*
G03X598078Y511348I-1314J489D01*
G02X597467Y511688I-211J340D01*
G01Y527368D01*
G02X598078Y527708I400J0D01*
G03X600131Y529388I739J1191D01*
G01X600118Y529421D01*
Y530364D01*
X600731Y530976D01*
X603144D01*
Y531476D01*
X604644D01*
Y534480D01*
X603144D01*
Y534980D01*
X598640D01*
Y532567D01*
X598150Y532076D01*
G02X597467Y532359I-283J283D01*
G01Y535518D01*
G02X598078Y535858I400J0D01*
G03X599768Y538079I738J1192D01*
G02X600040Y538772I272J293D01*
G01X600318D01*
Y546876D01*
X600118D01*
Y547435D01*
X600131Y547468D01*
G03X598078Y549148I-1314J489D01*
G02X597467Y549488I-211J340D01*
G01Y565052D01*
G02X598067Y565398I400J0D01*
G03X600318Y566699I750J1301D01*
G01Y568364D01*
X600731Y568776D01*
X603144D01*
Y569276D01*
X604644D01*
Y572280D01*
X603144D01*
Y572780D01*
X598640D01*
Y570367D01*
X598427Y570154D01*
X598380Y570139D01*
G03X598067Y570004I434J-1437D01*
G02X597467Y570350I-200J346D01*
G01Y573318D01*
G02X598078Y573658I400J0D01*
G03X599768Y575879I738J1192D01*
G02X600040Y576572I272J293D01*
G01X600318D01*
Y584676D01*
X600118D01*
Y585235D01*
X600131Y585268D01*
G03X598078Y586948I-1314J489D01*
G02X597467Y587288I-211J340D01*
G01Y602968D01*
G02X598078Y603308I400J0D01*
G03Y605690I739J1191D01*
G02X597467Y606030I-211J340D01*
G01Y607376D01*
X602244D01*
Y607876D01*
X603744D01*
Y610880D01*
X602244D01*
Y611380D01*
X600118D01*
Y612127D01*
X600131Y612160D01*
G03X598078Y613840I-1314J489D01*
G02X597467Y614180I-211J340D01*
G01Y619467D01*
X598500Y620500D01*
X641794D01*
X646345Y615949D01*
Y595558D01*
G02X645633Y595308I-400J0D01*
G03X644852Y592991I-1133J-908D01*
G02X645340Y592687I97J-388D01*
G03X646219Y591644I1420J305D01*
G01X646345Y591594D01*
Y569845D01*
X645900Y569400D01*
Y568694D01*
G03Y568552I1450J-71D01*
G01Y567800D01*
X646800Y566900D01*
X673700D01*
X674300Y566300D01*
Y557832D01*
X663800Y547332D01*
Y529297D01*
X665697Y527400D01*
Y523186D01*
X659862Y517352D01*
X650570D01*
X650219Y517000D01*
X649500D01*
X646500Y514000D01*
Y501451D01*
X646203Y501154D01*
X646126Y501150D01*
G03X644750Y499774I74J-1450D01*
G01X644746Y499697D01*
X638877Y493828D01*
G02X638195Y494075I-283J282D01*
G03X634800Y494014I-1695J-151D01*
G01X634796Y493938D01*
X634666Y493807D01*
Y491824D01*
X634241Y491399D01*
Y487400D01*
X633941Y487100D01*
X623323D01*
G37*
G36*
G01X662400Y2100D02*
X661800Y2700D01*
Y9100D01*
X658552Y12348D01*
Y16992D01*
X655508D01*
X652710Y19790D01*
Y23230D01*
X653580Y24100D01*
X656790D01*
X657390Y23500D01*
Y22070D01*
X658460Y21000D01*
X666000D01*
X667204Y19796D01*
Y4325D01*
G03X665036Y2172I9961J-12199D01*
G01X664976Y2100D01*
X662400D01*
G37*
G36*
G01X663500Y42500D02*
X662500Y43500D01*
Y49498D01*
X662502D01*
Y54502D01*
X662500D01*
Y57498D01*
X662502D01*
Y62502D01*
X662500D01*
Y67500D01*
X664900Y69900D01*
X668900D01*
X670050Y68750D01*
Y67050D01*
X667500Y64500D01*
Y43500D01*
X666500Y42500D01*
X663500D01*
G37*
G36*
G01X638272Y207986D02*
X635656Y210602D01*
Y246656D01*
X636100Y247100D01*
X637486D01*
Y247012D01*
X639490D01*
Y247100D01*
X653800D01*
X654900Y246000D01*
X655660Y245239D01*
Y209479D01*
X654167Y207986D01*
X638272D01*
G37*
G36*
G01X633686Y248836D02*
Y234058D01*
X633162Y233534D01*
X627196D01*
X626700Y234030D01*
Y249038D01*
X627362Y249700D01*
X632822D01*
X633686Y248836D01*
G37*
G36*
G01X664267Y290666D02*
G03X665659Y291230I-1J2002D01*
G01X665718Y291287D01*
X665998D01*
Y291048D01*
X669002D01*
Y292548D01*
X669502D01*
Y296781D01*
G02X670096Y297130I400J0D01*
G03X671651Y297224I704J1270D01*
G02X672286Y296900I235J-324D01*
G01Y296502D01*
X671998D01*
Y293498D01*
X672498D01*
Y293002D01*
X671998D01*
Y289753D01*
X671842Y289718D01*
G03X672627Y287031I308J-1368D01*
G02X673131Y286811I136J-376D01*
G03X674518Y288826I1338J564D01*
G01X674440Y288829D01*
X674242Y289026D01*
X674502Y289285D01*
Y289998D01*
X675002D01*
Y290498D01*
X679325D01*
X679525Y290298D01*
X681498D01*
Y289798D01*
X684502D01*
Y292802D01*
X684002D01*
Y293298D01*
X684502D01*
Y294904D01*
X686154Y296556D01*
X686230Y296560D01*
G03X687484Y297216I-91J1700D01*
G02X688200Y296971I316J-245D01*
G01Y296850D01*
X689070Y295980D01*
X691618D01*
G03X692329Y295768I712J1089D01*
G01X693702D01*
X696930Y292540D01*
Y288100D01*
X693030Y284200D01*
X691619D01*
X691471Y284348D01*
X691458Y284402D01*
G03X688628Y284358I-1410J-348D01*
G01X688594Y284200D01*
X682730D01*
X681487Y282957D01*
G02X680937Y282943I-282J283D01*
G03X678957Y280963I-937J-1043D01*
G02X678943Y280413I-297J-268D01*
G01X678680Y280150D01*
X665745D01*
X664824Y281070D01*
X661697D01*
G03X659558Y280409I-796J-1214D01*
G01X659507Y280285D01*
X657337D01*
X655809Y281814D01*
X651910D01*
X648200Y285523D01*
X647663Y284987D01*
X645640Y287010D01*
Y291028D01*
G03X643415Y292369I-840J1122D01*
G01X643389Y292200D01*
X632421D01*
X631495Y293126D01*
Y296700D01*
X632495Y297700D01*
X643500D01*
X646100Y300300D01*
Y307009D01*
G02X646543Y307406I400J0D01*
G03Y310294I157J1444D01*
G02X646100Y310691I-43J397D01*
G01Y324273D01*
G02X646565Y324667I400J-1D01*
G03X647547Y327345I235J1433D01*
G02X647433Y327928I206J343D01*
G03X646553Y330225I-1161J872D01*
G01X646392Y330256D01*
Y333502D01*
X646100D01*
Y335498D01*
X646392D01*
Y336792D01*
X647500Y337900D01*
X658161D01*
G03X659639I739J1250D01*
G01X661600D01*
X663900Y340200D01*
X672948D01*
G02X673326Y339670I0J-400D01*
G03X676074I1374J-470D01*
G02X676452Y340200I378J130D01*
G01X686800D01*
X688461Y338539D01*
Y329929D01*
G02X687918Y329556I-400J1D01*
G03X686511Y327052I-518J-1356D01*
G02X686489Y326404I-245J-316D01*
G03X687897Y323876I811J-1204D01*
G02X688461Y323512I164J-365D01*
G01Y317239D01*
X690500Y315200D01*
Y311014D01*
X688797D01*
X687805Y310023D01*
X687751Y310010D01*
G03X687000Y307652I349J-1410D01*
G01Y305200D01*
X688200Y304000D01*
Y299549D01*
G02X687484Y299304I-400J0D01*
G03X684440Y298350I-1344J-1044D01*
G01X684436Y298274D01*
X682464Y296302D01*
X681498D01*
Y293298D01*
X681998D01*
Y292802D01*
X681498D01*
Y292302D01*
X680355D01*
X680155Y292502D01*
X675002D01*
Y293002D01*
X674502D01*
Y293498D01*
X675002D01*
Y296762D01*
G03X672631Y299187I-1080J1315D01*
G02X671997Y299221I-304J260D01*
G03X669729Y299380I-1197J-821D01*
G02X669132Y299387I-295J270D01*
G03X666698Y297651I-1132J-987D01*
G02X666352Y297052I-347J-199D01*
G01X665498D01*
Y296883D01*
X664370Y295754D01*
G02X663687Y296060I-283J283D01*
G03X663548Y296771I-1449J86D01*
G02X663752Y297311I361J172D01*
G03X661919Y298030I-552J1289D01*
G02X661702Y297495I-365J-163D01*
G03X660828Y296495I535J-1350D01*
G01X660815Y296441D01*
X660552Y296178D01*
Y294976D01*
X660141D01*
G03X659609Y295544I-1287J-672D01*
G02X659462Y296069I209J342D01*
G03X656250Y296940I-1512J781D01*
G01X656246Y296864D01*
X655991Y296608D01*
X655834Y296765D01*
X655823Y296783D01*
G03X655564Y297085I-1221J-785D01*
G02X655535Y297654I266J299D01*
G03X653541Y297577I-1035J946D01*
G02X653555Y297008I-274J-291D01*
G03X653185Y296327I1045J-1009D01*
G01X653172Y296272D01*
X650958Y294057D01*
X650874Y294058D01*
G03X652658Y292274I-18J-1802D01*
G01X652657Y292358D01*
X653316Y293017D01*
G02X653998Y292734I282J-283D01*
G01Y291998D01*
X654498D01*
Y291502D01*
X653998D01*
Y291002D01*
X653385D01*
X652088Y289704D01*
X652012Y289699D01*
G03X653499Y288212I88J-1399D01*
G01X653504Y288288D01*
X653798Y288582D01*
X653998Y288498D01*
X656340D01*
X657116Y287723D01*
Y286870D01*
X659846D01*
X659898Y286748D01*
G03X660684Y285976I1334J573D01*
G02X660893Y285432I-151J-370D01*
G03X663298Y283849I1307J-633D01*
G02X663902I302J-261D01*
G03Y285751I1098J951D01*
G02X663298I-302J261D01*
G03X662748Y286145I-1098J-951D01*
G02X662539Y286689I151J370D01*
G03X660673Y288661I-1307J632D01*
G02X660118Y289030I-155J369D01*
G01Y289872D01*
X659618D01*
Y290370D01*
X660118D01*
Y291972D01*
X660766D01*
Y290972D01*
X663182D01*
G03X664246Y290666I1064J1697D01*
G01X664267D01*
G37*
G36*
G01X663206Y572416D02*
X661668Y573954D01*
Y576347D01*
X661674Y576371D01*
G03Y577097I-1457J363D01*
G01X661668Y577121D01*
Y581168D01*
X663900Y583400D01*
X674600D01*
X674898Y583102D01*
Y580998D01*
X674700Y580800D01*
X667900D01*
X666808Y579708D01*
Y572747D01*
X666477Y572416D01*
X663206D01*
G37*
G36*
G01X713037Y1452D02*
X712437Y2052D01*
Y13237D01*
X713000Y13800D01*
X713448D01*
Y13798D01*
X716452D01*
Y13800D01*
X717052D01*
X721700Y9152D01*
X733248D01*
X733537Y8863D01*
Y3652D01*
X733137Y3252D01*
X721652D01*
X719852Y1452D01*
X713037D01*
G37*
G36*
G01X669000Y8500D02*
X668300Y9200D01*
Y10400D01*
X669300Y11400D01*
Y19700D01*
X669252Y19748D01*
Y20002D01*
X668998D01*
X667500Y21500D01*
Y23300D01*
X668650Y24450D01*
X678850D01*
X679100Y24200D01*
Y20250D01*
X675200Y16350D01*
Y9200D01*
X674500Y8500D01*
X669000D01*
G37*
G36*
G01X728430Y-10200D02*
X727990Y-9760D01*
Y-7370D01*
X727520Y-6900D01*
X722250D01*
X721600Y-6250D01*
Y300D01*
X722500Y1200D01*
X724636D01*
Y1252D01*
X727834D01*
Y1200D01*
X730836D01*
Y1252D01*
X736945D01*
X737753Y444D01*
Y-3293D01*
X737023Y-4023D01*
Y-9377D01*
X736200Y-10200D01*
X728430D01*
G37*
G36*
G01X934720Y-5436D02*
G03X934673Y-3318I-1088J1035D01*
G02X934657Y-2757I277J289D01*
G03X934907Y-2385I-1024J958D01*
G01X934922Y-2352D01*
X935160Y-2114D01*
Y-100D01*
X942596D01*
Y-1229D01*
X942583Y-1262D01*
G03X945211I1314J-489D01*
G01X945198Y-1229D01*
Y-100D01*
X949288D01*
Y-1229D01*
X949276Y-1262D01*
G03X951904I1314J-489D01*
G01X951892Y-1229D01*
Y-100D01*
X955982D01*
Y-1321D01*
X955969Y-1354D01*
G03X958597I1314J-489D01*
G01X958584Y-1321D01*
Y-100D01*
X962174D01*
Y-1843D01*
G03X965778I1802J0D01*
G01Y-100D01*
X968868D01*
Y-1743D01*
G03X972470I1801J0D01*
G01Y-100D01*
X975922D01*
G02X976225Y-761I0J-400D01*
G03X978266Y-2943I1136J-983D01*
G02X978906Y-3262I240J-319D01*
G01Y-4536D01*
G03X982510I1802J0D01*
G01Y-3261D01*
G02X983150Y-2942I400J0D01*
G03X985192Y-761I906J1198D01*
G02X985495Y-100I303J261D01*
G01X988946D01*
Y-1743D01*
G03X992550I1802J0D01*
G01Y-100D01*
X996001D01*
G02X996304Y-761I0J-400D01*
G03X998345Y-2943I1136J-983D01*
G02X998986Y-3262I241J-319D01*
G01Y-4536D01*
G03X1002588I1801J0D01*
G01Y-3261D01*
G02X1003229Y-2942I400J0D01*
G03X1005277Y-2715I904J1200D01*
G02X1005927Y-2771I305J-259D01*
G03X1008999Y-2826I1553J913D01*
G02X1009650Y-2792I338J-215D01*
G03X1012148Y-2572I1176J934D01*
G02X1012851I352J-190D01*
G03X1015349Y-2792I1322J714D01*
G02X1016000Y-2826I313J-249D01*
G03X1019320Y-1858I1519J968D01*
G01Y-100D01*
X1019500D01*
Y7718D01*
X1021276Y9494D01*
X1025241D01*
X1026324Y10576D01*
X1026898D01*
Y10076D01*
X1027898D01*
Y8122D01*
X1027338Y7562D01*
G03X1029125Y5185I1061J-1062D01*
G02X1029718Y4835I193J-350D01*
G01Y-2672D01*
X1025386Y-7005D01*
Y-9237D01*
X1025606Y-9457D01*
Y-11637D01*
X1025595Y-11648D01*
Y-21305D01*
X1025160Y-21740D01*
X715648D01*
X714350Y-20442D01*
Y-19746D01*
X714465Y-19692D01*
G03Y-16974I-641J1359D01*
G01X714350Y-16920D01*
Y-13786D01*
X715370Y-12766D01*
X715728D01*
Y-13617D01*
G03X716778Y-15848I1130J-831D01*
G02X717155Y-16225I-22J-399D01*
G03X718836Y-14773I1400J78D01*
G02X718634Y-14099I81J391D01*
G01X719232Y-13501D01*
Y-13382D01*
X720732D01*
Y-12882D01*
X723232D01*
Y-7902D01*
X726988D01*
Y-10175D01*
X727470Y-10656D01*
Y-10760D01*
X728110Y-11400D01*
X741160D01*
X742160Y-12400D01*
X752084D01*
X752485Y-12802D01*
X765715D01*
X766116Y-12400D01*
X775500D01*
X777799Y-10101D01*
G02X778468Y-10283I282J-283D01*
G03X780303Y-8448I1453J382D01*
G02X780121Y-7779I101J387D01*
G01X780482Y-7418D01*
G02X781165Y-7700I283J-283D01*
G03X782044Y-6399I1402J0D01*
G01X781921Y-6449D01*
X781686Y-6214D01*
X782316Y-5584D01*
X782411Y-5594D01*
G03X784061Y-3944I156J1494D01*
G01X784051Y-3849D01*
X785252Y-2648D01*
X785394Y-2789D01*
Y-2790D01*
G03X785497Y-2883I990J993D01*
G02X785489Y-3198I-127J-154D01*
G03X785320Y-5458I899J-1204D01*
G02X785326Y-6015I-284J-282D01*
G03X785373Y-8133I1088J-1035D01*
G02X785389Y-8694I-277J-289D01*
G03X787439I1025J-956D01*
G02X787455Y-8133I293J272D01*
G03X787482Y-5993I-1041J1083D01*
G02X787476Y-5436I284J282D01*
G03X787429Y-3318I-1088J1035D01*
G02X787413Y-2757I277J289D01*
G03X787663Y-2385I-1024J958D01*
G01X787678Y-2352D01*
X787916Y-2114D01*
Y-100D01*
X795352D01*
Y-1229D01*
X795339Y-1262D01*
G03X797967I1314J-489D01*
G01X797954Y-1229D01*
Y-100D01*
X802044D01*
Y-1229D01*
X802032Y-1262D01*
G03X804660I1314J-489D01*
G01X804648Y-1229D01*
Y-100D01*
X808738D01*
Y-1279D01*
X808725Y-1312D01*
G03X811353I1314J-489D01*
G01X811340Y-1279D01*
Y-100D01*
X815430D01*
Y-1229D01*
X815418Y-1262D01*
G03X818046I1314J-489D01*
G01X818034Y-1229D01*
Y-100D01*
X822124D01*
Y-902D01*
G03X822174Y-2757I1075J-899D01*
G02X822158Y-3318I-293J-272D01*
G03X822131Y-5458I1041J-1083D01*
G02X822137Y-6015I-284J-282D01*
G03X822184Y-8133I1088J-1035D01*
G02X822200Y-8694I-277J-289D01*
G03X824250I1025J-956D01*
G02X824266Y-8133I293J272D01*
G03X824293Y-5993I-1041J1083D01*
G02X824287Y-5436I284J282D01*
G03X824240Y-3318I-1088J1035D01*
G02X824224Y-2757I277J289D01*
G03X824474Y-2385I-1024J958D01*
G01X824489Y-2352D01*
X824726Y-2114D01*
Y-100D01*
X832162D01*
Y-1229D01*
X832150Y-1262D01*
G03X834778I1314J-489D01*
G01X834766Y-1229D01*
Y-100D01*
X838856D01*
Y-1229D01*
X838843Y-1262D01*
G03X841471I1314J-489D01*
G01X841458Y-1229D01*
Y-100D01*
X845548D01*
Y-1279D01*
X845536Y-1312D01*
G03X848164I1314J-489D01*
G01X848152Y-1279D01*
Y-100D01*
X852242D01*
Y-1229D01*
X852229Y-1262D01*
G03X854857I1314J-489D01*
G01X854844Y-1229D01*
Y-100D01*
X858934D01*
Y-902D01*
G03X858985Y-2757I1076J-899D01*
G02X858969Y-3318I-293J-272D01*
G03X858942Y-5458I1041J-1083D01*
G02X858948Y-6015I-284J-282D01*
G03X858995Y-8133I1088J-1035D01*
G02X859011Y-8694I-277J-289D01*
G03X861061I1025J-956D01*
G02X861077Y-8133I293J272D01*
G03X861104Y-5993I-1041J1083D01*
G02X861098Y-5436I284J282D01*
G03X861051Y-3318I-1088J1035D01*
G02X861035Y-2757I277J289D01*
G03X861285Y-2385I-1024J958D01*
G01X861300Y-2352D01*
X861538Y-2114D01*
Y-100D01*
X868974D01*
Y-1229D01*
X868961Y-1262D01*
G03X871589I1314J-489D01*
G01X871576Y-1229D01*
Y-100D01*
X875666D01*
Y-1229D01*
X875654Y-1262D01*
G03X878282I1314J-489D01*
G01X878270Y-1229D01*
Y-100D01*
X882360D01*
Y-1279D01*
X882347Y-1312D01*
G03X884975I1314J-489D01*
G01X884962Y-1279D01*
Y-100D01*
X889052D01*
Y-1229D01*
X889040Y-1262D01*
G03X891668I1314J-489D01*
G01X891656Y-1229D01*
Y-100D01*
X895746D01*
Y-902D01*
G03X895796Y-2757I1075J-899D01*
G02X895780Y-3318I-293J-272D01*
G03X895753Y-5458I1041J-1083D01*
G02X895759Y-6015I-284J-282D01*
G03X895806Y-8133I1088J-1035D01*
G02X895822Y-8694I-277J-289D01*
G03X897872I1025J-956D01*
G02X897888Y-8133I293J272D01*
G03X897915Y-5993I-1041J1083D01*
G02X897909Y-5436I284J282D01*
G03X897862Y-3318I-1088J1035D01*
G02X897846Y-2757I277J289D01*
G03X898096Y-2385I-1024J958D01*
G01X898111Y-2352D01*
X898348Y-2114D01*
Y-100D01*
X905784D01*
Y-1229D01*
X905772Y-1262D01*
G03X908400I1314J-489D01*
G01X908388Y-1229D01*
Y-100D01*
X912478D01*
Y-1229D01*
X912465Y-1262D01*
G03X915093I1314J-489D01*
G01X915080Y-1229D01*
Y-100D01*
X919170D01*
Y-1279D01*
X919158Y-1312D01*
G03X921786I1314J-489D01*
G01X921774Y-1279D01*
Y-100D01*
X925864D01*
Y-1229D01*
X925851Y-1262D01*
G03X928479I1314J-489D01*
G01X928466Y-1229D01*
Y-100D01*
X932556D01*
Y-902D01*
G03X932607Y-2757I1076J-899D01*
G02X932591Y-3318I-293J-272D01*
G03X932564Y-5458I1041J-1083D01*
G02X932570Y-6015I-284J-282D01*
G03X932617Y-8133I1088J-1035D01*
G02X932633Y-8694I-277J-289D01*
G03X934683I1025J-956D01*
G02X934699Y-8133I293J272D01*
G03X934726Y-5993I-1041J1083D01*
G02X934720Y-5436I284J282D01*
G37*
G36*
G01X714995Y52505D02*
X714500Y53000D01*
X709500D01*
X709000Y53500D01*
Y61500D01*
X708500Y62000D01*
X695000D01*
X694000Y63000D01*
Y70500D01*
X692500Y72000D01*
Y76500D01*
X692998Y76998D01*
X695002D01*
Y77000D01*
X716500D01*
X717900Y75600D01*
Y72900D01*
X719900Y70900D01*
X724000D01*
X727500Y67400D01*
Y61500D01*
X724500Y58500D01*
X724002D01*
Y58502D01*
X718998D01*
Y58498D01*
X717803Y57302D01*
Y52947D01*
X717361Y52505D01*
X714995D01*
G37*
G36*
G01X709374Y35570D02*
Y48985D01*
X711224Y50835D01*
X717855D01*
X718916Y51896D01*
Y54916D01*
X719498Y55498D01*
X724002D01*
Y55500D01*
X736000D01*
X737500Y54000D01*
Y48500D01*
X735510Y46510D01*
X724176D01*
X723119Y45453D01*
Y40463D01*
X723168Y40414D01*
X724619D01*
X725094Y39940D01*
Y35240D01*
X709999D01*
G02X709374Y35570I-225J330D01*
G37*
G36*
G01X685700Y195277D02*
X679488Y201488D01*
X671112D01*
X667000Y205600D01*
Y248309D01*
G02X667442Y248706I400J-1D01*
G03X669036Y249759I158J1494D01*
G01X669079Y249900D01*
X685800D01*
X687700Y248000D01*
X716900D01*
X722494Y242406D01*
Y241560D01*
G03X728662Y240213I3231J0D01*
G01X733097D01*
X737007Y244123D01*
X746763D01*
X747559Y243327D01*
Y238550D01*
X746596Y237587D01*
X736862D01*
X735300Y236025D01*
Y235000D01*
X734702Y234402D01*
X720398D01*
X719700Y235100D01*
Y237000D01*
X718152Y238548D01*
Y239242D01*
X717458D01*
X715700Y241000D01*
X698740D01*
X698342Y240602D01*
X698215D01*
X696908Y239295D01*
Y239168D01*
X696500Y238760D01*
Y225500D01*
X698000Y224000D01*
Y219002D01*
X697998D01*
Y213998D01*
X698000D01*
Y212002D01*
X697998D01*
Y206998D01*
X698000D01*
Y205502D01*
X697998D01*
Y200498D01*
X698000D01*
Y200000D01*
X697500Y199500D01*
X695925D01*
X691702Y195277D01*
X685700D01*
G37*
G36*
G01X749468Y235348D02*
Y227761D01*
X750599Y226631D01*
Y225233D01*
X751612Y224220D01*
Y220199D01*
X747641Y216228D01*
Y211672D01*
X746470Y210502D01*
X741498D01*
X741002Y210998D01*
Y211415D01*
X741000Y211416D01*
Y212000D01*
X740000Y213000D01*
X739416D01*
X739415Y213002D01*
X733085D01*
X733084Y213000D01*
X733000D01*
X721900Y201900D01*
X715500D01*
X712800Y199200D01*
X710516D01*
X710461Y199313D01*
G03X707939I-1261J-613D01*
G01X707884Y199200D01*
X702600D01*
X701002Y200798D01*
Y205502D01*
X701000D01*
Y206998D01*
X701002D01*
Y212002D01*
X701000D01*
Y213998D01*
X701002D01*
Y219002D01*
X701000D01*
Y219600D01*
X702957Y221557D01*
G02X703298Y221416I141J-141D01*
G01Y221298D01*
X705028D01*
X705048Y221294D01*
G03X705314Y221256I451J2206D01*
G02X705446Y220923I-17J-199D01*
G03X705411Y218950I1115J-1007D01*
G02X705398Y218421I-306J-257D01*
G03X705368Y216413I1102J-1021D01*
G02Y215887I-302J-263D01*
G03X707632I1132J-987D01*
G02Y216413I302J263D01*
G03X707650Y218367I-1132J988D01*
G02X707663Y218896I306J257D01*
G03X707922Y219282I-1103J1020D01*
G02X708407Y219494I363J-169D01*
G03X710746Y219928I768J2381D01*
G02X711326Y219843I251J-312D01*
G03X712761Y218728I2473J1702D01*
G03X712725Y218306I2966J-466D01*
G03X713781Y212870I1666J-2497D01*
G03X716470Y213643I1319J475D01*
G03X717393Y215770I-2079J2166D01*
G03X716766Y221083I-1666J2497D01*
G03X715862Y223726I-2966J462D01*
G03X712961Y226218I-2162J418D01*
G03X709040Y227123I-2461J-1718D01*
G02X708781Y227179I-98J175D01*
G03X707247Y227689I-1128J-832D01*
G03X703876Y229547I-2798J-1089D01*
G02X703402Y229898I-76J393D01*
G01X702750Y230550D01*
X700150D01*
X697910Y232790D01*
Y238880D01*
X698630Y239600D01*
X715400D01*
X718000Y237000D01*
Y234100D01*
X718700Y233400D01*
X735159D01*
X736522Y234763D01*
Y234769D01*
X737703Y235950D01*
X748867D01*
X749468Y235348D01*
G37*
G36*
G01X726015Y187937D02*
G02X726619Y187933I300J-264D01*
G03X729227Y188854I1157J878D01*
G03X726708Y189795I-1451J-43D01*
G02X726093Y189827I-294J271D01*
G03X723530Y188288I-1205J-897D01*
G02X723091Y187725I-361J-171D01*
G01X694038Y193462D01*
X693672Y193828D01*
Y194328D01*
X696743Y197400D01*
X708674D01*
X708708Y197387D01*
G03X709692I492J1313D01*
G01X709726Y197400D01*
X715765D01*
G03X717349I792J1157D01*
G01X720300D01*
X722200Y199300D01*
Y199500D01*
X727300Y204600D01*
X736000D01*
X737700Y202900D01*
Y198800D01*
X746914Y189586D01*
X767882D01*
X768945Y188523D01*
Y179500D01*
X768445Y179000D01*
X767950D01*
X757243Y187156D01*
X728173Y186720D01*
X727493Y186855D01*
X727491D01*
G03X727438Y186866I-566J-2595D01*
G01X726092Y187132D01*
G02X725900Y187820I77J392D01*
G03X726015Y187937I-1012J1110D01*
G37*
G36*
G01X698816Y310402D02*
X698203Y311014D01*
X693702D01*
Y315162D01*
X694309Y315769D01*
X697513D01*
X698996Y317252D01*
Y324465D01*
G03Y326535I-1475J1035D01*
G01Y328096D01*
X701800Y330900D01*
X710300D01*
X714200Y327000D01*
Y322200D01*
X711550Y319550D01*
X708350D01*
X708200Y319400D01*
X707283D01*
G03X705371Y319450I-983J-1000D01*
G01X705314Y319400D01*
X705200D01*
X704100Y318300D01*
Y317455D01*
X703956Y317413D01*
G03Y314337I448J-1538D01*
G01X704100Y314295D01*
Y312302D01*
X703961Y312258D01*
G03X702960Y311023I443J-1383D01*
G01X702952Y310952D01*
X702000Y310000D01*
X701502D01*
Y310502D01*
X699454D01*
G02X698816Y310402I-355J183D01*
G37*
G36*
G01X715400Y354000D02*
Y341300D01*
X700700D01*
Y354000D01*
X715400D01*
G37*
G36*
G01X698800Y395750D02*
X698947Y395897D01*
X707023Y397882D01*
X712702D01*
X713300Y397284D01*
Y372000D01*
X711200Y369900D01*
X700800D01*
X700260Y370440D01*
Y375386D01*
X698800Y376846D01*
Y395750D01*
G37*
G36*
G01X706000Y519500D02*
X704000Y521500D01*
Y529750D01*
X703500Y530250D01*
X700300D01*
X700000Y530550D01*
Y535800D01*
X700450Y536250D01*
X717450D01*
X718500Y537300D01*
Y538100D01*
X719400Y539000D01*
X736700D01*
X737500Y538200D01*
Y533802D01*
X731085D01*
X730485Y533202D01*
X726585D01*
X726084Y532700D01*
X724300D01*
X723900Y532300D01*
Y532002D01*
X723898D01*
Y527198D01*
X723900D01*
Y520123D01*
X723277Y519500D01*
X706000D01*
G37*
G36*
G01X710900Y537800D02*
X709250Y539450D01*
Y546500D01*
X707500Y548250D01*
X698300D01*
X689900Y556650D01*
Y567400D01*
X690500Y568000D01*
X700829D01*
G03X703371I1271J800D01*
G01X715750D01*
X727500Y556250D01*
Y550700D01*
X725600Y548800D01*
Y542600D01*
X725100Y542100D01*
X724402D01*
Y542102D01*
X719398D01*
Y542100D01*
X719000D01*
X717400Y540500D01*
Y538200D01*
X717002Y537802D01*
X715398D01*
Y537800D01*
X710900D01*
G37*
G36*
G01X668803Y572203D02*
X668397Y572610D01*
Y576110D01*
X668820D01*
Y579232D01*
X674897D01*
X675397Y578732D01*
Y572997D01*
X674603Y572203D01*
X668803D01*
G37*
G36*
G01X705650Y586050D02*
X705100Y586600D01*
Y591000D01*
X705300Y591200D01*
X709300D01*
X710600Y589900D01*
X714600D01*
X715000Y590300D01*
X715702D01*
Y590250D01*
X718610D01*
X719060Y589800D01*
Y586172D01*
X718938Y586050D01*
X705650D01*
G37*
G36*
G01X718603Y592314D02*
X710686D01*
X709100Y593900D01*
X707300D01*
X706600Y594600D01*
Y599942D01*
X707708Y601050D01*
X712882D01*
X718603Y595329D01*
Y592314D01*
G37*
G36*
G01X1020200Y576400D02*
X1019634Y576966D01*
Y582318D01*
X1021885Y584569D01*
Y585149D01*
X1022792Y586055D01*
Y586610D01*
X1028860D01*
X1028898Y586648D01*
X1029572D01*
Y592652D01*
X1028748D01*
X1026290Y595110D01*
X1020819D01*
X1020787Y595121D01*
G03X1020121Y595191I-486J-1421D01*
G01X1020024Y595180D01*
X1019634Y595570D01*
Y603666D01*
X1019320Y603980D01*
Y604614D01*
G03X1016000Y605582I-1801J0D01*
G02X1015349Y605548I-338J215D01*
G03X1012763Y605131I-1176J-934D01*
G01X1012715Y605000D01*
X1012284D01*
X1012236Y605131D01*
G03X1009650Y605548I-1410J-517D01*
G02X1008999Y605582I-313J249D01*
G03X1005757Y605141I-1519J-968D01*
G01X1005714Y605000D01*
X1002209D01*
X1002156Y605118D01*
G03X999883Y605699I-1369J-619D01*
G02X999242Y606018I-241J319D01*
G01Y607292D01*
G03X995640I-1801J0D01*
G01Y606132D01*
G02X994999Y605813I-400J0D01*
G03X994255Y606107I-904J-1199D01*
G01X994185Y606115D01*
X987255Y613045D01*
X987250D01*
X986325Y613970D01*
X933926D01*
X933906Y613974D01*
G03X933358I-274J-1375D01*
G01X933338Y613970D01*
X907557D01*
X907526Y613980D01*
G03X906646I-440J-1331D01*
G01X906615Y613970D01*
X897115D01*
X897095Y613974D01*
G03X896547I-274J-1375D01*
G01X896527Y613970D01*
X890825D01*
X890794Y613980D01*
G03X889914I-440J-1331D01*
G01X889883Y613970D01*
X883955D01*
X883935Y613974D01*
G03X883387I-274J-1375D01*
G01X883367Y613970D01*
X877439D01*
X877408Y613980D01*
G03X876528I-440J-1331D01*
G01X876497Y613970D01*
X870746D01*
X870715Y613980D01*
G03X869835I-440J-1331D01*
G01X869804Y613970D01*
X860304D01*
X860284Y613974D01*
G03X859736I-274J-1375D01*
G01X859716Y613970D01*
X854014D01*
X853983Y613980D01*
G03X853103I-440J-1331D01*
G01X853072Y613970D01*
X847144D01*
X847124Y613974D01*
G03X846576I-274J-1375D01*
G01X846556Y613970D01*
X840628D01*
X840597Y613980D01*
G03X839717I-440J-1331D01*
G01X839686Y613970D01*
X833935D01*
X833904Y613980D01*
G03X833024I-440J-1331D01*
G01X832993Y613970D01*
X823493D01*
X823473Y613974D01*
G03X822925I-274J-1375D01*
G01X822905Y613970D01*
X817053D01*
X817022Y613980D01*
G03X816142I-440J-1331D01*
G01X816111Y613970D01*
X810333D01*
X810313Y613974D01*
G03X809765I-274J-1375D01*
G01X809745Y613970D01*
X803817D01*
X803786Y613980D01*
G03X802906I-440J-1331D01*
G01X802875Y613970D01*
X797124D01*
X797093Y613980D01*
G03X796213I-440J-1331D01*
G01X796182Y613970D01*
X786682D01*
X786662Y613974D01*
G03X786114I-274J-1375D01*
G01X786094Y613970D01*
X780392D01*
X780361Y613980D01*
G03X779481I-440J-1331D01*
G01X779450Y613970D01*
X774980D01*
X774150Y614800D01*
X771213D01*
G03X767787I-1713J-2217D01*
G01X766089D01*
G03X766000Y614802I-107J-2800D01*
G01X759000D01*
G03X758911Y614800I18J-2802D01*
G01X756823D01*
X756062Y615562D01*
G03X753565Y614941I-1062J-1062D01*
G01X753521Y614800D01*
X741799D01*
X735299Y608300D01*
X726674D01*
X721124Y602750D01*
Y599733D01*
G03X720921Y598725I1282J-783D01*
G01X720936Y598625D01*
X719930Y597619D01*
X717868D01*
X714064Y601424D01*
X713265Y602223D01*
X712677D01*
X710100Y604800D01*
Y614715D01*
G02X710716Y615052I400J0D01*
G03X712949Y616180I784J1222D01*
G02X713381Y616553I399J-26D01*
G03X712051Y618094I119J1447D01*
G02X711619Y617721I-399J26D01*
G03X710716Y617496I-119J-1447D01*
G02X710100Y617833I-216J337D01*
G01Y618100D01*
X716100Y624100D01*
X723900D01*
X726500Y621500D01*
X730500D01*
X731548Y622548D01*
X998352D01*
X1000461Y620439D01*
G03X1000925Y619975I1485J1021D01*
G01X1002100Y618800D01*
X1006400D01*
X1007200Y619600D01*
Y623400D01*
X1007900Y624100D01*
X1033000D01*
X1033900Y623200D01*
Y617385D01*
X1031148Y614633D01*
Y579717D01*
G02X1030466Y579434I-400J0D01*
G01X1030200Y579700D01*
X1027884D01*
X1027883Y579702D01*
X1025407D01*
X1024320Y578615D01*
Y578520D01*
X1024270Y578470D01*
Y577970D01*
X1022700Y576400D01*
X1020200D01*
G37*
G36*
G01X727066Y32248D02*
X726095Y33219D01*
Y40454D01*
X726132D01*
Y45500D01*
X738000D01*
X739000Y44500D01*
Y35500D01*
X738000Y34500D01*
Y33049D01*
X737199Y32248D01*
X727066D01*
G37*
G36*
G01X755710Y-11800D02*
Y-10902D01*
X758210D01*
Y-5898D01*
X757522D01*
G02X757223Y-5233I0J400D01*
G03X755230Y-3266I-1047J932D01*
G02X754674Y-3250I-270J295D01*
G03X752538Y-3238I-1074J-1050D01*
G01X751706Y-4070D01*
Y-5398D01*
X750900D01*
Y-1352D01*
G02X751430Y-974I400J0D01*
G03X752922Y-632I470J1374D01*
G02X753505Y-653I282J-284D01*
G03X753578Y1332I1095J954D01*
G02X752995Y1353I-282J284D01*
G03X751430Y1774I-1095J-953D01*
G02X750900Y2152I-130J378D01*
G01Y20244D01*
X755536D01*
X756997Y21705D01*
X757052Y21718D01*
G03X755552Y24001I-338J1412D01*
G02X754896Y24025I-320J240D01*
G03X752343Y23818I-1221J-786D01*
G01X752291Y23698D01*
X750900D01*
Y28976D01*
X755710D01*
Y29476D01*
X758210D01*
Y34480D01*
X757326D01*
G02X757054Y35173I0J400D01*
G03X754701Y36288I-954J1027D01*
G01X754696Y36212D01*
X753463Y34980D01*
X750900D01*
Y39122D01*
G02X751363Y39517I400J0D01*
G03Y42483I237J1483D01*
G02X750900Y42878I-63J395D01*
G01Y51200D01*
X750270Y51830D01*
X750259Y51893D01*
G03X745308Y56844I-5966J-1015D01*
G01X745245Y56855D01*
X738400Y63700D01*
Y66394D01*
G02X739140Y66603I400J-1D01*
G03X749934Y67585I5153J3175D01*
G02X750706Y67440I372J-145D01*
G01Y66776D01*
X755710D01*
Y67276D01*
X758210D01*
Y72280D01*
X755710D01*
Y72780D01*
X754569D01*
X752998Y74351D01*
X752983Y74384D01*
G03X750706Y72819I-1275J-584D01*
G01Y72116D01*
G02X749934Y71971I-400J0D01*
G03X738337Y70851I-5641J-2193D01*
G02X737660Y70640I-394J71D01*
G01X734585Y73715D01*
G02X734609Y74304I282J283D01*
G03X732563Y76350I-938J1108D01*
G02X731974Y76326I-306J258D01*
G01X728428Y79872D01*
Y87073D01*
G02X729097Y87369I400J0D01*
G03X731034Y87422I941J1039D01*
G02X731603I285J-282D01*
G03X733598Y87425I996J986D01*
G02X734185Y87407I285J-281D01*
G03X734242Y89312I1056J922D01*
G02X733655Y89330I-285J281D01*
G03X731603Y89394I-1056J-922D01*
G02X731034I-284J282D01*
G03X729097Y89447I-996J-986D01*
G02X728428Y89743I-269J296D01*
G01Y90103D01*
X729525Y91200D01*
X738200D01*
G02X738578Y90668I0J-400D01*
G03X749183Y92244I5715J-1990D01*
G01X749082Y92382D01*
X753900Y97200D01*
X760500D01*
X763650Y100350D01*
X766650D01*
X767500Y99500D01*
Y87774D01*
G02X767040Y87379I-400J0D01*
G03X765468Y86461I-216J-1436D01*
G02X764849Y86288I-374J143D01*
G03X765343Y84592I-919J-1188D01*
G02X765958Y84777I376J-136D01*
G03X766756Y84493I865J1166D01*
G03X767130Y83303I2744J208D01*
G01Y75321D01*
X766748Y74940D01*
Y69778D01*
G03X767500Y67888I2751J0D01*
G01Y48336D01*
G03X767130Y46957I2381J-1378D01*
G01Y37197D01*
X766748Y36816D01*
Y31978D01*
G03X767500Y30088I2751J0D01*
G01Y10536D01*
G03X767130Y9157I2381J-1378D01*
G01Y-603D01*
X766748Y-984D01*
Y-6000D01*
G03X767500Y-7890I2751J0D01*
G01Y-9600D01*
X765300Y-11800D01*
X755710D01*
G37*
G36*
G01X785100Y203700D02*
X782720Y206080D01*
Y210551D01*
X783870Y211701D01*
Y220798D01*
X784002D01*
Y225802D01*
X783870D01*
Y227532D01*
X783934D01*
Y232534D01*
X783870D01*
Y234032D01*
X783934D01*
Y239034D01*
X783866D01*
X782731Y240169D01*
Y242647D01*
X784100Y244016D01*
Y269500D01*
X784088Y269512D01*
Y269988D01*
X782708Y271368D01*
Y274714D01*
X784100Y276106D01*
Y302500D01*
X782697Y303903D01*
Y306590D01*
X783848Y307741D01*
Y317152D01*
X783934D01*
Y322154D01*
X783848D01*
Y323652D01*
X783934D01*
Y328654D01*
X783848D01*
Y329471D01*
X784302Y329925D01*
Y330152D01*
X784334D01*
Y335154D01*
X784302D01*
Y335346D01*
X783983Y335665D01*
X783966D01*
X783654Y335977D01*
X783139D01*
X782800Y336316D01*
Y340300D01*
X784100Y341600D01*
Y365800D01*
X784609Y366309D01*
X816791D01*
X818250Y364850D01*
Y208800D01*
X816750Y207300D01*
X812100D01*
X809772Y204972D01*
X809054D01*
X808991Y204909D01*
X808863Y204971D01*
G03X806597Y203859I-698J-1442D01*
G01X806564Y203700D01*
X804559D01*
G03X801709I-1425J-731D01*
G01X785100D01*
G37*
G36*
G01X758202Y207648D02*
Y205795D01*
X764400Y199598D01*
Y190951D01*
X764058Y190609D01*
X748791D01*
X739500Y199900D01*
Y203000D01*
X737000Y205500D01*
X736516D01*
X736415Y205602D01*
X733398D01*
X733000Y206000D01*
Y211500D01*
X733500Y212000D01*
X739000D01*
X740000Y211000D01*
Y210000D01*
X740500Y209500D01*
X747762D01*
X749246Y210984D01*
Y216120D01*
X749499Y216373D01*
X754248D01*
X755117Y215504D01*
Y210733D01*
X758202Y207648D01*
G37*
G36*
G01X777579Y220893D02*
G02X777179Y221266I-1J400D01*
G03X776731Y222383I-1947J-133D01*
G03X773733I-1499J1250D01*
G03X773536Y222100I1497J-1252D01*
G01X769959D01*
G03X768768Y222496I-1360J-2100D01*
G02X768582Y222686I14J199D01*
G03X768136Y223833I-1950J-98D01*
G03X765228Y223945I-1404J1356D01*
G03X764913Y223515I1403J-1358D01*
G02X764278Y223422I-352J189D01*
G01X762600Y225100D01*
Y229400D01*
X761404Y230596D01*
X761501Y230733D01*
G03X761233Y233580I-1801J1267D01*
G02X761302Y234208I279J287D01*
G03X758856Y234594I-998J1619D01*
G02X758728Y233976I-305J-259D01*
G03X758433Y233801I973J-1976D01*
G01X758296Y233704D01*
X757876Y234124D01*
Y239940D01*
X755960Y241856D01*
Y246634D01*
X753900Y248694D01*
Y250905D01*
G02X754295Y251305I400J0D01*
G03Y257109I-32J2902D01*
G02X753900Y257509I5J400D01*
G01Y269481D01*
G02X754347Y269878I400J0D01*
G03X757595Y275409I411J3478D01*
G03X754366Y279202I-2749J931D01*
G02X753900Y279597I-66J394D01*
G01Y306200D01*
X744989Y315111D01*
X744998Y315205D01*
G03X741179Y319024I-3486J333D01*
G01X741085Y319015D01*
X738300Y321800D01*
Y385365D01*
X741750Y388815D01*
Y397182D01*
X742845Y398277D01*
X763076D01*
X763088Y398275D01*
G03X763578I245J1937D01*
G01X763590Y398277D01*
X766597D01*
X767420Y399100D01*
X779910D01*
X780400Y398610D01*
Y376190D01*
X778480D01*
Y375690D01*
X777984D01*
Y376190D01*
X776121D01*
G02X775732Y376499I1J400D01*
G03X775721Y376533I-195J-44D01*
G02X775832Y376798I184J79D01*
G03X776469Y377204I-711J1818D01*
G02X776737Y377212I138J-144D01*
G03X777610Y380613I1263J1488D01*
G02X777131Y381026I-80J392D01*
G03X776681Y382383I-1949J107D01*
G03X773683I-1499J1250D01*
G03X773359Y381830I1499J-1250D01*
G01X773310Y381702D01*
X770598D01*
Y381202D01*
X770102D01*
Y381702D01*
X768911D01*
G02X768525Y382207I0J400D01*
G03X768286Y383778I-1882J517D01*
G03X765474Y384288I-1131J1772D01*
G03X764705Y382491I1169J-1563D01*
G02X764548Y382272I-199J-23D01*
G03X763444Y379130I409J-1909D01*
G02X763303Y378515I-310J-253D01*
G03X762653Y375472I828J-1768D01*
G02X762646Y375202I-151J-131D01*
G03X765645Y375230I1513J-1459D01*
G02X765632Y375499I141J142D01*
G03X765644Y377980I-1501J1248D01*
G02X765785Y378595I310J253D01*
G03X766503Y379171I-828J1768D01*
G01X766563Y379248D01*
X767098D01*
Y378698D01*
X769220D01*
G02X769620Y378298I0J-400D01*
G03X769656Y378132I400J0D01*
G02X769818Y376518I-2274J-1043D01*
G03X769902Y376169I390J-91D01*
G02X769904Y375653I-305J-259D01*
G03X770600Y372619I1496J-1254D01*
G03X772142Y370047I1843J-643D01*
G02X772309Y369822I-31J-198D01*
G03X776689Y369628I2181J-303D01*
G02X777091Y370048I400J20D01*
G03X777856Y370200I10J1952D01*
G02X778410Y369831I154J-369D01*
G01Y368633D01*
G03X779312Y367732I901J0D01*
G01X780900D01*
Y344190D01*
X778530D01*
Y343690D01*
X778034D01*
Y344190D01*
X776171D01*
G02X775782Y344499I1J400D01*
G03X775771Y344533I-195J-44D01*
G02X775882Y344798I184J79D01*
G03X776375Y345080I-712J1817D01*
G03X777581Y348552I1225J1520D01*
G02X777178Y348983I-4J400D01*
G03X776731Y350383I-1946J150D01*
G03X773733I-1499J1250D01*
G03X773409Y349830I1499J-1250D01*
G01X773360Y349702D01*
X770898D01*
Y349202D01*
X770402D01*
Y349702D01*
X769749D01*
G02X769363Y350205I0J400D01*
G03X768503Y352368I-1886J503D01*
G03X765706Y351529I-1771J821D01*
G03X765525Y350711I1771J-821D01*
G02X765105Y350313I-400J1D01*
G03X763933Y346733I-98J-1950D01*
G02X763951Y346078I-220J-334D01*
G03X763638Y343237I1165J-1566D01*
G02X763631Y342967I-151J-131D01*
G03X763046Y341638I1513J-1459D01*
G02X762838Y341450I-200J12D01*
G03X764695Y339246I-78J-1950D01*
G02X764915Y339418I198J-27D01*
G03X766630Y342995I229J2090D01*
G02X766617Y343264I141J142D01*
G03X766190Y346142I-1501J1248D01*
G02X766172Y346797I220J334D01*
G03X766610Y347248I-1163J1568D01*
G01X767398D01*
Y346698D01*
X769270D01*
G02X769670Y346298I0J-400D01*
G03X769706Y346132I400J0D01*
G02X769787Y344243I-2274J-1044D01*
G02X769906Y344095I-1889J-1641D01*
G03X769962Y344034I321J239D01*
G02X770038Y343525I-265J-300D01*
G03X771951Y340565I1662J-1024D01*
G02X772401Y340137I51J-397D01*
G03X772855Y338724I1946J-154D01*
G02X772843Y338195I-306J-258D01*
G03X776340Y337846I1617J-1495D01*
G01X776647Y338152D01*
X776755Y338128D01*
G03X778557Y338647I427J1905D01*
G03X779033Y338301I1373J1388D01*
G03X779020Y338153I889J-153D01*
G01Y336553D01*
G03X779922Y335652I901J0D01*
G01X780900D01*
Y312190D01*
X778530D01*
Y311690D01*
X778034D01*
Y312190D01*
X776171D01*
G02X775782Y312499I1J400D01*
G03X775771Y312533I-195J-44D01*
G02X775882Y312798I184J79D01*
G03X776532Y313216I-710J1819D01*
G03X777619Y316644I1268J1484D01*
G02X777183Y317057I-37J398D01*
G03X776731Y318383I-1951J75D01*
G03X773733I-1499J1250D01*
G03X773327Y317558I1499J-1250D01*
G01X773292Y317402D01*
X770398D01*
Y316902D01*
X769902D01*
Y317402D01*
X769246D01*
G02X768864Y317920I0J400D01*
G03X768268Y319984I-1864J580D01*
G03X765464Y319705I-1536J1205D01*
G03X765048Y318508I1536J-1205D01*
G02X764863Y318310I-200J1D01*
G03X763933Y314733I144J-1947D01*
G02X763951Y314078I-220J-334D01*
G03X763638Y311237I1165J-1566D01*
G02X763631Y310967I-151J-131D01*
G03X766630Y310995I1513J-1459D01*
G02X766617Y311264I141J142D01*
G03X766190Y314142I-1501J1248D01*
G02X766172Y314797I220J334D01*
G03X766298Y314899I-1164J1567D01*
G01X766354Y314948D01*
X766898D01*
Y314398D01*
X769695D01*
Y314198D01*
G03X769713Y314116I200J1D01*
G02X769461Y311625I-2281J-1027D01*
G02X769512Y311518I-2232J-1130D01*
G03X769618Y311415I183J82D01*
G02X769734Y311172I-75J-185D01*
G03X770040Y309427I1866J-572D01*
G03X771049Y305979I1238J-1509D01*
G02X771398Y305528I-47J-397D01*
G03X775744Y304825I2182J-297D01*
G02X776160Y305151I393J-73D01*
G03X777941Y306091I110J1949D01*
G02X778204Y306166I172J-103D01*
G03X778700Y305990I895J1735D01*
G01X778758Y305977D01*
X779190Y305545D01*
Y304763D01*
G03X780092Y303862I901J0D01*
G01X780900D01*
Y280190D01*
X778530D01*
Y279690D01*
X778034D01*
Y280190D01*
X776996D01*
Y280467D01*
X777047Y280524D01*
G03X777080Y280575I-149J133D01*
G02X777303Y280689I183J-82D01*
G03X777598Y284549I398J1911D01*
G02X777178Y284980I-21J400D01*
G03X776731Y286383I-1946J153D01*
G03X773733I-1499J1250D01*
G03X773377Y285739I1500J-1249D01*
G01X773332Y285602D01*
X770398D01*
Y285102D01*
X769902D01*
Y285602D01*
X769602D01*
G02X769212Y286091I0J400D01*
G03X767026Y288461I-1902J439D01*
G03X763633Y286366I-2046J-481D01*
G02X763654Y285770I-256J-307D01*
G03X763933Y282733I1353J-1407D01*
G02X763951Y282078I-220J-334D01*
G03X763638Y279237I1165J-1566D01*
G02X763631Y278967I-151J-131D01*
G03X766533Y275930I1513J-1459D01*
G02X767175Y275761I264J-300D01*
G03X769422Y274490I1844J639D01*
G02X769658Y274341I41J-196D01*
G03X773978Y274528I2142J510D01*
G01X774004Y274698D01*
X774920D01*
G03X777846Y273920I1780J802D01*
G02X778480Y273596I234J-324D01*
G01Y272733D01*
G03X779382Y271832I901J0D01*
G01X780900D01*
Y248190D01*
X778530D01*
Y247690D01*
X778034D01*
Y248190D01*
X776171D01*
G02X775782Y248499I1J400D01*
G03X775771Y248533I-195J-44D01*
G02X775882Y248798I184J79D01*
G03X776426Y249121I-711J1818D01*
G03X777598Y252549I1274J1479D01*
G02X777178Y252980I-21J400D01*
G03X776731Y254383I-1946J153D01*
G03X773733I-1499J1250D01*
G03X773349Y253649I1498J-1251D01*
G01X773309Y253502D01*
X770798D01*
Y253002D01*
X770302D01*
Y253502D01*
X768761D01*
G02X768382Y254029I0J400D01*
G03X768036Y255896I-1850J623D01*
G03X765128Y256008I-1404J1356D01*
G03X764617Y254276I1404J-1356D01*
G03X763933Y250733I390J-1913D01*
G02X763951Y250078I-220J-334D01*
G03X763638Y247237I1165J-1566D01*
G02X763631Y246967I-151J-131D01*
G03X766141Y243657I1513J-1459D01*
G02X766710Y243433I190J-352D01*
G03X769066Y242170I1850J622D01*
G02X769566Y241835I103J-386D01*
G03X773863Y242740I2184J286D01*
G01X773829Y242854D01*
X774052Y243076D01*
Y243906D01*
X774939Y244793D01*
G02X775280Y244652I141J-141D01*
G01Y244425D01*
X775259Y244383D01*
G03X777897Y241766I1741J-883D01*
G02X778480Y241411I183J-355D01*
G01Y240483D01*
G03X779382Y239582I901J0D01*
G01X780900D01*
Y220893D01*
X777579D01*
G37*
G36*
G01X762321Y399366D02*
X761800Y399887D01*
Y404700D01*
X762298Y405198D01*
X764202D01*
Y405200D01*
X765298D01*
Y405198D01*
X767302D01*
Y405200D01*
X768598D01*
Y405098D01*
X770602D01*
Y405200D01*
X772545D01*
X772549Y405196D01*
X772983D01*
X773333Y404846D01*
Y402100D01*
X772833Y401600D01*
X766464D01*
X764230Y399366D01*
X762321D01*
G37*
G36*
G01X817883Y369537D02*
X816735Y368389D01*
X783118D01*
X782697Y368810D01*
Y376675D01*
X782800Y376778D01*
Y376800D01*
X783950Y377950D01*
Y378000D01*
X784500Y378550D01*
Y399700D01*
X787600Y402800D01*
X802750D01*
X803546Y402004D01*
X807100D01*
X809554Y399550D01*
X816260D01*
X817883Y397927D01*
Y369537D01*
G37*
G36*
G01X732820Y519819D02*
Y513990D01*
X731904Y513074D01*
X731806Y513088D01*
G03X731088Y513012I-206J-1488D01*
G01X731055Y513000D01*
X729073D01*
G03X728927I-73J-1500D01*
G01X727000D01*
X726500Y513500D01*
Y513562D01*
X726113Y513949D01*
Y526804D01*
X726508Y527198D01*
X726902D01*
Y532102D01*
X727000Y532200D01*
X730900D01*
X731500Y532800D01*
X736900D01*
X738061Y531639D01*
Y525060D01*
X732820Y519819D01*
G37*
G36*
G01X763864Y503196D02*
X760925Y506135D01*
X753195D01*
X749026Y510304D01*
X749131Y510443D01*
G03X745655Y519976I-4838J3636D01*
G01X745500Y520012D01*
Y527022D01*
X745655Y527058D01*
G03Y538852I-1362J5897D01*
G01X745500Y538888D01*
Y545946D01*
X745655Y545982D01*
G03Y557776I-1362J5897D01*
G01X745500Y557812D01*
Y564822D01*
X745655Y564858D01*
G03Y576652I-1362J5897D01*
G01X745500Y576688D01*
Y583746D01*
X745655Y583782D01*
G03Y595576I-1362J5897D01*
G01X745500Y595612D01*
Y599800D01*
X747800Y602100D01*
X755717D01*
G03X758302Y604600I84J2500D01*
G01Y604702D01*
X759300Y605700D01*
X760752D01*
X763126Y603326D01*
G03X765482Y603160I1274J1274D01*
G01X765536Y603200D01*
X765800D01*
X766900Y602100D01*
X767000D01*
X767500Y601600D01*
Y592541D01*
X767006Y592046D01*
X766899Y592070D01*
G03X767089Y589386I-299J-1370D01*
G01X767122Y589398D01*
X767500D01*
Y588711D01*
G02X766841Y588406I-400J0D01*
G03X764476Y587018I-941J-1106D01*
G02X763947Y586564I-393J-78D01*
G03X764874Y585482I-497J-1364D01*
G02X765403Y585936I393J78D01*
G03X766218Y585883I498J1364D01*
G02X766704Y585519I87J-390D01*
G03X767080Y584289I2796J182D01*
G01Y580624D01*
G03X767500Y579148I2801J-1D01*
G01Y577344D01*
X765258Y575102D01*
X758500D01*
G03X757004Y574668I2J-2801D01*
G02X756393Y574961I-214J338D01*
G03X753686Y574311I-1393J-161D01*
G01X753698Y574278D01*
Y573802D01*
X753498D01*
Y570801D01*
G03X752498Y568800I1502J-2001D01*
G01Y566000D01*
G03X757502I2502J0D01*
G01Y566298D01*
X758500D01*
G03X759842Y566689I-1J2502D01*
G01X759977Y566775D01*
X762026Y564726D01*
G03X764806Y566989I1274J1273D01*
G01X764773Y567039D01*
Y567298D01*
X765161D01*
X765356Y567104D01*
X767500D01*
Y549790D01*
G03X767130Y546503I2000J-1889D01*
G01Y542824D01*
G03X767500Y541445I2751J-1D01*
G01Y539300D01*
X767100Y538900D01*
X764000D01*
X762402Y537302D01*
X759500D01*
G03X758004Y536868I2J-2801D01*
G02X757393Y537161I-214J338D01*
G03X754686Y536511I-1393J-161D01*
G01X754698Y536478D01*
Y536002D01*
X754498D01*
Y533001D01*
G03X753498Y531000I1502J-2001D01*
G01Y525950D01*
G03X758502I2502J0D01*
G01Y528498D01*
X759500D01*
G03X761245Y529207I0J2502D01*
G01X763126Y527326D01*
G03X766199Y528514I1274J1274D01*
G02X766882Y528778I400J-19D01*
G01X767500Y528159D01*
Y511990D01*
G03X767130Y508703I2000J-1889D01*
G01Y505024D01*
G03X767475Y503689I2751J-1D01*
G01X767500Y503644D01*
Y503196D01*
X763864D01*
G37*
G36*
G01X823300Y208000D02*
X821163Y210137D01*
Y363177D01*
X821252Y363266D01*
Y363933D01*
X821743Y364424D01*
X838176D01*
X841900Y360700D01*
X849200D01*
X851100Y358800D01*
Y358794D01*
X904504Y305390D01*
Y305341D01*
X921801D01*
X925884Y307836D01*
G02X926420Y307724I208J-342D01*
G03X928892Y309235I1187J836D01*
G02X929038Y309763I354J186D01*
G01X938168Y315341D01*
X940093D01*
G03X942161I1034J1019D01*
G01X946853D01*
G03X948921I1034J1019D01*
G01X953613D01*
G03X955681I1034J1019D01*
G01X960372D01*
G03X962440I1034J1019D01*
G01X963012D01*
G02X963395Y314826I0J-400D01*
G03X965821Y313391I1391J-417D01*
G01X965822D01*
X965964Y313533D01*
X966741Y312756D01*
X966728Y312658D01*
G03X968364Y311022I1438J-198D01*
G01X968462Y311035D01*
X968656Y310841D01*
X969695D01*
G02X970095Y310456I0J-400D01*
G03X972997I1451J53D01*
G02X973397Y310841I400J-15D01*
G01X976455D01*
G02X976855Y310456I0J-400D01*
G03X979757I1451J53D01*
G02X980157Y310841I400J-15D01*
G01X983215D01*
G02X983615Y310456I0J-400D01*
G03X986517I1451J53D01*
G02X986917Y310841I400J-15D01*
G01X988803D01*
X989154Y311192D01*
X989177Y311205D01*
G03X989701Y311729I-731J1255D01*
G01X989714Y311752D01*
X991104Y313142D01*
X991230Y313085D01*
G03X993271Y314269I596J1324D01*
G01X993289Y314450D01*
X996080D01*
X997071Y315441D01*
X1002503D01*
X1004369Y313575D01*
X1011125D01*
X1013184Y311516D01*
Y311087D01*
X1014404Y309866D01*
X1016201D01*
X1016750Y310414D01*
X1029829D01*
X1030868Y311454D01*
Y314710D01*
X1031500Y315341D01*
X1058073D01*
X1058274Y315140D01*
X1058014Y314880D01*
Y309421D01*
X1057072Y308479D01*
Y304481D01*
X1056932Y304341D01*
X1056410D01*
Y304412D01*
X1051408D01*
Y304341D01*
X1049210D01*
Y304412D01*
X1044208D01*
Y304341D01*
X1042010D01*
Y304412D01*
X1037008D01*
Y304341D01*
X1034810D01*
Y304412D01*
X1029808D01*
Y304341D01*
X1027610D01*
Y304412D01*
X1022608D01*
Y304341D01*
X1020410D01*
Y304412D01*
X1015408D01*
Y304341D01*
X1014756D01*
X1014400Y303985D01*
Y301928D01*
X1014270Y301799D01*
Y295547D01*
X1014400Y295418D01*
Y294200D01*
X1014600Y294000D01*
X1015818D01*
X1016095Y293722D01*
X1057752D01*
X1057814Y293660D01*
Y292830D01*
X1057698Y292715D01*
Y292276D01*
X1057155Y291732D01*
Y288014D01*
X1056552Y287412D01*
X1051408D01*
Y287341D01*
X1049210D01*
Y287412D01*
X1044208D01*
Y287341D01*
X1042010D01*
Y287412D01*
X1037008D01*
Y287341D01*
X1034810D01*
Y287412D01*
X1029808D01*
Y287341D01*
X1027610D01*
Y287412D01*
X1022608D01*
Y287341D01*
X1020410D01*
Y287412D01*
X1015408D01*
Y287341D01*
X1015109D01*
X1014384Y286616D01*
Y284824D01*
X1014138Y284578D01*
Y278383D01*
X1016683Y275838D01*
X1026662D01*
X1028043Y274457D01*
Y269457D01*
X1028064Y269436D01*
Y269169D01*
X1029176Y268058D01*
X1036441D01*
X1036515Y268132D01*
X1036653D01*
X1037538Y267247D01*
Y263562D01*
X1038800Y262300D01*
X1079565D01*
X1080791Y263526D01*
Y263738D01*
X1081091D01*
X1081151Y263658D01*
G03X1081481Y265909I1281J962D01*
G02X1080944Y265965I-238J322D01*
G03X1080791Y266113I-1083J-967D01*
G01Y270113D01*
X1081019Y270341D01*
X1086998D01*
Y268498D01*
X1087509D01*
G02X1087831Y267861I0J-400D01*
G03X1087969Y265977I1169J-861D01*
G02X1087991Y265437I-284J-282D01*
G03X1090276Y263648I1109J-937D01*
G02X1090924I324J-234D01*
G03X1093167Y265485I1175J853D01*
G02X1093210Y266068I294J271D01*
G03X1093241Y266095I-938J1108D01*
G02X1093900Y265810I259J-305D01*
G03X1096855Y267283I1800J90D01*
G02X1096806Y267850I256J308D01*
G03X1097035Y268220I-1106J940D01*
G01X1097087Y268341D01*
X1105256D01*
X1105756Y267841D01*
Y265841D01*
X1101256Y263841D01*
X1094756Y260341D01*
X1080779Y251870D01*
G02X1080224Y252014I-207J342D01*
G03X1077577Y250861I-1262J-718D01*
G02X1077195Y250341I-382J-120D01*
G01X1076640D01*
G03X1074524I-1058J-994D01*
G01X1073969D01*
G02X1073587Y250861I0J400D01*
G03X1070888Y250679I-1385J435D01*
G01X1070948Y250552D01*
X1070580Y250184D01*
G02X1069979Y250225I-283J283D01*
G03X1067944Y248190I-1157J-878D01*
G02X1067985Y247589I-242J-318D01*
G01X1067896Y247500D01*
X1066700D01*
X1066669Y247663D01*
G03X1063815I-1427J-267D01*
G01X1063784Y247500D01*
X1059154D01*
G02X1058757Y247945I0J400D01*
G03X1055871I-1443J164D01*
G02X1055474Y247500I-397J-45D01*
G01X1049844D01*
X1049810Y247514D01*
G03X1048758I-526J-1354D01*
G01X1048724Y247500D01*
X1047744D01*
G02X1047347Y247945I0J400D01*
G03X1044461I-1443J164D01*
G02X1044064Y247500I-397J-45D01*
G01X1043731D01*
X1043675Y247546D01*
G03X1041373I-1151J-1386D01*
G01X1041317Y247500D01*
X1040985D01*
G02X1040588Y247945I0J400D01*
G03X1037702I-1443J164D01*
G02X1037305Y247500I-397J-45D01*
G01X1036972D01*
X1036916Y247546D01*
G03X1034614I-1151J-1386D01*
G01X1034558Y247500D01*
X1034225D01*
G02X1033828Y247945I0J400D01*
G03X1030942I-1443J164D01*
G02X1030545Y247500I-397J-45D01*
G01X1030212D01*
X1030156Y247546D01*
G03X1028540Y247901I-1151J-1386D01*
G01X1028429Y247871D01*
X1024959Y251341D01*
X1022930D01*
X1022888Y251362D01*
G03X1021602I-643J-1302D01*
G01X1021560Y251341D01*
X1020697D01*
G02X1020302Y251799I1J400D01*
G03X1017428I-1437J210D01*
G02X1017033Y251341I-396J-58D01*
G01X1016755D01*
X1016698Y251393D01*
G03X1014272I-1213J-1333D01*
G01X1014215Y251341D01*
X1013852D01*
Y251565D01*
X1013857Y251588D01*
G03X1011139Y253530I-1752J421D01*
G02X1010525Y253885I-214J338D01*
G03X1007759Y255481I-1800J75D01*
G02X1007146Y255836I-213J338D01*
G03X1004379Y257430I-1801J73D01*
G02X1003765Y257785I-214J338D01*
G03X1000659Y259102I-1800J75D01*
G01X1000657Y259100D01*
X1000514Y258957D01*
X1000282Y259189D01*
X1000315Y259303D01*
G03X998080Y261538I-1729J506D01*
G01X997966Y261505D01*
X996693Y262778D01*
X996683Y262792D01*
G03X996238Y263237I-1477J-1032D01*
G01X996224Y263247D01*
X995751Y263720D01*
G02X995855Y264361I282J283D01*
G03X993907Y266309I-649J1299D01*
G02X993266Y266205I-358J178D01*
G01X992878Y266593D01*
X992983Y266732D01*
G03X990949Y268766I-1157J877D01*
G01X990810Y268661D01*
X990223Y269248D01*
X990235Y269344D01*
G03X989283Y271156I-1789J216D01*
G02Y271864I186J354D01*
G03Y275056I-837J1596D01*
G02Y275764I186J354D01*
G03X987480Y278881I-837J1596D01*
G02X986866Y279236I-214J338D01*
G03X983266I-1800J74D01*
G02X982652Y278881I-400J-17D01*
G03X980720I-966J-1521D01*
G02X980106Y279236I-214J338D01*
G03X976506I-1800J74D01*
G02X975892Y278881I-400J-17D01*
G03X973960I-966J-1521D01*
G02X973346Y279236I-214J338D01*
G03X972512Y277789I-1800J74D01*
G02X973126Y277434I214J-338D01*
G03X973570Y276173I1800J-75D01*
G02X973420Y275841I-150J-132D01*
G01X972939D01*
X972888Y275964D01*
G03X970204I-1342J-555D01*
G01X970153Y275841D01*
X969642D01*
G02X969323Y276483I0J400D01*
G03X967009I-1157J877D01*
G02X966690Y275841I-319J-242D01*
G01X966541D01*
X966496Y275978D01*
G03X963076I-1710J-569D01*
G01X963031Y275841D01*
X962882D01*
G02X962563Y276483I0J400D01*
G03X960249I-1157J877D01*
G02X959930Y275841I-319J-242D01*
G01X959419D01*
X959368Y275964D01*
G03X956684I-1342J-555D01*
G01X956633Y275841D01*
X956123D01*
G02X955804Y276483I0J400D01*
G03X953490I-1157J877D01*
G02X953171Y275841I-319J-242D01*
G01X952660D01*
X952609Y275964D01*
G03X949925I-1342J-555D01*
G01X949874Y275841D01*
X949363D01*
G02X949044Y276483I0J400D01*
G03X946730I-1157J877D01*
G02X946411Y275841I-319J-242D01*
G01X945900D01*
X945849Y275964D01*
G03X943165I-1342J-555D01*
G01X943114Y275841D01*
X942603D01*
G02X942284Y276483I0J400D01*
G03X939970I-1157J877D01*
G02X939651Y275841I-319J-242D01*
G01X939140D01*
X939089Y275964D01*
G03X936405I-1342J-555D01*
G01X936354Y275841D01*
X935843D01*
G02X935524Y276483I0J400D01*
G03X933210I-1157J877D01*
G02X932891Y275841I-319J-242D01*
G01X932380D01*
X932329Y275964D01*
G03X929633Y274886I-1342J-555D01*
G01X929679Y274764D01*
X929545Y274630D01*
G02X928961Y274649I-283J283D01*
G03X926035Y274341I-1354J-1189D01*
G01X925633D01*
G02X925462Y274646I-1J200D01*
G03X922873Y274885I-1235J763D01*
G02X922500Y274341I-373J-144D01*
G01X922001D01*
G03X919693I-1154J-881D01*
G01X914941D01*
G03X912689Y274410I-1154J-881D01*
G01X912629Y274341D01*
X912441D01*
X896700Y258600D01*
Y239092D01*
X866089Y208482D01*
X827189D01*
X826708Y208000D01*
X823300D01*
G37*
G36*
G01X848600Y362400D02*
X847902Y361702D01*
X842315D01*
X841600Y362416D01*
Y367000D01*
X842730Y368130D01*
X842998D01*
Y368048D01*
X846002D01*
Y368130D01*
X846870D01*
X848600Y366400D01*
Y362400D01*
G37*
G36*
G01X905158Y306342D02*
X849900Y361600D01*
Y366800D01*
X846700Y370000D01*
X846002D01*
Y370052D01*
X842998D01*
Y370000D01*
X842619D01*
X838299Y365680D01*
X821320D01*
X818920Y368080D01*
Y397450D01*
X823112Y401642D01*
X823245Y401565D01*
G03X824950Y401700I755J1298D01*
G01X826850D01*
G03X828750I950J1163D01*
G01X831350D01*
G03X833250I950J1163D01*
G01X834900D01*
X836875Y399725D01*
X841125D01*
X880500Y360350D01*
Y352100D01*
X880878Y351722D01*
Y349510D01*
X889519Y340870D01*
X891730D01*
X891761Y340839D01*
X896138D01*
X896598Y340378D01*
Y339498D01*
X899602D01*
Y339998D01*
X900602D01*
Y342002D01*
X900600D01*
Y342871D01*
X900828Y343099D01*
X902701D01*
X903768Y342032D01*
Y342015D01*
X909200Y336584D01*
Y335200D01*
X912290Y332110D01*
X912286Y332022D01*
G03X914789Y330841I1501J-62D01*
G01X915666D01*
G02X916055Y330348I0J-400D01*
G03X918879I1412J-339D01*
G02X919268Y330841I389J93D01*
G01X919432D01*
X919491Y330773D01*
G03X922203I1356J1187D01*
G01X922262Y330841D01*
X922426D01*
G02X922815Y330348I0J-400D01*
G03X925639I1412J-339D01*
G02X926028Y330841I389J93D01*
G01X926682D01*
G03X928481Y330801I925J1119D01*
G01X928535Y330841D01*
X928828D01*
G02X929220Y330363I0J-400D01*
G03X932754Y330364I1767J-354D01*
G02X933146Y330842I392J78D01*
G01X933437Y330843D01*
X933491Y330802D01*
G03X935245Y330803I876J1158D01*
G01X935298Y330844D01*
X935588D01*
G02X935981Y330365I1J-400D01*
G03X939513Y330367I1766J-356D01*
G02X939905Y330847I392J80D01*
G01X940192D01*
X940246Y330806D01*
G03X942009Y330807I881J1154D01*
G01X942063Y330848D01*
X942349D01*
G02X942741Y330368I0J-400D01*
G03X946272Y330371I1766J-359D01*
G02X946664Y330851I392J80D01*
G01X946947D01*
X947001Y330809D01*
G03X948774Y330810I886J1151D01*
G01X948828Y330852D01*
X949469Y330853D01*
G02X949857Y330357I0J-400D01*
G03X952676Y330358I1410J-348D01*
G02X953064Y330855I388J97D01*
G01X953702D01*
X953757Y330813D01*
G03X955539Y330814I890J1147D01*
G01X955593Y330856D01*
X956229Y330857D01*
G02X956617Y330360I0J-400D01*
G03X959435Y330362I1409J-351D01*
G02X959822Y330859I388J97D01*
G01X959977D01*
X960036Y330789D01*
G03X962777Y330791I1370J1171D01*
G01X962837Y330861D01*
X962990D01*
G02X963378Y330363I0J-400D01*
G03X966194Y330365I1408J-354D01*
G02X966581Y330863I388J98D01*
G01X966733D01*
X966793Y330793D01*
G03X969540Y330794I1373J1167D01*
G01X969600Y330865D01*
X969751D01*
G02X970139Y330367I0J-400D01*
G03X972953Y330368I1407J-358D01*
G02X973340Y330867I387J99D01*
G01X973490D01*
X973550Y330796D01*
G03X976303Y330798I1376J1164D01*
G01X976363Y330869D01*
X976512D01*
G02X976900Y330370I0J-400D01*
G03X979712Y330372I1406J-361D01*
G02X980099Y330871I387J99D01*
G01X980722Y330872D01*
X980777Y330828D01*
G03X982596Y330829I909J1132D01*
G01X982651Y330873D01*
X983457D01*
X983733Y330598D01*
X983692Y330480D01*
G03X986439Y330481I1374J-471D01*
G01X986399Y330599D01*
X986675Y330875D01*
X987477Y330876D01*
X987533Y330831D01*
G03X989361Y330832I913J1129D01*
G01X989416Y330877D01*
X990034D01*
G02X990421Y330376I0J-400D01*
G03X993230Y330378I1405J-367D01*
G02X993617Y330880I387J102D01*
G01X994233D01*
X994288Y330835D01*
G03X996125Y330836I918J1125D01*
G01X996181Y330881D01*
X996795Y330882D01*
G02X997182Y330380I0J-400D01*
G03X999989Y330381I1404J-371D01*
G02X1000376Y330884I387J103D01*
G01X1000672D01*
X1000826Y331038D01*
X1000968Y330905D01*
G03X1003407Y332132I997J1055D01*
G02X1003804Y332579I397J47D01*
G01X1004605D01*
X1004985Y332198D01*
X1012526D01*
G02X1012921Y331736I0J-400D01*
G03X1015742Y331939I1434J-227D01*
G01X1015733Y331968D01*
Y332198D01*
X1016136D01*
X1016394Y331941D01*
X1018856D01*
X1019114Y332198D01*
X1030915D01*
X1031295Y332579D01*
X1034329D01*
X1034556Y332352D01*
Y327200D01*
X1032300D01*
X1029808Y324708D01*
Y321592D01*
X1029058Y320842D01*
X1024754D01*
Y320841D01*
X1023258D01*
Y320842D01*
X1018254D01*
Y320841D01*
X1016545D01*
X1010280Y314576D01*
X1007896D01*
G02X1007630Y315275I0J400D01*
G03X1005700I-965J1085D01*
G02X1005434Y314576I-266J-299D01*
G01X1005076D01*
X1003287Y316365D01*
X1002995D01*
X1002918Y316442D01*
X996665D01*
X996637Y316608D01*
G03X993810Y315961I-1431J-249D01*
G02X993425Y315452I-385J-109D01*
G01X992837D01*
G03X990413Y314077I-1011J-1043D01*
G01X990438Y313968D01*
X989997Y313527D01*
G02X989440Y313518I-283J283D01*
G03X987004Y312289I-994J-1058D01*
G02X986607Y311842I-397J-47D01*
G01X985642D01*
X985606Y311857D01*
G03X984526I-540J-1348D01*
G01X984490Y311842D01*
X983525D01*
G02X983128Y312289I0J400D01*
G03X980244I-1442J171D01*
G02X979847Y311842I-397J-47D01*
G01X978882D01*
X978846Y311857D01*
G03X977766I-540J-1348D01*
G01X977730Y311842D01*
X976765D01*
G02X976368Y312289I0J400D01*
G03X973484I-1442J171D01*
G02X973087Y311842I-397J-47D01*
G01X972122D01*
X972086Y311857D01*
G03X971006I-540J-1348D01*
G01X970970Y311842D01*
X970005D01*
G02X969608Y312289I0J400D01*
G03X967525Y313763I-1442J171D01*
G01X967397Y313700D01*
X966125Y314972D01*
X966110Y315006D01*
G03X965383Y315733I-1324J-597D01*
G01X965349Y315748D01*
X965258Y315839D01*
Y316342D01*
X962869D01*
X962849Y316520D01*
G03X959963I-1443J-160D01*
G01X959943Y316342D01*
X956110D01*
X956090Y316520D01*
G03X953204I-1443J-160D01*
G01X953184Y316342D01*
X949350D01*
X949330Y316520D01*
G03X946444I-1443J-160D01*
G01X946424Y316342D01*
X942590D01*
X942570Y316520D01*
G03X939684I-1443J-160D01*
G01X939664Y316342D01*
X937886D01*
X936315Y315382D01*
G02X935731Y315861I-208J341D01*
G03X934189Y314919I-1364J499D01*
G02X934348Y314181I-50J-397D01*
G01X932507Y313056D01*
X920759Y306342D01*
X905158D01*
G37*
G36*
G01X980363Y209099D02*
X976822Y212640D01*
X966638D01*
G02X966238Y213033I0J400D01*
G03X963334I-1452J-24D01*
G02X962934Y212640I-400J7D01*
G01X959878D01*
G02X959478Y213033I0J400D01*
G03X956574I-1452J-24D01*
G02X956174Y212640I-400J7D01*
G01X953469D01*
G02X953069Y213034I0J400D01*
G03X952104Y214605I-1802J-25D01*
G02Y215313I186J354D01*
G03Y218505I-837J1596D01*
G02Y219213I186J354D01*
G03X953067Y220884I-837J1596D01*
G02X953681Y221239I400J17D01*
G03X952847Y222685I966J1521D01*
G02X952233Y222330I-400J-17D01*
G03X950301I-966J-1521D01*
G02X949687Y222685I-214J338D01*
G03X948853Y221239I-1800J75D01*
G02X949467Y220884I214J-338D01*
G03X950430Y219213I1800J-75D01*
G02Y218505I-186J-354D01*
G03Y215313I837J-1596D01*
G02Y214605I-186J-354D01*
G03X949465Y213034I837J-1596D01*
G02X949065Y212640I-400J6D01*
G01X946359D01*
G02X945959Y213033I0J400D01*
G03X943055I-1452J-24D01*
G02X942655Y212640I-400J7D01*
G01X939599D01*
G02X939199Y213033I0J400D01*
G03X936295I-1452J-24D01*
G02X935895Y212640I-400J7D01*
G01X935235D01*
X935192Y212662D01*
G03X933542I-825J-1602D01*
G01X933499Y212640D01*
X932839D01*
G02X932439Y213033I0J400D01*
G03X929535I-1452J-24D01*
G02X929135Y212640I-400J7D01*
G01X926079D01*
G02X925679Y213033I0J400D01*
G03X922775I-1452J-24D01*
G02X922375Y212640I-400J7D01*
G01X915900D01*
X915390Y213150D01*
X912650D01*
X912000Y213800D01*
X910050D01*
X908890Y212640D01*
X900190D01*
X898640Y214190D01*
Y221940D01*
X912544Y235844D01*
X922884D01*
X922940Y235737D01*
G03X925514I1287J672D01*
G01X925570Y235844D01*
X926038D01*
G02X926377Y235232I0J-400D01*
G03X928837I1230J-772D01*
G02X929176Y235844I339J212D01*
G01X929644D01*
X929700Y235737D01*
G03X932274I1287J672D01*
G01X932330Y235844D01*
X932798D01*
G02X933137Y235232I0J-400D01*
G03X935597I1230J-772D01*
G02X935936Y235844I339J212D01*
G01X936404D01*
X936460Y235737D01*
G03X939034I1287J672D01*
G01X939090Y235844D01*
X939558D01*
G02X939897Y235232I0J-400D01*
G03X942357I1230J-772D01*
G02X942696Y235844I339J212D01*
G01X943164D01*
X943220Y235737D01*
G03X945794I1287J672D01*
G01X945850Y235844D01*
X946318D01*
G02X946657Y235232I0J-400D01*
G03X949117I1230J-772D01*
G02X949456Y235844I339J212D01*
G01X949924D01*
X949980Y235737D01*
G03X952554I1287J672D01*
G01X952610Y235844D01*
X953033D01*
G02X953194Y235526I0J-200D01*
G03X952847Y234385I1453J-1065D01*
G02X952233Y234030I-400J-17D01*
G03X953067Y232584I-966J-1521D01*
G02X953681Y232939I400J17D01*
G03X956100Y235526I966J1521D01*
G02X956261Y235844I161J118D01*
G01X956683D01*
X956739Y235737D01*
G03X959313I1287J672D01*
G01X959369Y235844D01*
X959792D01*
G02X959953Y235526I0J-200D01*
G03X963207Y234533I1453J-1066D01*
G02X963820Y234888I400J17D01*
G03X965752I966J1521D01*
G02X966365Y234533I213J-338D01*
G03X967330Y232864I1801J-72D01*
G02Y232155I-186J-355D01*
G03X966365Y230486I836J-1597D01*
G02X965752Y230131I-400J-17D01*
G03X962986Y228536I-966J-1521D01*
G02X962372Y228181I-400J-17D01*
G03X963206Y226734I-966J-1521D01*
G02X963820Y227089I400J17D01*
G03X966587Y228683I966J1521D01*
G02X967200Y229038I400J17D01*
G03X969132I966J1521D01*
G02X969745Y228683I213J-338D01*
G03X970580Y230131I1801J-74D01*
G02X969967Y230486I-213J338D01*
G03X969002Y232155I-1801J72D01*
G02Y232864I186J354D01*
G03X969619Y235526I-836J1596D01*
G02X969780Y235844I161J118D01*
G01X970203D01*
X970259Y235737D01*
G03X972833I1287J672D01*
G01X972889Y235844D01*
X973357D01*
G02X973696Y235232I0J-400D01*
G03X975939Y235501I1230J-772D01*
G02X976078Y235844I139J143D01*
G01X976590D01*
X976641Y235720D01*
G03X979971I1665J689D01*
G01X980022Y235844D01*
X980534D01*
G02X980673Y235501I0J-200D01*
G03X982916Y235232I1013J-1041D01*
G02X983255Y235844I339J212D01*
G01X983723D01*
X983779Y235737D01*
G03X986353I1287J672D01*
G01X986409Y235844D01*
X986877D01*
G02X987216Y235232I0J-400D01*
G03X989459Y235501I1230J-772D01*
G02X989598Y235844I139J143D01*
G01X990110D01*
X990161Y235720D01*
G03X993491I1665J689D01*
G01X993542Y235844D01*
X993983D01*
G02X994127Y235505I0J-200D01*
G03X996285I1079J-1045D01*
G02X996429Y235844I144J139D01*
G01X996870D01*
X996921Y235720D01*
G03X1000251I1665J689D01*
G01X1000302Y235844D01*
X1000813D01*
G02X1000952Y235501I0J-200D01*
G03X1002978I1013J-1041D01*
G02X1003117Y235844I139J143D01*
G01X1003629D01*
X1003680Y235720D01*
G03X1007010I1665J689D01*
G01X1007061Y235844D01*
X1007502D01*
G02X1007646Y235505I0J-200D01*
G03X1009804I1079J-1045D01*
G02X1009948Y235844I144J139D01*
G01X1010389D01*
X1010440Y235720D01*
G03X1013770I1665J689D01*
G01X1013821Y235844D01*
X1014333D01*
G02X1014472Y235501I0J-200D01*
G03X1016498I1013J-1041D01*
G02X1016637Y235844I139J143D01*
G01X1017149D01*
X1017200Y235720D01*
G03X1020530I1665J689D01*
G01X1020581Y235844D01*
X1021068D01*
X1021283Y235629D01*
X1021150Y235488D01*
G03X1023273Y233365I1095J-1028D01*
G01X1023414Y233498D01*
X1024186Y232726D01*
X1024178Y232633D01*
G03X1025749Y231062I1447J-124D01*
G01X1025842Y231070D01*
X1027656Y229256D01*
X1027758D01*
X1027815Y229206D01*
G03X1030195I1190J1353D01*
G01X1030252Y229256D01*
X1030499D01*
G02X1030896Y228804I0J-400D01*
G03X1033874I1489J-194D01*
G02X1034271Y229256I397J52D01*
G01X1034518D01*
X1034575Y229206D01*
G03X1036955I1190J1353D01*
G01X1037012Y229256D01*
X1037309D01*
G02X1037706Y228803I1J-400D01*
G03X1040584I1439J-193D01*
G02X1040981Y229256I396J53D01*
G01X1041277D01*
X1041334Y229206D01*
G03X1043714I1190J1353D01*
G01X1043771Y229256D01*
X1044018D01*
G02X1044415Y228804I0J-400D01*
G03X1047393I1489J-194D01*
G02X1047790Y229256I397J52D01*
G01X1048037D01*
X1048094Y229206D01*
G03X1048738Y228842I1190J1353D01*
G01X1048784Y228827D01*
X1048929Y228682D01*
G02X1048784Y228023I-282J-283D01*
G03X1050647Y226160I500J-1363D01*
G02X1051306Y226305I376J-137D01*
G01X1053231Y224380D01*
X1055893D01*
X1055938Y224244D01*
G03X1058690I1376J465D01*
G01X1058735Y224380D01*
X1063390D01*
G02X1063790Y223983I0J-400D01*
G03X1066694I1452J13D01*
G02X1067094Y224380I400J-3D01*
G01X1067931D01*
X1067975Y224357D01*
G03X1067985Y224351I931J1540D01*
G02Y223643I-186J-354D01*
G03X1069788Y220526I837J-1596D01*
G02X1070402Y220171I214J-338D01*
G03X1074002I1800J-75D01*
G02X1074616Y220526I400J17D01*
G03X1073782Y221972I966J1521D01*
G02X1073168Y221617I-400J-17D01*
G03X1071236I-966J-1521D01*
G02X1070622Y221972I-214J338D01*
G03X1069659Y223643I-1800J75D01*
G02Y224351I186J354D01*
G03X1069669Y224357I-921J1546D01*
G01X1069713Y224380D01*
X1070350D01*
G02X1070750Y223983I0J-400D01*
G03X1073654I1452J13D01*
G02X1074054Y224380I400J-3D01*
G01X1077110D01*
G02X1077510Y223983I0J-400D01*
G03X1080414I1452J13D01*
G02X1080814Y224380I400J-3D01*
G01X1081450D01*
X1081494Y224357D01*
G03X1083188I847J1590D01*
G01X1083232Y224380D01*
X1083869D01*
G02X1084269Y223983I0J-400D01*
G03X1087173I1452J13D01*
G02X1087573Y224380I400J-3D01*
G01X1090629D01*
G02X1091029Y223983I0J-400D01*
G03X1093933I1452J13D01*
G02X1094333Y224380I400J-3D01*
G01X1094970D01*
X1095014Y224357D01*
G03X1096708I847J1590D01*
G01X1096752Y224380D01*
X1097389D01*
G02X1097789Y223983I0J-400D01*
G03X1100693I1452J13D01*
G02X1101093Y224380I400J-3D01*
G01X1101730D01*
X1101774Y224357D01*
G03X1101784Y224351I931J1540D01*
G02Y223643I-186J-354D01*
G03X1103587Y220526I837J-1596D01*
G02X1104201Y220171I214J-338D01*
G03X1106967Y218575I1800J-75D01*
G02X1107580Y218220I213J-338D01*
G03X1111182I1801J-73D01*
G02X1111795Y218575I400J17D01*
G03X1110960Y220023I966J1522D01*
G02X1110347Y219668I-400J-17D01*
G03X1108415I-966J-1521D01*
G02X1107802Y220023I-213J338D01*
G03X1105035Y221617I-1801J73D01*
G02X1104421Y221972I-214J338D01*
G03X1103458Y223643I-1800J75D01*
G02Y224351I186J354D01*
G03X1103468Y224357I-921J1546D01*
G01X1103512Y224380D01*
X1104149D01*
G02X1104549Y223983I0J-400D01*
G03X1106288Y225419I1452J13D01*
G02X1106084Y226094I79J392D01*
G01X1106535Y226545D01*
X1106571Y226561D01*
G03X1107336Y227326I-570J1335D01*
G01X1107352Y227362D01*
X1108351Y228361D01*
X1108483Y228284D01*
G03X1110347Y228326I897J1563D01*
G02X1110961Y227971I214J-338D01*
G03X1113727Y226375I1800J-75D01*
G02X1114340Y226020I213J-338D01*
G03X1115175Y227468I1801J-74D01*
G02X1114562Y227823I-213J338D01*
G03X1111795Y229417I-1801J73D01*
G02X1111181Y229772I-214J338D01*
G03X1110944Y230745I-1800J77D01*
G01X1110867Y230877D01*
X1110980Y230990D01*
G02X1111587Y230943I283J-282D01*
G03X1113615Y232971I1174J854D01*
G02X1113568Y233578I235J324D01*
G01X1114006Y234016D01*
G02X1114689Y233736I283J-283D01*
G03X1116151Y235198I1452J10D01*
G02X1115871Y235881I3J400D01*
G01X1116184Y236194D01*
X1116257Y236200D01*
G03X1117588Y237531I-116J1447D01*
G01X1117594Y237604D01*
X1118520Y238530D01*
X1118659Y238428D01*
G03X1120689Y240458I862J1168D01*
G01X1120587Y240597D01*
X1120713Y240723D01*
G02X1121342Y240642I283J-282D01*
G03X1123805Y243105I1558J905D01*
G02X1123724Y243734I201J346D01*
G01X1125682Y245692D01*
X1125795Y245661D01*
G03X1128015Y247881I485J1735D01*
G01X1127984Y247994D01*
X1128224Y248234D01*
X1128367Y248092D01*
X1128368Y248091D01*
G03X1130626Y247826I1292J1256D01*
G02X1131240Y247471I214J-338D01*
G03X1134766Y247915I1800J-75D01*
G02X1135149Y248430I383J115D01*
G01X1135291D01*
X1135350Y248365D01*
G03X1137546Y248430I1070J982D01*
G01X1142560D01*
G02X1142936Y247893I0J-400D01*
G03X1145664I1364J-497D01*
G02X1146040Y248430I376J137D01*
G01X1146554D01*
G03X1148806I1126J917D01*
G01X1149360D01*
X1149751Y248039D01*
X1149705Y247917D01*
G03X1152486Y247670I1355J-521D01*
G02X1152879Y248145I393J75D01*
G01X1153625D01*
G03X1155255I815J1202D01*
G01X1156001D01*
G02X1156394Y247670I0J-400D01*
G03X1159246I1426J-274D01*
G02X1159639Y248145I393J75D01*
G01X1160385D01*
G03X1162015I815J1202D01*
G01X1163000D01*
X1163222Y247923D01*
X1163188Y247809D01*
G03X1164993Y246004I1392J-413D01*
G01X1165107Y246038D01*
X1166004Y245141D01*
X1165745Y244881D01*
X1165608Y244976D01*
G03X1166362Y243762I-1028J-1480D01*
G02X1167041Y244104I396J60D01*
G01X1167584Y243561D01*
G02X1167444Y242904I-283J-283D01*
G03X1169317Y241031I516J-1357D01*
G02X1169974Y241171I374J-143D01*
G01X1170414Y240731D01*
X1170281Y240590D01*
G03X1172333Y238538I1058J-994D01*
G01X1172474Y238671D01*
X1173280Y237865D01*
X1173272Y237772D01*
G03X1174844Y236200I1447J-125D01*
G01X1174937Y236208D01*
X1177423Y233722D01*
G02X1177342Y233094I-283J-283D01*
G03X1179396Y231040I757J-1297D01*
G02X1180024Y231121I345J-202D01*
G01X1180359Y230786D01*
X1180269Y230649D01*
G03X1182658Y229000I1210J-802D01*
G01X1183092D01*
G02X1183464Y228452I0J-400D01*
G03X1186254I1395J-556D01*
G02X1186626Y229000I372J148D01*
G01X1187060D01*
G03X1189418I1179J847D01*
G01X1190232D01*
X1190455Y228778D01*
X1190374Y228644D01*
G03X1192388Y226664I1245J-748D01*
G02X1193000Y226325I212J-339D01*
G01Y222938D01*
G02X1192470Y222560I-400J0D01*
G03X1190213Y222291I-851J-2464D01*
G02X1189618Y222502I-215J337D01*
G03X1186860I-1379J-455D01*
G02X1186265Y222291I-380J126D01*
G03X1183453I-1406J-2195D01*
G02X1182858Y222502I-215J337D01*
G03X1180032Y222167I-1379J-455D01*
G02X1179633Y221800I-399J33D01*
G01X1179300D01*
X1178848Y221348D01*
X1178721Y221408D01*
G03X1176787Y219474I-622J-1312D01*
G01X1176847Y219347D01*
X1176480Y218980D01*
G02X1175878Y219022I-283J283D01*
G03X1173634Y217182I-1158J-876D01*
G02X1173519Y216561I-299J-266D01*
G03X1172876Y216090I1201J-2314D01*
G03X1172845Y216059I9628J-9659D01*
G01X1172786Y216000D01*
X1172769D01*
X1171915Y215146D01*
X1171615D01*
X1171353Y215297D01*
X1171352Y215299D01*
X1169262Y216505D01*
G03X1169160Y216561I-1305J-2256D01*
G02X1169045Y217182I184J355D01*
G03X1166581Y218602I-1085J965D01*
G02X1165986Y218391I-380J126D01*
G03X1163174I-1406J-2195D01*
G02X1162579Y218602I-215J337D01*
G03X1159769Y218392I-1379J-455D01*
G01X1159763Y218357D01*
X1159645Y218153D01*
X1159371Y218310D01*
X1159366Y218418D01*
G03X1159168Y219555I-4925J-272D01*
G03X1158027Y221533I-1348J541D01*
G03X1157700Y221849I-3588J-3385D01*
G02X1157933Y222548I264J300D01*
G03X1156442Y224453I-113J1448D01*
G02X1155846Y224242I-380J125D01*
G03X1153137Y224305I-1406J-2195D01*
G01X1153017Y224235D01*
G02X1152438Y224455I-200J346D01*
G03X1149904Y223117I-1378J-460D01*
G02X1149867Y222590I-318J-242D01*
G03X1149852Y222575I2242J-2257D01*
G01X1149617Y222340D01*
X1149110D01*
X1149066Y222480D01*
G03X1146294I-1386J-433D01*
G01X1146250Y222340D01*
X1145627D01*
X1145581Y222366D01*
G03X1142974Y222340I-1281J-2270D01*
G01X1137850D01*
X1137806Y222480D01*
G03X1135034I-1386J-433D01*
G01X1134990Y222340D01*
X1134401D01*
G02X1134107Y223011I0J400D01*
G03X1131973I-1067J985D01*
G02X1131679Y222340I-294J-271D01*
G01X1131090D01*
X1131046Y222480D01*
G03X1128211Y221957I-1386J-433D01*
G01X1128216Y221866D01*
X1127642Y221292D01*
X1127501Y221422D01*
G03X1125314Y221617I-1220J-1326D01*
G02X1124700Y221972I-214J338D01*
G03X1123737Y223643I-1800J75D01*
G02Y224351I186J354D01*
G03X1122063I-837J1596D01*
G02Y223643I-186J-354D01*
G03X1123866Y220526I837J-1596D01*
G02X1124480Y220171I214J-338D01*
G03X1124954Y218875I1800J-76D01*
G01X1125084Y218734D01*
X1124902Y218552D01*
G02X1124248Y218686I-283J283D01*
G03X1122361Y216799I-1348J-539D01*
G02X1122495Y216145I-149J-371D01*
G01X1120016Y213666D01*
X1119904Y213696D01*
G03X1118296Y213078I-385J-1400D01*
G01X1118229Y212973D01*
X1117026Y213107D01*
G03X1115635Y212887I-295J-2640D01*
G01X1115585Y212864D01*
X1111808Y213284D01*
X1111160Y213154D01*
X1110639Y213502D01*
X1110707Y213656D01*
G03X1108147Y213482I-1326J591D01*
G02X1107937Y212894I-340J-210D01*
G03X1107773Y212831I870J-2510D01*
G02X1107269Y213004I-155J368D01*
G03X1104630Y212774I-1268J-708D01*
G01X1104583Y212640D01*
X1104026D01*
G02X1103722Y213301I-1J400D01*
G03X1101520I-1101J946D01*
G02X1101216Y212640I-303J-261D01*
G01X1100659D01*
X1100612Y212774D01*
G03X1098051Y213128I-1371J-478D01*
G01X1097976Y213020D01*
X1095451Y213525D01*
X1091327Y212699D01*
X1091288Y212640D01*
X1090506D01*
G02X1090202Y213301I-1J400D01*
G03X1088000I-1101J946D01*
G02X1087696Y212640I-303J-261D01*
G01X1087139D01*
X1087092Y212774D01*
G03X1084350I-1371J-478D01*
G01X1084303Y212640D01*
X1083746D01*
G02X1083442Y213301I-1J400D01*
G03X1081240I-1101J946D01*
G02X1080936Y212640I-303J-261D01*
G01X1080379D01*
X1080332Y212774D01*
G03X1077807Y213178I-1371J-478D01*
G01X1077729Y213075D01*
X1074283Y213895D01*
X1072331Y212640D01*
X1070227D01*
G02X1069923Y213301I-1J400D01*
G03X1068611Y212810I-1102J946D01*
G02X1068836Y212132I-58J-396D01*
G01X1066203Y209499D01*
X1066065Y209593D01*
G03X1063971Y209099I-823J-1196D01*
G01X1058777D01*
X1058756Y209276D01*
G03X1055872I-1442J-167D01*
G01X1055851Y209099D01*
X1050837D01*
G02X1050555Y209783I0J400D01*
G03X1048013I-1271J1277D01*
G02X1047731Y209099I-282J-284D01*
G01X1047367D01*
X1047346Y209276D01*
G03X1044462I-1442J-167D01*
G01X1044441Y209099D01*
X1044077D01*
G02X1043795Y209783I0J400D01*
G03X1041559Y212582I-1271J1277D01*
G02X1040946Y212936I-214J338D01*
G03X1040110Y211487I-1801J73D01*
G02X1040723Y211133I214J-338D01*
G03X1041253Y209783I1801J-72D01*
G02X1040971Y209099I-282J-284D01*
G01X1040608D01*
X1040587Y209276D01*
G03X1037703I-1442J-167D01*
G01X1037682Y209099D01*
X1033848D01*
X1033827Y209276D01*
G03X1030943I-1442J-167D01*
G01X1030922Y209099D01*
X1027088D01*
X1027067Y209276D01*
G03X1024183I-1442J-167D01*
G01X1024162Y209099D01*
X1013568D01*
X1013547Y209276D01*
G03X1010663I-1442J-167D01*
G01X1010642Y209099D01*
X1006808D01*
X1006787Y209276D01*
G03X1003903I-1442J-167D01*
G01X1003882Y209099D01*
X1000049D01*
X1000028Y209276D01*
G03X997144I-1442J-167D01*
G01X997123Y209099D01*
X996759D01*
G02X996477Y209783I0J400D01*
G03X997007Y211133I-1271J1278D01*
G02X997620Y211488I400J17D01*
G03X996785Y212936I966J1522D01*
G02X996172Y212581I-400J-17D01*
G03X994240I-966J-1521D01*
G02X993627Y212936I-213J338D01*
G03X992663Y214605I-1801J73D01*
G02Y215313I186J354D01*
G03X990025Y216836I-837J1596D01*
G02X989412Y216481I-400J-17D01*
G03Y213439I-966J-1521D01*
G02X990026Y213084I214J-338D01*
G03X990989Y211413I1800J-75D01*
G02Y210705I-186J-354D01*
G03X990032Y209280I837J-1596D01*
G01X990015Y209099D01*
X980363D01*
G37*
G36*
G01X895523Y354694D02*
X894686Y355532D01*
Y365844D01*
X894685Y365845D01*
Y381405D01*
X897010Y383730D01*
X919120D01*
G02X919493Y383185I0J-400D01*
G03X922201I1354J-525D01*
G02X922574Y383730I373J145D01*
G01X925880D01*
G02X926253Y383185I0J-400D01*
G03X928961I1354J-525D01*
G02X929334Y383730I373J145D01*
G01X929831D01*
G03X932143I1156J879D01*
G01X932640D01*
G02X933013Y383185I0J-400D01*
G03X935721I1354J-525D01*
G02X936094Y383730I373J145D01*
G01X936591D01*
G03X938903I1156J879D01*
G01X939400D01*
G02X939773Y383185I0J-400D01*
G03X942481I1354J-525D01*
G02X942854Y383730I373J145D01*
G01X943351D01*
G03X945607Y383661I1156J879D01*
G01X945666Y383730D01*
X945789D01*
G02X946170Y383208I0J-400D01*
G03X949604I1717J-548D01*
G02X949985Y383730I381J122D01*
G01X950108D01*
X950167Y383661D01*
G03X952367I1100J948D01*
G01X952426Y383730D01*
X952549D01*
G02X952930Y383208I0J-400D01*
G03X956364I1717J-548D01*
G02X956745Y383730I381J122D01*
G01X956867D01*
X956926Y383661D01*
G03X959182Y383730I1100J948D01*
G01X959679D01*
G02X960052Y383185I0J-400D01*
G03X962096Y383938I1354J-525D01*
G02X962003Y384573I190J352D01*
G01X962301Y384871D01*
G02X962984Y384592I283J-283D01*
G03X963949Y383013I1802J17D01*
G02Y382305I-186J-354D01*
G03X965623I837J-1596D01*
G02Y383013I186J354D01*
G03X964304Y386345I-837J1596D01*
G01X964192Y386314D01*
X963968Y386538D01*
X964510Y387080D01*
X964607Y387068D01*
G03X966024Y387750I179J1441D01*
G01X966491D01*
G02X966853Y387179I0J-400D01*
G03X969479I1313J-619D01*
G02X969841Y387750I362J171D01*
G01X973251D01*
G02X973613Y387179I0J-400D01*
G03X976239I1313J-619D01*
G02X976601Y387750I362J171D01*
G01X990588D01*
G03X993064I1238J759D01*
G01X993531D01*
G02X993893Y387179I0J-400D01*
G03X996519I1313J-619D01*
G02X996881Y387750I362J171D01*
G01X997348D01*
G03X999824I1238J759D01*
G01X1000290D01*
G02X1000652Y387179I0J-400D01*
G03X1003278I1313J-619D01*
G02X1003640Y387750I362J171D01*
G01X1004107D01*
G03X1006583I1238J759D01*
G01X1007050D01*
G02X1007412Y387179I0J-400D01*
G03X1010038I1313J-619D01*
G02X1010400Y387750I362J171D01*
G01X1010867D01*
G03X1013343I1238J759D01*
G01X1013760D01*
X1017070Y384440D01*
X1017079Y384373D01*
G03X1020438Y383730I1786J236D01*
G01X1020841D01*
G02X1021011Y383425I0J-200D01*
G03X1023479I1234J-765D01*
G02X1023649Y383730I170J105D01*
G01X1024052D01*
G03X1027198I1573J879D01*
G01X1027601D01*
G02X1027771Y383425I0J-200D01*
G03X1030239I1234J-765D01*
G02X1030409Y383730I170J105D01*
G01X1030812D01*
G03X1033958I1573J879D01*
G01X1034361D01*
G02X1034531Y383425I0J-200D01*
G03X1036999I1234J-765D01*
G02X1037169Y383730I170J105D01*
G01X1037572D01*
G03X1040718I1573J879D01*
G01X1041120D01*
G02X1041290Y383425I0J-200D01*
G03X1043758I1234J-765D01*
G02X1043928Y383730I170J105D01*
G01X1044331D01*
G03X1047477I1573J879D01*
G01X1047880D01*
G02X1048050Y383425I0J-200D01*
G03X1050638Y383185I1234J-765D01*
G02X1051011Y383730I373J145D01*
G01X1058590D01*
X1059009Y383311D01*
X1058973Y383195D01*
G03X1059857Y381064I1721J-535D01*
G02Y380356I-186J-354D01*
G03X1062494Y378842I837J-1596D01*
G02X1063176Y379144I400J19D01*
G01X1067050Y375270D01*
Y361820D01*
X1066230Y361000D01*
X1062378D01*
G02X1062138Y361720I0J400D01*
G03X1059972I-1083J1440D01*
G02X1059732Y361000I-240J-320D01*
G01X1058390D01*
X1054107Y365283D01*
X1054096Y365346D01*
G03X1052901Y366541I-1432J-237D01*
G01X1052838Y366552D01*
X1052510Y366880D01*
G02X1052765Y367562I283J283D01*
G03X1051255Y368660I-101J1448D01*
G01X1051282Y368551D01*
X1051061Y368329D01*
X1050810Y368580D01*
X1050253D01*
X1050206Y368608D01*
G03X1048362I-922J-1548D01*
G01X1048315Y368580D01*
X1047756D01*
G02X1047356Y368986I0J400D01*
G03X1044452I-1452J24D01*
G02X1044052Y368580I-400J-6D01*
G01X1043493D01*
X1043446Y368608D01*
G03X1041602I-922J-1548D01*
G01X1041555Y368580D01*
X1040997D01*
G02X1040597Y368986I0J400D01*
G03X1037693I-1452J24D01*
G02X1037293Y368580I-400J-6D01*
G01X1036734D01*
X1036687Y368608D01*
G03X1034843I-922J-1548D01*
G01X1034796Y368580D01*
X1034287D01*
G02X1033887Y368986I0J400D01*
G03X1030883I-1502J24D01*
G02X1030483Y368580I-400J-6D01*
G01X1029974D01*
X1029927Y368608D01*
G03X1028083I-922J-1548D01*
G01X1028036Y368580D01*
X1027477D01*
G02X1027077Y368986I0J400D01*
G03X1024173I-1452J24D01*
G02X1023773Y368580I-400J-6D01*
G01X1023214D01*
X1023167Y368608D01*
G03X1021323I-922J-1548D01*
G01X1021276Y368580D01*
X1020767D01*
G02X1020367Y368986I0J400D01*
G03X1017363I-1502J24D01*
G02X1016963Y368580I-400J-6D01*
G01X1016454D01*
X1016407Y368608D01*
G03X1014563I-922J-1548D01*
G01X1014516Y368580D01*
X1013957D01*
G02X1013557Y368986I0J400D01*
G03X1012177Y367560I-1452J24D01*
G01X1012266Y367564D01*
X1012470Y367360D01*
X1012045Y366935D01*
X1011980D01*
X1011650Y366605D01*
X1010926D01*
G02X1010526Y367015I0J400D01*
G03X1006924I-1801J45D01*
G02X1006524Y366605I-400J-10D01*
G01X1004166D01*
G02X1003766Y367015I0J400D01*
G03X1000164I-1801J45D01*
G02X999764Y366605I-400J-10D01*
G01X997407D01*
G02X997007Y367015I0J400D01*
G03X993405I-1801J45D01*
G02X993005Y366605I-400J-10D01*
G01X990297D01*
G02X989897Y367017I0J400D01*
G03X986995I-1451J43D01*
G02X986595Y366605I-400J-12D01*
G01X986072D01*
X986023Y366636D01*
G03X985902Y366705I-952J-1530D01*
G02Y367414I186J354D01*
G03X986867Y369083I-836J1597D01*
G02X987480Y369438I400J17D01*
G03X986645Y370886I966J1522D01*
G02X986032Y370531I-400J-17D01*
G03X984100I-966J-1521D01*
G02X983487Y370886I-213J338D01*
G03X982522Y372555I-1801J72D01*
G02Y373264I186J354D01*
G03X983487Y374933I-836J1597D01*
G02X984100Y375288I400J17D01*
G03X986866Y376884I966J1521D01*
G02X987480Y377239I400J17D01*
G03X986646Y378685I966J1521D01*
G02X986032Y378330I-400J-17D01*
G03X983265Y376736I-966J-1521D01*
G02X982652Y376381I-400J-17D01*
G03X980850Y373264I-966J-1521D01*
G02Y372555I-186J-354D01*
G03X979885Y370886I836J-1597D01*
G02X979272Y370531I-400J-17D01*
G03X980107Y369083I-966J-1522D01*
G02X980720Y369438I400J17D01*
G03X982652I966J1521D01*
G02X983265Y369083I213J-338D01*
G03X984230Y367414I1801J-72D01*
G02Y366705I-186J-354D01*
G03X984109Y366636I831J-1599D01*
G01X984060Y366605D01*
X983587D01*
G02X983187Y367017I0J400D01*
G03X980185I-1501J43D01*
G02X979785Y366605I-400J-12D01*
G01X976777D01*
G02X976377Y367017I0J400D01*
G03X973475I-1451J43D01*
G02X973075Y366605I-400J-12D01*
G01X972552D01*
X972503Y366636D01*
G03X970589I-957J-1527D01*
G01X970540Y366605D01*
X970017D01*
G02X969617Y367017I0J400D01*
G03X966715I-1451J43D01*
G02X966315Y366605I-400J-12D01*
G01X963607D01*
G02X963207Y367015I0J400D01*
G03X959605Y367127I-1801J45D01*
G01X959598Y366935D01*
X956106D01*
X956098Y367126D01*
G03X953465Y367904I-1451J-66D01*
G02X952857Y367853I-326J232D01*
G01X952492Y368218D01*
X952559Y368347D01*
G03X949940Y369600I-1292J663D01*
G01X949471D01*
G02X949129Y370207I0J400D01*
G03X946645I-1242J752D01*
G02X946303Y369600I-342J-207D01*
G01X945834D01*
G03X943180I-1327J-590D01*
G01X942711D01*
G02X942369Y370207I0J400D01*
G03X939885I-1242J752D01*
G02X939543Y369600I-342J-207D01*
G01X939074D01*
G03X936420I-1327J-590D01*
G01X935951D01*
G02X935609Y370207I0J400D01*
G03X933125I-1242J752D01*
G02X932783Y369600I-342J-207D01*
G01X932314D01*
G03X929660I-1327J-590D01*
G01X929239D01*
G02X929076Y369916I0J200D01*
G03X926138I-1469J1043D01*
G02X925975Y369600I-163J-116D01*
G01X925554D01*
G03X922900I-1327J-590D01*
G01X918494D01*
G03X915840I-1327J-590D01*
G01X897700D01*
X897000Y368900D01*
Y368502D01*
X896998D01*
Y366498D01*
X897000D01*
Y365502D01*
X896998D01*
Y363498D01*
X897000D01*
Y362502D01*
X896998D01*
Y360498D01*
X897000D01*
Y359502D01*
X896998D01*
Y357498D01*
X897000D01*
Y356502D01*
X896998D01*
Y354694D01*
X895523D01*
G37*
G36*
G01X953627Y26664D02*
X952201Y28090D01*
Y29199D01*
X949500Y31900D01*
Y36400D01*
X950482Y37382D01*
X953518D01*
X953526Y37389D01*
X957220D01*
X958519Y36090D01*
Y29610D01*
G02X957933Y29256I-400J0D01*
G03X956092Y27275I-650J-1242D01*
G02X955752Y26664I-340J-211D01*
G01X953627D01*
G37*
G36*
G01X961421Y26500D02*
X959820Y28101D01*
Y29648D01*
X962663D01*
G02X962955Y28975I0J-400D01*
G03X962874Y27147I1021J-961D01*
G02X962560Y26500I-314J-247D01*
G01X961421D01*
G37*
G36*
G01X965078Y27147D02*
G03X964436Y29338I-1102J867D01*
G01X964302Y29385D01*
Y30148D01*
X965802D01*
Y34052D01*
X964302D01*
Y34552D01*
X962124D01*
G02X961792Y35175I0J400D01*
G03X961713Y36846I-1163J782D01*
G02X962022Y37500I309J254D01*
G01X965929D01*
G02X966238Y36846I0J-400D01*
G03X968406I1084J-889D01*
G02X968715Y37500I309J254D01*
G01X972622D01*
G02X972931Y36846I0J-400D01*
G03X972852Y35175I1084J-889D01*
G02X972520Y34552I-332J-223D01*
G01X971998D01*
Y33502D01*
X970977D01*
G03Y30698I-35J-1402D01*
G01X971998D01*
Y29648D01*
X972702D01*
G02X972994Y28975I0J-400D01*
G03X972913Y27147I1021J-961D01*
G02X972599Y26500I-314J-247D01*
G01X972085D01*
G02X971771Y27147I0J400D01*
G03X969567I-1102J867D01*
G02X969253Y26500I-314J-247D01*
G01X965392D01*
G02X965078Y27147I0J400D01*
G37*
G36*
G01X962300Y8200D02*
X961956Y8544D01*
Y8659D01*
X961965Y8689D01*
G03X960203Y10450I-1336J425D01*
G01X960087Y10413D01*
X959984Y10516D01*
G02X960267Y11198I283J282D01*
G01X964202D01*
Y11698D01*
X965702D01*
Y14702D01*
X964202D01*
Y15202D01*
X959698D01*
Y14602D01*
X958900D01*
Y16700D01*
X959800Y17600D01*
X962180D01*
G02X962578Y17168I-1J-400D01*
G03X965374I1398J-111D01*
G02X965772Y17600I399J32D01*
G01X968873D01*
G02X969271Y17168I-1J-400D01*
G03X972038Y17357I1398J-111D01*
G01X972034Y17378D01*
Y17600D01*
X972650D01*
Y17378D01*
X972646Y17357D01*
G03X975413Y17168I1369J-300D01*
G02X975811Y17600I399J32D01*
G01X978912D01*
G02X979310Y17168I-1J-400D01*
G03X982077Y17357I1398J-111D01*
G01X982073Y17378D01*
Y17600D01*
X982690D01*
Y17378D01*
X982686Y17357D01*
G03X985453Y17168I1369J-300D01*
G02X985851Y17600I399J32D01*
G01X988952D01*
G02X989350Y17168I-1J-400D01*
G03X992117Y17357I1398J-111D01*
G01X992113Y17378D01*
Y17600D01*
X992729D01*
Y17378D01*
X992725Y17357D01*
G03X995492Y17168I1369J-300D01*
G02X995890Y17600I399J32D01*
G01X998991D01*
G02X999389Y17168I-1J-400D01*
G03X1002156Y17357I1398J-111D01*
G01X1002152Y17378D01*
Y17600D01*
X1002769D01*
Y17378D01*
X1002765Y17357D01*
G03X1003322Y15914I1369J-300D01*
G02X1003373Y15305I-232J-326D01*
G01X1003269Y15202D01*
X1000856D01*
Y14702D01*
X999356D01*
Y11698D01*
X1000856D01*
Y11198D01*
X1005360D01*
Y11474D01*
X1005710D01*
X1005752Y11329D01*
G03X1007589Y10400I1348J385D01*
G01X1007622Y10412D01*
X1009150D01*
G02X1009502Y9824I-1J-400D01*
G03X1009380Y8708I1324J-709D01*
G02X1008995Y8200I-385J-108D01*
G01X1005460D01*
Y8667D01*
X1005469Y8697D01*
G03X1002797I-1336J425D01*
G01X1002806Y8667D01*
Y8200D01*
X998768D01*
Y8667D01*
X998777Y8697D01*
G03X996105I-1336J425D01*
G01X996114Y8667D01*
Y8200D01*
X995420D01*
Y8667D01*
X995430Y8697D01*
G03X992758I-1336J425D01*
G01X992768Y8667D01*
Y8200D01*
X988728D01*
Y8659D01*
X988737Y8689D01*
G03X986065I-1336J425D01*
G01X986074Y8659D01*
Y8200D01*
X985382D01*
Y8662D01*
X985391Y8691D01*
G03Y9537I-1337J423D01*
G01X985382Y9566D01*
Y9662D01*
X985314Y9730D01*
X985299Y9758D01*
G03X982719Y8686I-1245J-645D01*
G01X982728Y8656D01*
Y8200D01*
X978688D01*
Y8659D01*
X978698Y8689D01*
G03X976026I-1336J425D01*
G01X976036Y8659D01*
Y8200D01*
X975342D01*
Y8659D01*
X975351Y8689D01*
G03X972679I-1336J425D01*
G01X972688Y8659D01*
Y8200D01*
X969049D01*
G02X968666Y8714I0J400D01*
G03X965978I-1344J400D01*
G02X965595Y8200I-383J-114D01*
G01X962300D01*
G37*
G36*
G01X952066Y65985D02*
X952053Y66041D01*
G03X950932Y67162I-1463J-342D01*
G01X950876Y67175D01*
X949500Y68551D01*
Y74400D01*
X950294Y75194D01*
X953406D01*
X953443Y75232D01*
X957137D01*
X958436Y73933D01*
Y69533D01*
G02X957925Y69149I-400J0D01*
G03Y66455I-389J-1347D01*
G02X958436Y66071I111J-384D01*
G01Y65908D01*
X957035Y64507D01*
X953544D01*
X952066Y65985D01*
G37*
G36*
G01X1005919Y93308D02*
X1007678D01*
X1009620Y91366D01*
Y84813D01*
X1008811Y84004D01*
X1005460D01*
Y86952D01*
X1005467Y86979D01*
G03Y87805I-1444J413D01*
G01X1005460Y87832D01*
Y87833D01*
X1005445Y87875D01*
G03X1002806Y86511I-1422J-483D01*
G01Y84004D01*
X998768D01*
Y86686D01*
X998788Y86728D01*
G03X996094I-1347J664D01*
G01X996114Y86686D01*
Y84004D01*
X995518D01*
Y84235D01*
X995527Y84264D01*
G03X992612Y84469I-1433J450D01*
G02X992217Y84004I-395J-65D01*
G01X989293D01*
G02X988895Y84445I0J400D01*
G03X985940Y84250I-1494J154D01*
G01X985945Y84228D01*
Y84004D01*
X985382D01*
Y86686D01*
X985402Y86728D01*
G03X982708I-1347J664D01*
G01X982728Y86686D01*
Y84004D01*
X978688D01*
Y86686D01*
X978709Y86728D01*
G03X976015I-1347J664D01*
G01X976036Y86686D01*
Y84004D01*
X975471D01*
Y84228D01*
X975476Y84250D01*
G03X972521Y84445I-1461J349D01*
G02X972123Y84004I-398J-41D01*
G01X969148D01*
G02X968754Y84471I0J400D01*
G03X965890I-1432J243D01*
G02X965496Y84004I-394J-67D01*
G01X964478D01*
X959057Y89425D01*
Y90800D01*
X959357Y91100D01*
X970900D01*
X972639Y89361D01*
X972654Y89329D01*
G03X975362Y90628I1361J635D01*
G01X975342Y90670D01*
Y92742D01*
X975908Y93308D01*
X979382D01*
Y90670D01*
X979361Y90628D01*
G03X982055I1347J-664D01*
G01X982034Y90670D01*
Y93308D01*
X982590D01*
Y93087D01*
X982585Y93067D01*
G03X985552Y92876I1470J-310D01*
G02X985951Y93308I399J32D01*
G01X988852D01*
G02X989251Y92876I0J-400D01*
G03X992218Y93067I1497J-119D01*
G01X992213Y93087D01*
Y93308D01*
X992768D01*
Y90670D01*
X992747Y90628D01*
G03X995441I1347J-664D01*
G01X995420Y90670D01*
Y93308D01*
X999460D01*
Y90670D01*
X999440Y90628D01*
G03X1002134I1347J-664D01*
G01X1002114Y90670D01*
Y93308D01*
X1002558D01*
Y93087D01*
X1002553Y93067D01*
G03X1005445Y92274I1470J-310D01*
G01X1005457Y92309D01*
X1005467Y92344D01*
G03X1005520Y92876I-1444J413D01*
G02X1005919Y93308I399J32D01*
G37*
G36*
G01X1014552Y48998D02*
Y52002D01*
X1013052D01*
Y52502D01*
X1008770D01*
X1008734Y52656D01*
G03X1006143Y51654I-1364J-323D01*
G02X1005793Y51060I-350J-194D01*
G01X1005360D01*
Y53002D01*
X1000856D01*
Y52502D01*
X999356D01*
Y49498D01*
X1000856D01*
Y48998D01*
X1003127D01*
X1003420Y48706D01*
G02X1003358Y48090I-283J-283D01*
G03X1002789Y46525I775J-1168D01*
G01X1002797Y46497D01*
X1002806Y46467D01*
Y46200D01*
X998768D01*
Y46467D01*
X998773Y46483D01*
Y46486D01*
X998778Y46501D01*
G03X996097Y46525I-1337J421D01*
G01X996105Y46497D01*
X996114Y46467D01*
Y46200D01*
X995420D01*
Y46467D01*
X995430Y46497D01*
G03X992758I-1336J425D01*
G01X992768Y46467D01*
Y46200D01*
X988728D01*
Y46459D01*
X988733Y46475D01*
Y46478D01*
X988738Y46493D01*
G03X986057Y46517I-1337J421D01*
G01X986065Y46489D01*
X986074Y46459D01*
Y46200D01*
X985382D01*
Y46462D01*
X985391Y46492D01*
Y46493D01*
G03Y47335I-1337J421D01*
G01Y47336D01*
X985382Y47366D01*
Y47462D01*
X985314Y47530D01*
X985299Y47558D01*
X985285Y47584D01*
G03X982719Y46486I-1231J-671D01*
G01X982728Y46457D01*
Y46200D01*
X978688D01*
Y46459D01*
X978698Y46489D01*
G03X976022Y46503I-1336J425D01*
G01X976026Y46490D01*
X976036Y46427D01*
Y46200D01*
X975342D01*
Y46459D01*
X975347Y46475D01*
Y46478D01*
X975352Y46493D01*
G03X972671Y46517I-1337J421D01*
G01X972679Y46489D01*
X972688Y46459D01*
Y46200D01*
X969096D01*
G02X968703Y46670I1J400D01*
G03X965941I-1381J244D01*
G02X965548Y46200I-394J-70D01*
G01X961956D01*
Y46459D01*
X961961Y46475D01*
Y46478D01*
X961966Y46493D01*
G03X960076Y48202I-1337J421D01*
G01X959951Y48149D01*
X959784Y48316D01*
G02X960067Y48998I283J282D01*
G01X964102D01*
Y49498D01*
X965602D01*
Y52502D01*
X964102D01*
Y53002D01*
X959598D01*
Y52252D01*
X958700D01*
Y54200D01*
X960300Y55800D01*
X962650D01*
Y55312D01*
X962640Y55282D01*
G03X965312I1336J-425D01*
G01X965302Y55312D01*
Y55800D01*
X969342D01*
Y55312D01*
X969337Y55296D01*
Y55293D01*
X969332Y55278D01*
G03X972013Y55254I1337J-421D01*
G01X972005Y55282D01*
X971996Y55312D01*
Y55800D01*
X972688D01*
Y55312D01*
X972683Y55296D01*
Y55293D01*
X972678Y55278D01*
G03X975359Y55254I1337J-421D01*
G01X975351Y55282D01*
X975342Y55312D01*
Y55800D01*
X979382D01*
Y55312D01*
X979372Y55282D01*
G03X982044I1336J-425D01*
G01X982034Y55312D01*
Y55800D01*
X982728D01*
Y55312D01*
X982723Y55296D01*
Y55293D01*
X982718Y55278D01*
G03X985399Y55254I1337J-421D01*
G01X985391Y55282D01*
X985382Y55312D01*
Y55800D01*
X989422D01*
Y55312D01*
X989412Y55282D01*
G03X992084I1336J-425D01*
G01X992074Y55312D01*
Y55800D01*
X992768D01*
Y55312D01*
X992758Y55282D01*
G03X995430I1336J-425D01*
G01X995420Y55312D01*
Y55800D01*
X999460D01*
Y55312D01*
X999455Y55296D01*
Y55293D01*
X999450Y55278D01*
G03X1002131Y55254I1337J-421D01*
G01X1002123Y55282D01*
X1002114Y55312D01*
Y55800D01*
X1002806D01*
Y55309D01*
X1002797Y55279D01*
Y55278D01*
G03X1005470Y55285I1338J-421D01*
G01X1005460Y55314D01*
Y55800D01*
X1009296D01*
G02X1009490Y55554I0J-200D01*
G01X1009479Y55507D01*
X1009470Y55487D01*
G03X1012148Y54128I1357J-644D01*
G02X1012851I352J-190D01*
G03X1015521Y55505I1322J714D01*
G01X1015500Y55547D01*
Y55800D01*
X1016400D01*
Y63900D01*
X1015800Y64500D01*
X1005681D01*
G02X1005338Y65105I0J400D01*
G03X1005421Y66376I-1205J717D01*
G02X1005788Y66934I368J158D01*
G01X1007325D01*
G03X1008694Y68822I55J1401D01*
G01X1008682Y68855D01*
Y70415D01*
X1008694Y70448D01*
G03X1006066I-1314J487D01*
G01X1006078Y70415D01*
Y69736D01*
X1005360D01*
Y72352D01*
X1005189D01*
X1005059Y72696D01*
X1005146Y72787D01*
G03X1005277Y74569I-1012J970D01*
G02X1005603Y75200I326J231D01*
G01X1015400D01*
X1016200Y76000D01*
Y86856D01*
X1016217Y86895D01*
G03Y88105I-1375J605D01*
G01X1016200Y88144D01*
Y91366D01*
G03Y93634I-985J1134D01*
G01Y101000D01*
X1016500Y101300D01*
X1018600D01*
Y76200D01*
X1024298Y70502D01*
Y66598D01*
X1024100Y66400D01*
X1020400D01*
X1018500Y64500D01*
Y64016D01*
X1018498Y64015D01*
Y56324D01*
X1018526D01*
X1018997Y55854D01*
X1019564D01*
X1019934Y55484D01*
X1021885D01*
X1022624Y54744D01*
Y48924D01*
X1019672D01*
X1018498Y47750D01*
Y39185D01*
X1018500Y39184D01*
Y38100D01*
X1019000Y37600D01*
X1020084D01*
X1020085Y37598D01*
X1021402D01*
X1024200Y34800D01*
Y28700D01*
X1022002Y26502D01*
X1019899D01*
X1019800Y26600D01*
X1019000D01*
X1018850Y26450D01*
X1016350D01*
X1016300Y26500D01*
X1015714D01*
G02X1015390Y27134I0J400D01*
G03X1015159Y29147I-1217J880D01*
G02X1015422Y29848I263J301D01*
G01X1015752D01*
Y33752D01*
X1014252D01*
Y34432D01*
X1014419Y34460D01*
G03X1015365Y36857I-246J1482D01*
G02X1015682Y37500I317J243D01*
G01X1015800D01*
X1016400Y38100D01*
Y46200D01*
X1015500D01*
Y47163D01*
X1015310Y47353D01*
X1015295Y47397D01*
G03X1013540Y48379I-1422J-483D01*
G02X1013052Y48769I-88J390D01*
G01Y48998D01*
X1014552D01*
G37*
G36*
G01X960933Y64500D02*
X959627Y65806D01*
Y67448D01*
X962663D01*
G02X962955Y66775I0J-400D01*
G03X962768Y65103I1021J-961D01*
G02X962423Y64500I-345J-203D01*
G01X960933D01*
G37*
G36*
G01X965529D02*
G02X965184Y65103I0J400D01*
G03X964436Y67138I-1208J711D01*
G01X964302Y67185D01*
Y67902D01*
X964348Y67948D01*
X965802D01*
Y71852D01*
X964548D01*
X964302Y72098D01*
Y72352D01*
X964048D01*
X964000Y72400D01*
X959927D01*
X959627Y72700D01*
Y73946D01*
X960881Y75200D01*
X965853D01*
G02X966179Y74569I0J-400D01*
G03X968465I1143J-812D01*
G02X968791Y75200I326J231D01*
G01X972546D01*
G02X972872Y74569I0J-400D01*
G03X972852Y72975I1143J-811D01*
G02X972520Y72352I-332J-223D01*
G01X971998D01*
Y71302D01*
X970977D01*
G03Y68498I-35J-1402D01*
G01X971998D01*
Y67448D01*
X972702D01*
G02X972994Y66775I0J-400D01*
G03X972807Y65103I1021J-961D01*
G02X972462Y64500I-345J-203D01*
G01X972222D01*
G02X971877Y65103I0J400D01*
G03X969461I-1208J711D01*
G02X969116Y64500I-345J-203D01*
G01X965529D01*
G37*
G36*
G01X967100Y95600D02*
X966500Y96200D01*
Y101500D01*
X965800Y102200D01*
X962200D01*
X961600Y101600D01*
Y96100D01*
X961200Y95700D01*
X959800D01*
X959600Y95900D01*
Y104800D01*
X960900Y106100D01*
Y109967D01*
G02X961378Y110359I400J0D01*
G01X966582Y109318D01*
X967200Y108700D01*
X968000D01*
X968200Y108500D01*
Y95900D01*
X967900Y95600D01*
X967100D01*
G37*
G36*
G01X972600Y492300D02*
X971530Y493370D01*
Y496266D01*
X971500D01*
Y498900D01*
X973300Y500700D01*
X974699D01*
G02X975082Y500182I1J-400D01*
G03X975437Y498770I1339J-414D01*
G02X975445Y498208I-281J-285D01*
G03X977524Y498296I1085J-1038D01*
G02X977486Y498856I265J299D01*
G03X977760Y500182I-1065J911D01*
G02X978143Y500700I382J118D01*
G01X1017300D01*
X1019100Y498900D01*
Y494700D01*
X1016700Y492300D01*
X972600D01*
G37*
G36*
G01X956800D02*
X955243Y493857D01*
G03X953763Y496183I-1243J843D01*
G02X953300Y496578I-63J395D01*
G01Y497800D01*
X956200Y500700D01*
Y502700D01*
X956100Y502800D01*
Y513400D01*
X956800Y514100D01*
X958400D01*
X958700Y513800D01*
Y512272D01*
X959100Y511872D01*
Y511500D01*
X958200Y510600D01*
Y499500D01*
X959066Y498634D01*
Y496266D01*
X959048D01*
Y492548D01*
X958800Y492300D01*
X956800D01*
G37*
G36*
G01X962125Y510263D02*
X962116Y510329D01*
G03X960844Y511601I-1487J-215D01*
G01X960778Y511610D01*
X959701Y512687D01*
Y518186D01*
X960305Y518790D01*
X962103D01*
G02X962497Y518320I0J-400D01*
G03X965455I1479J-263D01*
G02X965849Y518790I394J70D01*
G01X968781D01*
G02X969178Y518341I0J-400D01*
G03X972122Y518539I1491J-183D01*
G01X972115Y518564D01*
Y518790D01*
X972688D01*
Y516070D01*
X972668Y516028D01*
G03X975362I1347J-664D01*
G01X975342Y516070D01*
Y518790D01*
X979382D01*
Y516070D01*
X979361Y516028D01*
G03X982055I1347J-664D01*
G01X982034Y516070D01*
Y518790D01*
X982609D01*
Y518564D01*
X982602Y518539D01*
G03X985546Y518341I1453J-381D01*
G02X985943Y518790I397J49D01*
G01X988860D01*
G02X989257Y518341I0J-400D01*
G03X992201Y518539I1491J-183D01*
G01X992194Y518564D01*
Y518790D01*
X992768D01*
Y516070D01*
X992747Y516028D01*
G03X995441I1347J-664D01*
G01X995420Y516070D01*
Y518790D01*
X999460D01*
Y516070D01*
X999440Y516028D01*
G03X1002134I1347J-664D01*
G01X1002114Y516070D01*
Y518790D01*
X1002688D01*
Y518564D01*
X1002681Y518539D01*
G03X1005625Y518341I1453J-381D01*
G02X1006022Y518790I397J49D01*
G01X1009500D01*
Y515075D01*
X1009813Y514761D01*
X1009828Y514717D01*
G03X1012266Y514094I1422J483D01*
G02X1012817Y514083I270J-295D01*
G03X1015295Y514669I1056J1069D01*
G01X1015310Y514713D01*
X1015500Y514903D01*
Y518790D01*
X1017701D01*
X1018361Y518130D01*
Y510159D01*
X1017756Y509554D01*
X1015500D01*
Y510363D01*
X1015310Y510553D01*
X1015295Y510597D01*
G03X1012788Y511153I-1422J-483D01*
G02X1012211I-288J277D01*
G03X1009704Y510597I-1085J-1039D01*
G01X1009689Y510553D01*
X1009500Y510363D01*
Y509554D01*
X1005460D01*
Y513123D01*
X1005352Y513231D01*
X1005337Y513275D01*
G03X1002806Y511778I-1422J-484D01*
G01Y509554D01*
X998768D01*
Y512086D01*
X998788Y512128D01*
G03X996094I-1347J664D01*
G01X996114Y512086D01*
Y509554D01*
X995557D01*
Y509775D01*
X995562Y509796D01*
G03X992597Y509988I-1468J318D01*
G02X992199Y509554I-398J-34D01*
G01X989302D01*
G02X988903Y509963I1J400D01*
G03X985915Y509783I-1502J36D01*
G01X985917Y509768D01*
Y509554D01*
X985382D01*
Y512086D01*
X985402Y512128D01*
G03X982708I-1347J664D01*
G01X982728Y512086D01*
Y509554D01*
X978688D01*
Y512086D01*
X978709Y512128D01*
G03X976015I-1347J664D01*
G01X976036Y512086D01*
Y509554D01*
X975499D01*
Y509768D01*
X975501Y509783D01*
G03X972513Y509963I-1486J216D01*
G02X972114Y509554I-400J-9D01*
G01X969167D01*
G02X968769Y509989I0J400D01*
G03X965875I-1447J125D01*
G02X965477Y509554I-398J-35D01*
G01X962834D01*
X962125Y510263D01*
G37*
G36*
G01X961052Y492172D02*
Y496266D01*
X960068D01*
Y499981D01*
X960664Y500577D01*
X969719D01*
X970491Y499805D01*
Y496266D01*
X969526D01*
Y492172D01*
X961052D01*
G37*
G36*
G01X952974Y527430D02*
X952158Y528246D01*
Y533789D01*
G02X952848Y534065I400J0D01*
G03Y536135I1088J1035D01*
G02X952158Y536411I-290J276D01*
G01Y537239D01*
X952871Y537952D01*
X957814D01*
X958400Y537366D01*
Y530654D01*
G02X957957Y530257I-400J1D01*
G03X956657Y528059I-151J-1394D01*
G02X956330Y527430I-328J-229D01*
G01X952974D01*
G37*
G36*
G01Y565230D02*
X952158Y566046D01*
Y571589D01*
G02X952848Y571865I400J0D01*
G03Y573935I1088J1035D01*
G02X952158Y574211I-290J276D01*
G01Y575039D01*
X952871Y575752D01*
X957814D01*
X958400Y575166D01*
Y568498D01*
G02X957909Y568109I-400J0D01*
G03X956489Y565877I-317J-1366D01*
G02X956175Y565230I-314J-247D01*
G01X952974D01*
G37*
G36*
G01X961956Y547091D02*
Y547459D01*
X961965Y547489D01*
G03X960131Y549225I-1336J425D01*
G02X959589Y549598I-142J374D01*
G01Y549998D01*
X964202D01*
Y550498D01*
X965702D01*
Y553502D01*
X964202D01*
Y554002D01*
X959589D01*
Y556038D01*
X960104Y556553D01*
X962650D01*
Y556312D01*
X962640Y556282D01*
G03X965312I1336J-425D01*
G01X965302Y556312D01*
Y556553D01*
X969342D01*
Y556312D01*
X969333Y556282D01*
G03X972005I1336J-425D01*
G01X971996Y556312D01*
Y556553D01*
X972688D01*
Y556312D01*
X972679Y556282D01*
G03X975351I1336J-425D01*
G01X975342Y556312D01*
Y556553D01*
X979382D01*
Y556312D01*
X979372Y556282D01*
G03X982044I1336J-425D01*
G01X982034Y556312D01*
Y556553D01*
X982728D01*
Y556312D01*
X982719Y556282D01*
G03X985391I1336J-425D01*
G01X985382Y556312D01*
Y556553D01*
X989422D01*
Y556312D01*
X989412Y556282D01*
G03X992084I1336J-425D01*
G01X992074Y556312D01*
Y556553D01*
X992768D01*
Y556312D01*
X992758Y556282D01*
G03X995430I1336J-425D01*
G01X995420Y556312D01*
Y556553D01*
X999460D01*
Y556312D01*
X999451Y556282D01*
G03X1002123I1336J-425D01*
G01X1002114Y556312D01*
Y556553D01*
X1002806D01*
Y556309D01*
X1002797Y556280D01*
G03X1005469Y556285I1337J-423D01*
G01X1005460Y556315D01*
Y556553D01*
X1009500D01*
Y556307D01*
X1009491Y556279D01*
G03X1009665Y555029I1437J-437D01*
G02X1009329Y554412I-336J-217D01*
G01X1007669D01*
X1007636Y554425D01*
G03X1005758Y553299I-489J-1314D01*
G01X1005734Y553126D01*
X1005360D01*
Y554002D01*
X1000856D01*
Y553502D01*
X999356D01*
Y550498D01*
X1000856D01*
Y549998D01*
X1003269D01*
X1003469Y549798D01*
X1004861D01*
X1005450Y549210D01*
X1006625D01*
X1006658Y549197D01*
G03X1008461Y550022I489J1314D01*
G01X1008510Y550153D01*
X1008848D01*
Y549898D01*
X1013352D01*
Y550398D01*
X1014852D01*
Y553402D01*
X1013352D01*
Y553902D01*
X1010939D01*
X1010700Y554141D01*
X1010897Y554338D01*
X1010976Y554341D01*
G03X1012209Y555058I-48J1501D01*
G02X1012892I341J-208D01*
G03X1015655Y556088I1281J784D01*
G02X1016049Y556553I395J65D01*
G01X1018137D01*
X1018382Y556308D01*
X1018352Y556196D01*
G03X1019017Y554519I1448J-396D01*
G01X1019336Y554200D01*
X1023600D01*
X1023898Y553902D01*
Y549000D01*
X1021900D01*
X1020002Y547102D01*
X1018632D01*
Y547091D01*
X1015500D01*
Y548163D01*
X1015310Y548353D01*
X1015295Y548397D01*
G03X1012788Y548953I-1422J-483D01*
G02X1012211I-288J277D01*
G03X1009704Y548397I-1085J-1039D01*
G01X1009689Y548353D01*
X1009500Y548163D01*
Y547091D01*
X1005460D01*
Y547467D01*
X1005469Y547497D01*
G03X1002797I-1336J425D01*
G01X1002806Y547467D01*
Y547091D01*
X998768D01*
Y547467D01*
X998777Y547497D01*
G03X996105I-1336J425D01*
G01X996114Y547467D01*
Y547091D01*
X995420D01*
Y547467D01*
X995430Y547497D01*
G03X992758I-1336J425D01*
G01X992768Y547467D01*
Y547091D01*
X988728D01*
Y547459D01*
X988737Y547489D01*
G03X986065I-1336J425D01*
G01X986074Y547459D01*
Y547091D01*
X985382D01*
Y547462D01*
X985391Y547491D01*
G03Y548337I-1337J423D01*
G01X985382Y548366D01*
Y548462D01*
X985314Y548530D01*
X985299Y548558D01*
G03X982719Y547486I-1245J-645D01*
G01X982728Y547456D01*
Y547091D01*
X978688D01*
Y547459D01*
X978698Y547489D01*
G03X976026I-1336J425D01*
G01X976036Y547459D01*
Y547091D01*
X975342D01*
Y547459D01*
X975351Y547489D01*
G03X972679I-1336J425D01*
G01X972688Y547459D01*
Y547091D01*
X969074D01*
G02X968685Y547585I0J400D01*
G03X965959I-1363J329D01*
G02X965570Y547091I-389J-94D01*
G01X961956D01*
G37*
G36*
G01X1003127Y587798D02*
X1003420Y587506D01*
G02X1003358Y586890I-283J-283D01*
G03X1002797Y585297I775J-1168D01*
G01X1002806Y585267D01*
Y584812D01*
X998768D01*
Y585267D01*
X998777Y585297D01*
G03X996105I-1336J425D01*
G01X996114Y585267D01*
Y584812D01*
X995420D01*
Y585267D01*
X995430Y585297D01*
G03X992758I-1336J425D01*
G01X992768Y585267D01*
Y584812D01*
X988728D01*
Y585259D01*
X988737Y585289D01*
G03X986065I-1336J425D01*
G01X986074Y585259D01*
Y584812D01*
X985382D01*
Y585262D01*
X985391Y585291D01*
G03Y586137I-1337J423D01*
G01X985382Y586166D01*
Y586262D01*
X985314Y586330D01*
X985299Y586358D01*
G03X982719Y585286I-1245J-645D01*
G01X982728Y585256D01*
Y584812D01*
X978688D01*
Y585259D01*
X978698Y585289D01*
G03X976026I-1336J425D01*
G01X976036Y585259D01*
Y584812D01*
X975342D01*
Y585259D01*
X975351Y585289D01*
G03X972679I-1336J425D01*
G01X972688Y585259D01*
Y584812D01*
X969053D01*
G02X968668Y585323I-1J400D01*
G03X965976I-1346J391D01*
G02X965591Y584812I-384J-111D01*
G01X961956D01*
Y585259D01*
X961965Y585289D01*
G03X960131Y587025I-1336J425D01*
G02X959589Y587398I-142J374D01*
G01Y587798D01*
X964202D01*
Y588298D01*
X965702D01*
Y591302D01*
X964202D01*
Y591802D01*
X960281D01*
X959681Y592402D01*
X959589D01*
Y593838D01*
X960104Y594353D01*
X962650D01*
Y594112D01*
X962640Y594082D01*
G03X965312I1336J-425D01*
G01X965302Y594112D01*
Y594353D01*
X969342D01*
Y594112D01*
X969333Y594082D01*
G03X972005I1336J-425D01*
G01X971996Y594112D01*
Y594353D01*
X972688D01*
Y594112D01*
X972679Y594082D01*
G03X975351I1336J-425D01*
G01X975342Y594112D01*
Y594353D01*
X979382D01*
Y594112D01*
X979372Y594082D01*
G03X982044I1336J-425D01*
G01X982034Y594112D01*
Y594353D01*
X982728D01*
Y594112D01*
X982719Y594082D01*
G03X985391I1336J-425D01*
G01X985382Y594112D01*
Y594353D01*
X989422D01*
Y594112D01*
X989412Y594082D01*
G03X992084I1336J-425D01*
G01X992074Y594112D01*
Y594353D01*
X992768D01*
Y594112D01*
X992758Y594082D01*
G03X995430I1336J-425D01*
G01X995420Y594112D01*
Y594353D01*
X997913D01*
X997943Y594323D01*
X999005D01*
G02X999400Y593864I0J-400D01*
G03X1002174I1387J-207D01*
G02X1002569Y594323I395J59D01*
G01X1002801D01*
Y594093D01*
X1002793Y594065D01*
G03X1005521Y593864I1341J-408D01*
G02X1005916Y594323I395J59D01*
G01X1008400D01*
X1009000Y593723D01*
Y592218D01*
X1007040D01*
X1006999Y592236D01*
G03X1005280Y591802I-594J-1270D01*
G01X1000856D01*
Y591302D01*
X999356D01*
Y588298D01*
X1000856D01*
Y587798D01*
X1003127D01*
G37*
G36*
G01X960412Y527422D02*
X959589Y528245D01*
Y530648D01*
X964302D01*
Y531148D01*
X965802D01*
Y535052D01*
X964302D01*
Y535552D01*
X962243D01*
G02X961904Y536163I0J400D01*
G03X961681Y538029I-1275J794D01*
G02X961962Y538714I281J285D01*
G01X966136D01*
G02X966400Y538013I1J-400D01*
G03X968244I922J-1056D01*
G02X968508Y538714I263J301D01*
G01X972829D01*
G02X973093Y538013I1J-400D01*
G03X972852Y536175I922J-1056D01*
G02X972520Y535552I-332J-223D01*
G01X971998D01*
Y534502D01*
X970977D01*
G03Y531698I-35J-1402D01*
G01X971998D01*
Y530648D01*
X972702D01*
G02X972994Y529975I0J-400D01*
G03X972964Y528087I1021J-960D01*
G02X972664Y527422I-300J-265D01*
G01X972151D01*
G02X971839Y528073I0J400D01*
G03X969499I-1170J941D01*
G02X969187Y527422I-312J-251D01*
G01X960412D01*
G37*
G36*
G01X960554Y565080D02*
X959589Y566045D01*
Y568448D01*
X962529D01*
G02X962833Y567789I0J-400D01*
G03X962905Y565761I1143J-975D01*
G02X962620Y565080I-285J-281D01*
G01X960554D01*
G37*
G36*
G01X965047Y565761D02*
G03X964440Y568243I-1071J1053D01*
G01X964301Y568287D01*
Y568948D01*
X965802D01*
Y572852D01*
X964302D01*
Y573352D01*
X962243D01*
G02X961904Y573963I0J400D01*
G03X961679Y575831I-1275J794D01*
G02X961959Y576517I280J286D01*
G01X966140D01*
G02X966402Y575815I0J-400D01*
G03X968242I920J-1058D01*
G02X968504Y576517I262J302D01*
G01X972833D01*
G02X973095Y575815I0J-400D01*
G03X972852Y573975I920J-1058D01*
G02X972520Y573352I-332J-223D01*
G01X971998D01*
Y572302D01*
X970977D01*
G03Y569498I-35J-1402D01*
G01X971998D01*
Y568448D01*
X972702D01*
G02X972994Y567775I0J-400D01*
G03X973072Y565776I1021J-961D01*
G02X972804Y565080I-269J-296D01*
G01X971880D01*
G02X971612Y565776I1J400D01*
G03X969726I-943J1038D01*
G02X969458Y565080I-269J-296D01*
G01X965332D01*
G02X965047Y565761I0J400D01*
G37*
G36*
G01X975117Y27147D02*
G03X975036Y28975I-1102J867D01*
G02X975328Y29648I292J273D01*
G01X976502D01*
Y30148D01*
X978002D01*
Y34052D01*
X976502D01*
Y34698D01*
X976745D01*
X976784Y34680D01*
G03X978446Y36846I578J1277D01*
G02X978755Y37500I309J254D01*
G01X982662D01*
G02X982971Y36846I0J-400D01*
G03X984478Y34620I1084J-889D01*
G02X984998Y34239I120J-381D01*
G01Y33502D01*
X983935D01*
G03Y30698I-35J-1402D01*
G01X984998D01*
Y29648D01*
X989502D01*
Y30148D01*
X991002D01*
Y34052D01*
X989502D01*
Y34552D01*
X988896D01*
G02X988564Y35175I0J400D01*
G03X988485Y36846I-1163J782D01*
G02X988794Y37500I309J254D01*
G01X992701D01*
G02X993010Y36846I0J-400D01*
G03X995178I1084J-889D01*
G02X995487Y37500I309J254D01*
G01X996048D01*
G02X996357Y36846I0J-400D01*
G03X998525I1084J-889D01*
G02X998834Y37500I309J254D01*
G01X1002741D01*
G02X1003050Y36846I0J-400D01*
G03X1002971Y35175I1084J-889D01*
G02X1002639Y34552I-332J-223D01*
G01X1000856D01*
Y34052D01*
X999356D01*
Y30148D01*
X1000856D01*
Y29619D01*
G02X1000673Y29419I-200J-1D01*
G03X999690Y27149I114J-1397D01*
G02X999377Y26500I-313J-249D01*
G01X995504D01*
G02X995191Y27149I0J400D01*
G03X992997I-1097J873D01*
G02X992684Y26500I-313J-249D01*
G01X992158D01*
G02X991845Y27149I0J400D01*
G03X989651I-1097J873D01*
G02X989338Y26500I-313J-249D01*
G01X985470D01*
G02X985156Y27147I0J400D01*
G03X982952I-1102J867D01*
G02X982638Y26500I-314J-247D01*
G01X982124D01*
G02X981810Y27147I0J400D01*
G03X979606I-1102J867D01*
G02X979292Y26500I-314J-247D01*
G01X975431D01*
G02X975117Y27147I0J400D01*
G37*
G36*
G01X1005230Y27149D02*
G03X1005160Y28976I-1097J873D01*
G02X1005360Y29637I293J272D01*
G01Y29876D01*
G02X1005701Y30017I200J0D01*
G01X1006383Y29334D01*
X1008165D01*
G03X1009094Y29656I34J1402D01*
G02X1009748Y29347I254J-309D01*
G01Y29063D01*
X1009699Y29006D01*
G03X1009609Y27134I1127J-992D01*
G02X1009284Y26500I-324J-234D01*
G01X1005543D01*
G02X1005230Y27149I0J400D01*
G37*
G36*
G01X1016004Y8200D02*
G02X1015619Y8708I0J400D01*
G03X1012851Y9828I-1446J407D01*
G02X1012148I-352J190D01*
G03X1010768Y10615I-1322J-714D01*
G01X1010681Y10611D01*
X1010477Y10815D01*
X1010739Y11076D01*
X1013152D01*
Y11576D01*
X1014652D01*
Y14580D01*
X1013152D01*
Y15080D01*
X1008648D01*
Y14979D01*
X1008339D01*
X1008280Y15071D01*
G03X1006611Y15628I-1180J-757D01*
G01X1006578Y15616D01*
X1005604D01*
G02X1005278Y16247I0J400D01*
G03X1005532Y17168I-1144J811D01*
G02X1005930Y17600I399J32D01*
G01X1010592D01*
X1010774Y17159D01*
X1010771Y17112D01*
G03X1013327Y15947I1499J-98D01*
G02X1013884Y15953I282J-284D01*
G03X1015946Y15946I1035J1089D01*
G02X1016492I273J-292D01*
G03X1018446Y15860I1027J1096D01*
G01X1018501Y15903D01*
X1018686D01*
X1019337Y15252D01*
X1019384D01*
X1019410Y15225D01*
X1024217D01*
X1024398Y15044D01*
Y10608D01*
X1024303Y10513D01*
X1020761D01*
X1020353Y10105D01*
X1018564D01*
X1018470Y10011D01*
Y8370D01*
X1018300Y8200D01*
X1016004D01*
G37*
G36*
G01X1026247Y15580D02*
Y15831D01*
X1025825Y16253D01*
X1019752D01*
X1019500Y16505D01*
Y17806D01*
X1019757Y18063D01*
Y18546D01*
X1019500Y18803D01*
Y24800D01*
X1020200Y25500D01*
X1025500D01*
Y29476D01*
X1026798D01*
Y28976D01*
X1029098D01*
Y26899D01*
G03X1028898Y26150I1303J-749D01*
G01Y22578D01*
X1029388Y22088D01*
G03X1029718Y21839I1061J1063D01*
G01Y16080D01*
X1026898D01*
Y15580D01*
X1026247D01*
G37*
G36*
G01X1027910Y66665D02*
X1027385Y67190D01*
Y69658D01*
X1027302Y69742D01*
Y71602D01*
X1025442D01*
X1024068Y72975D01*
X1023380D01*
X1022850Y73505D01*
Y77600D01*
X1023500Y78250D01*
X1024658D01*
X1029718Y73190D01*
Y66665D01*
X1027910D01*
G37*
G36*
G01X1005460Y46200D02*
Y46467D01*
X1005469Y46497D01*
G03X1005331Y47650I-1336J425D01*
G02X1005673Y48258I342J208D01*
G01X1006830D01*
X1006863Y48246D01*
G03X1007370Y48158I506J1413D01*
G01X1009421D01*
G02X1009780Y47580I0J-400D01*
G03X1009704Y47397I1346J-666D01*
G01X1009689Y47353D01*
X1009500Y47163D01*
Y46200D01*
X1005460D01*
G37*
G36*
G01X1006865Y33676D02*
G02X1006194Y33488I-388J95D01*
G01X1006181Y33502D01*
X1005360D01*
Y34552D01*
X1005189D01*
X1005057Y34902D01*
G03X1005218Y36846I-923J1055D01*
G02X1005527Y37500I309J254D01*
G01X1009317D01*
G02X1009634Y36857I0J-400D01*
G03X1009502Y35232I1192J-915D01*
G02X1009150Y34644I-353J-188D01*
G01X1008749D01*
X1008716Y34656D01*
G03X1006865Y33676I-489J-1314D01*
G37*
G36*
G01X975568Y64500D02*
G02X975223Y65103I0J400D01*
G03X975036Y66775I-1208J711D01*
G02X975328Y67448I292J273D01*
G01X976502D01*
Y67948D01*
X978002D01*
Y71852D01*
X976502D01*
Y72498D01*
X976745D01*
X976784Y72480D01*
G03X978505Y74569I578J1277D01*
G02X978831Y75200I326J231D01*
G01X982586D01*
G02X982912Y74569I0J-400D01*
G03X984478Y72420I1143J-812D01*
G02X984998Y72039I120J-381D01*
G01Y71202D01*
X984422D01*
X984389Y71214D01*
G03Y68586I-489J-1314D01*
G01X984422Y68598D01*
X984998D01*
Y67448D01*
X989502D01*
Y67948D01*
X991002D01*
Y71852D01*
X989502D01*
Y72352D01*
X988896D01*
G02X988564Y72975I0J400D01*
G03X988544Y74569I-1163J783D01*
G02X988870Y75200I326J231D01*
G01X992625D01*
G02X992951Y74569I0J-400D01*
G03X995237I1143J-812D01*
G02X995563Y75200I326J231D01*
G01X995972D01*
G02X996298Y74569I0J-400D01*
G03X998584I1143J-812D01*
G02X998910Y75200I326J231D01*
G01X1002665D01*
G02X1002991Y74569I0J-400D01*
G03X1002971Y72975I1143J-811D01*
G02X1002639Y72352I-332J-223D01*
G01X1000856D01*
Y71852D01*
X999356D01*
Y67948D01*
X1000856D01*
Y67419D01*
G02X1000673Y67219I-200J-1D01*
G03X999582Y65105I114J-1397D01*
G02X999239Y64500I-343J-205D01*
G01X995642D01*
G02X995299Y65105I0J400D01*
G03X992889I-1205J717D01*
G02X992546Y64500I-343J-205D01*
G01X992296D01*
G02X991953Y65105I0J400D01*
G03X989543I-1205J717D01*
G02X989200Y64500I-343J-205D01*
G01X985607D01*
G02X985262Y65103I0J400D01*
G03X982846I-1208J711D01*
G02X982501Y64500I-345J-203D01*
G01X982261D01*
G02X981916Y65103I0J400D01*
G03X979500I-1208J711D01*
G02X979155Y64500I-345J-203D01*
G01X975568D01*
G37*
G36*
G01X1030150Y42227D02*
Y39942D01*
X1029718Y39511D01*
Y34980D01*
X1026798D01*
Y34480D01*
X1025500D01*
Y35400D01*
X1022300Y38600D01*
X1020500D01*
X1019500Y39600D01*
Y47335D01*
X1020087Y47922D01*
X1023088D01*
X1023564Y48398D01*
X1024102D01*
Y48898D01*
X1026098D01*
Y48398D01*
X1027098D01*
Y45278D01*
X1030150Y42227D01*
G37*
G36*
G01X1031418Y62189D02*
Y58239D01*
X1030968Y57788D01*
X1030850Y57828D01*
G03X1029816Y55226I-449J-1328D01*
G01Y54402D01*
X1026098D01*
Y53902D01*
X1024102D01*
Y54402D01*
X1023626D01*
Y55159D01*
X1022300Y56485D01*
X1020349D01*
X1019508Y57326D01*
X1019500D01*
Y63600D01*
X1019800Y63900D01*
X1029718D01*
Y63889D01*
X1031418Y62189D01*
G37*
G36*
G01X1020300Y76100D02*
X1019900Y76500D01*
Y101200D01*
X1020100Y101400D01*
X1024200D01*
X1024500Y101700D01*
Y102282D01*
X1024552D01*
Y104852D01*
X1024700Y105000D01*
X1028700D01*
X1029800Y106100D01*
X1033000D01*
X1033198Y105902D01*
Y101998D01*
X1033200D01*
Y98192D01*
X1029018Y94011D01*
Y79150D01*
X1025174D01*
X1025073Y79252D01*
X1023085D01*
X1023034Y79200D01*
X1022550D01*
X1021800Y78450D01*
Y76500D01*
X1021400Y76100D01*
X1020300D01*
G37*
G36*
G01X976910Y105621D02*
G03I-700J0D01*
G37*
G36*
G01X1029591Y269059D02*
X1029066Y269584D01*
Y275024D01*
X1027251Y276839D01*
X1017098D01*
X1015139Y278798D01*
Y284163D01*
X1015384Y284408D01*
X1020410D01*
Y284476D01*
X1022608D01*
Y284408D01*
X1027610D01*
Y284476D01*
X1029808D01*
Y284408D01*
X1034810D01*
Y284476D01*
X1037008D01*
Y284408D01*
X1042010D01*
Y284476D01*
X1044208D01*
Y284408D01*
X1049210D01*
Y284476D01*
X1051408D01*
Y284408D01*
X1056410D01*
Y284476D01*
X1058608D01*
Y284408D01*
X1063610D01*
Y284476D01*
X1065808D01*
Y284408D01*
X1070810D01*
Y284476D01*
X1073008D01*
Y284408D01*
X1078010D01*
Y284476D01*
X1080208D01*
Y284408D01*
X1085210D01*
Y284476D01*
X1087408D01*
Y284408D01*
X1092410D01*
Y284476D01*
X1092707D01*
X1093177Y284006D01*
Y277342D01*
X1091754D01*
Y272210D01*
X1087756D01*
X1086600Y273366D01*
X1086210D01*
Y273412D01*
X1081208D01*
Y273366D01*
X1079010D01*
Y273412D01*
X1074008D01*
Y273366D01*
X1071810D01*
Y273412D01*
X1066808D01*
Y273366D01*
X1064610D01*
Y273412D01*
X1059608D01*
Y273366D01*
X1057410D01*
Y273412D01*
X1052408D01*
Y273366D01*
X1050158D01*
Y273442D01*
X1044967D01*
Y275233D01*
X1044096Y276104D01*
X1037165D01*
X1036226Y275164D01*
Y274542D01*
X1036054D01*
Y269540D01*
X1036158D01*
X1036260Y269293D01*
X1036026Y269059D01*
X1029591D01*
G37*
G36*
G01X1031443Y318415D02*
X1031300Y318558D01*
Y324200D01*
X1033200Y326100D01*
X1035400D01*
X1036508Y327208D01*
X1037566D01*
Y331566D01*
X1038200Y332200D01*
X1039684D01*
X1040044Y331840D01*
X1041960D01*
X1043454Y330346D01*
Y329940D01*
X1043860D01*
X1043900Y329900D01*
X1084656D01*
X1086398Y328158D01*
Y327798D01*
X1091602D01*
X1094535Y324865D01*
X1107064D01*
X1109603Y322326D01*
X1111018D01*
X1111267Y322077D01*
Y320302D01*
X1109298D01*
Y320079D01*
X1107758D01*
Y320342D01*
X1102754D01*
Y319972D01*
X1101197Y318415D01*
X1031443D01*
G37*
G36*
G01X1014819Y310868D02*
X1014185Y311502D01*
Y316940D01*
X1015509Y318264D01*
X1018254D01*
Y317840D01*
X1023258D01*
Y318264D01*
X1024754D01*
Y317840D01*
X1029867D01*
Y311869D01*
X1029414Y311416D01*
X1028189D01*
G03X1028083I-53J-1601D01*
G01X1024687D01*
X1024656Y311427D01*
G03X1023624I-516J-1517D01*
G01X1023593Y311416D01*
X1017630D01*
X1017599Y311427D01*
G03X1016567I-516J-1517D01*
G01X1016536Y311416D01*
X1016336D01*
X1016073Y311154D01*
X1016066Y311148D01*
G03X1015841Y310922I1017J-1238D01*
G01X1015787Y310868D01*
X1014819D01*
G37*
G36*
G01X1108754Y309240D02*
X1108812D01*
Y308242D01*
X1108754D01*
Y306240D01*
X1108812D01*
Y305102D01*
X1108698D01*
Y303098D01*
X1108812D01*
Y302102D01*
X1108798D01*
Y300098D01*
X1108812D01*
Y299102D01*
X1108798D01*
Y297098D01*
X1108812D01*
Y295502D01*
X1108798D01*
Y293498D01*
X1108812D01*
Y290342D01*
X1108754D01*
Y288340D01*
X1108812D01*
Y287142D01*
X1108754D01*
Y285140D01*
X1108812D01*
Y283942D01*
X1108754D01*
Y282070D01*
X1108521Y281837D01*
X1107190D01*
X1106732Y282295D01*
Y285748D01*
X1105982Y286498D01*
X1105258D01*
Y286592D01*
X1102254D01*
Y286498D01*
X1099758D01*
Y287342D01*
X1094860D01*
X1094747Y287455D01*
Y288131D01*
X1094902Y288285D01*
Y293476D01*
X1094948Y293522D01*
Y293806D01*
X1094030Y294724D01*
X1093992D01*
X1093715Y295002D01*
X1059985D01*
X1059708Y294724D01*
X1016510D01*
X1015272Y295962D01*
Y301408D01*
X1020410D01*
Y301443D01*
X1022608D01*
Y301408D01*
X1027610D01*
Y301443D01*
X1029808D01*
Y301408D01*
X1034810D01*
Y301443D01*
X1037008D01*
Y301408D01*
X1042010D01*
Y301443D01*
X1044208D01*
Y301408D01*
X1049210D01*
Y301443D01*
X1051408D01*
Y301408D01*
X1056410D01*
Y301443D01*
X1058608D01*
Y301408D01*
X1063610D01*
Y301443D01*
X1065808D01*
Y301408D01*
X1070810D01*
Y301443D01*
X1073008D01*
Y301408D01*
X1078010D01*
Y301443D01*
X1080208D01*
Y301408D01*
X1085210D01*
Y301443D01*
X1087408D01*
Y301408D01*
X1092410D01*
Y301443D01*
X1094754D01*
Y301340D01*
X1099758D01*
Y301443D01*
X1102254D01*
Y300840D01*
X1105258D01*
Y301356D01*
X1105977Y302076D01*
Y311585D01*
X1107231Y312839D01*
X1108396D01*
X1109020Y313463D01*
Y315377D01*
X1109769Y316126D01*
X1112807D01*
X1113265Y315668D01*
Y312590D01*
X1112640Y311965D01*
X1109436D01*
X1108812Y311341D01*
Y311242D01*
X1108754D01*
Y309240D01*
G37*
G36*
G01X1016937Y343500D02*
X1019400D01*
X1020476Y344576D01*
X1022197D01*
X1024267Y342506D01*
X1033376D01*
X1034472Y343602D01*
X1035288D01*
X1037882Y346196D01*
X1039543D01*
X1040859Y347512D01*
X1053065D01*
G02X1053465Y347087I0J-400D01*
G03X1055557Y348302I1449J-87D01*
G02X1055451Y348943I177J359D01*
G01X1057108Y350600D01*
X1059524D01*
G03X1061864I1170J860D01*
G01X1095400D01*
X1103100Y342900D01*
Y340000D01*
X1101100Y338000D01*
X1100894D01*
X1100834Y338080D01*
G03X1097891Y338000I-1443J-1079D01*
G01X1095700D01*
X1090500Y332800D01*
Y330802D01*
X1086800D01*
Y331200D01*
X1086272Y331728D01*
Y336764D01*
X1085098Y337938D01*
X1082659D01*
X1082499Y338098D01*
Y339697D01*
X1081296Y340900D01*
X1081154D01*
X1081053Y341002D01*
X1053544D01*
X1053443Y340900D01*
X1042600D01*
X1042580Y340880D01*
X1042464D01*
X1041884Y340300D01*
X1037600D01*
X1030500Y333200D01*
X1005400D01*
X1004600Y334000D01*
X1008920Y338320D01*
X1008981Y338331D01*
G03X1010154Y339504I-256J1429D01*
G01X1010165Y339565D01*
X1011179Y340579D01*
X1011315Y340491D01*
G03X1013466Y342214I790J1218D01*
G01X1013422Y342334D01*
X1013810Y342722D01*
G02X1014393Y342703I283J-283D01*
G03X1016902Y343344I1092J957D01*
G01X1016937Y343500D01*
G37*
G36*
G01X1038100Y490000D02*
X1036400D01*
X1033002Y493398D01*
Y507502D01*
X1033900Y508400D01*
X1034800D01*
X1036000Y507200D01*
X1036100D01*
X1041800Y501500D01*
Y500100D01*
X1043798Y498102D01*
Y493698D01*
X1043800D01*
Y493200D01*
X1043102Y492502D01*
X1039900D01*
G03X1039835Y492500I17J-1601D01*
G01X1039100D01*
X1038300Y491700D01*
Y490965D01*
G03Y490835I1600J-65D01*
G01Y490200D01*
X1038100Y490000D01*
G37*
G36*
G01X1022900Y492600D02*
X1021700Y493800D01*
Y497400D01*
X1021552Y497548D01*
Y498552D01*
X1020548D01*
X1020102Y498998D01*
Y499315D01*
X1019634Y499782D01*
Y526300D01*
X1020234Y526900D01*
X1028300D01*
X1030807Y529407D01*
G02X1031148Y529266I141J-141D01*
G01Y528733D01*
X1029148Y526733D01*
Y525648D01*
X1027650Y524150D01*
Y498550D01*
X1026200Y497100D01*
Y493600D01*
X1025200Y492600D01*
X1022900D01*
G37*
G36*
G01X1026302Y568161D02*
Y573280D01*
X1026172D01*
Y573581D01*
X1025322Y574431D01*
Y578200D01*
X1025822Y578700D01*
X1027468D01*
X1027668Y578500D01*
Y577667D01*
X1030419Y574916D01*
Y568727D01*
X1029853Y568161D01*
X1026302D01*
G37*
G36*
G01X1025404Y541448D02*
X1025865Y541909D01*
X1027103D01*
X1030703Y538309D01*
Y530846D01*
X1030359Y530502D01*
X1027467D01*
X1026840Y531129D01*
Y536044D01*
X1025404Y537480D01*
Y541448D01*
G37*
G36*
G01X1019120Y584560D02*
X1017874Y585806D01*
X1017866Y585875D01*
G03X1016634Y587107I-1393J-161D01*
G01X1016565Y587115D01*
X1015980Y587700D01*
X1014050D01*
X1013552Y588198D01*
Y591222D01*
X1013940Y591610D01*
X1015210D01*
X1016420Y592820D01*
Y593591D01*
G03Y593693I-1501J51D01*
G01Y594570D01*
X1016500Y594650D01*
X1018450D01*
X1018924Y594176D01*
X1018895Y594066D01*
G03X1020666Y592295I1405J-366D01*
G01X1020776Y592324D01*
X1021790Y591310D01*
Y586470D01*
X1019996Y584676D01*
X1019366D01*
Y584662D01*
X1019120Y584560D01*
G37*
G36*
G01X1005460Y584812D02*
Y585267D01*
X1005469Y585297D01*
G03X1005372Y586378I-1336J425D01*
G02X1005726Y586964I354J186D01*
G01X1006371D01*
G03X1007639Y587698I35J1402D01*
G01X1009000D01*
Y585813D01*
X1007999Y584812D01*
X1005460D01*
G37*
G36*
G01X1005298Y528074D02*
G03X1005525Y529585I-1165J948D01*
G02X1005896Y530136I371J151D01*
G01X1007169D01*
X1007172Y530135D01*
G03X1008521Y532026I35J1402D01*
G01X1008508Y532059D01*
Y533615D01*
X1008521Y533648D01*
G03X1005893I-1314J489D01*
G01X1005906Y533615D01*
Y532938D01*
X1005360D01*
Y535552D01*
X1005189D01*
X1005057Y535902D01*
G03X1005056Y538013I-923J1055D01*
G02X1005320Y538714I263J301D01*
G01X1018122D01*
X1019255Y537581D01*
X1022410D01*
X1023381Y536610D01*
Y531676D01*
X1021439Y529734D01*
X1019821D01*
X1018770Y528683D01*
Y527954D01*
X1018238Y527422D01*
X1014661D01*
G02X1014403Y528128I0J400D01*
G03X1014814Y529689I-903J1072D01*
G01X1014802Y529722D01*
Y529939D01*
X1014575Y530166D01*
G02X1014858Y530848I283J282D01*
G01X1015252D01*
Y534752D01*
X1013752D01*
Y535252D01*
X1009248D01*
Y530348D01*
X1010711D01*
X1012122Y528938D01*
X1012134Y528882D01*
G03X1012597Y528128I1365J319D01*
G02X1012339Y527422I-258J-306D01*
G01X1005609D01*
G02X1005298Y528074I0J400D01*
G37*
G36*
G01X975066Y528087D02*
G03X975036Y529975I-1051J928D01*
G02X975328Y530648I292J273D01*
G01X976502D01*
Y531148D01*
X978002D01*
Y535052D01*
X976502D01*
Y535698D01*
X976745D01*
X976784Y535680D01*
G03X978284Y538013I578J1277D01*
G02X978548Y538714I263J301D01*
G01X982869D01*
G02X983133Y538013I1J-400D01*
G03X984478Y535620I922J-1056D01*
G02X984998Y535239I120J-381D01*
G01Y534502D01*
X983935D01*
G03Y531698I-35J-1402D01*
G01X984998D01*
Y530836D01*
G02X984484Y530453I-400J0D01*
G03X982884Y528073I-430J-1439D01*
G02X982572Y527422I-312J-251D01*
G01X982059D01*
G02X981759Y528087I0J400D01*
G03X979657I-1051J927D01*
G02X979357Y527422I-300J-265D01*
G01X975366D01*
G02X975066Y528087I0J400D01*
G37*
G36*
G01X985224Y528073D02*
G03X985197Y529989I-1170J942D01*
G02X985501Y530648I304J259D01*
G01X989502D01*
Y531148D01*
X991002D01*
Y535052D01*
X989502D01*
Y535552D01*
X988896D01*
G02X988564Y536175I0J400D01*
G03X988323Y538013I-1163J782D01*
G02X988587Y538714I263J301D01*
G01X992908D01*
G02X993172Y538013I1J-400D01*
G03X995016I922J-1056D01*
G02X995280Y538714I263J301D01*
G01X996255D01*
G02X996519Y538013I1J-400D01*
G03X998363I922J-1056D01*
G02X998627Y538714I263J301D01*
G01X1002948D01*
G02X1003212Y538013I1J-400D01*
G03X1002971Y536175I922J-1056D01*
G02X1002639Y535552I-332J-223D01*
G01X1000856D01*
Y535052D01*
X999356D01*
Y531148D01*
X1000856D01*
Y530619D01*
G02X1000673Y530419I-200J-1D01*
G03X999741Y528088I114J-1397D01*
G02X999443Y527422I-298J-266D01*
G01X995570D01*
G02X995259Y528074I0J400D01*
G03X992929I-1165J948D01*
G02X992618Y527422I-311J-252D01*
G01X992092D01*
G02X991794Y528088I0J400D01*
G03X989702I-1046J934D01*
G02X989404Y527422I-298J-266D01*
G01X985536D01*
G02X985224Y528073I0J400D01*
G37*
G36*
G01X1015244Y565761D02*
G03X1014802Y568178I-1071J1053D01*
G01Y572352D01*
X1013302D01*
Y572852D01*
X1012007D01*
G02X1011759Y573565I1J400D01*
G03X1012148Y574028I-932J1178D01*
G02X1012851I352J-190D01*
G03X1015211Y575828I1321J715D01*
G02X1015487Y576517I276J289D01*
G01X1017936D01*
X1019659Y574794D01*
X1021925D01*
X1023340Y573379D01*
X1023298Y573280D01*
Y568276D01*
X1023542D01*
Y567109D01*
X1022571Y566138D01*
X1019093D01*
X1018035Y565080D01*
X1015529D01*
G02X1015244Y565761I0J400D01*
G37*
G36*
G01X974958Y565776D02*
G03X975036Y567775I-943J1038D01*
G02X975328Y568448I292J273D01*
G01X976502D01*
Y568948D01*
X978002D01*
Y572852D01*
X976502D01*
Y573498D01*
X976745D01*
X976784Y573480D01*
G03X978282Y575815I578J1277D01*
G02X978544Y576517I262J302D01*
G01X982873D01*
G02X983135Y575815I0J-400D01*
G03X984478Y573420I920J-1058D01*
G02X984998Y573039I120J-381D01*
G01Y572302D01*
X983935D01*
G03Y569498I-35J-1402D01*
G01X984998D01*
Y568448D01*
X989502D01*
Y568948D01*
X991002D01*
Y572852D01*
X989502D01*
Y573352D01*
X989015D01*
G02X988676Y573963I0J400D01*
G03X988451Y575831I-1275J794D01*
G02X988731Y576517I280J286D01*
G01X992912D01*
G02X993174Y575815I0J-400D01*
G03X995014I920J-1058D01*
G02X995276Y576517I262J302D01*
G01X996111D01*
G02X996391Y575831I0J-400D01*
G03X998491I1050J-1074D01*
G02X998771Y576517I280J286D01*
G01X1002952D01*
G02X1003214Y575815I0J-400D01*
G03X1002971Y573975I920J-1058D01*
G02X1002639Y573352I-332J-223D01*
G01X1000856D01*
Y572852D01*
X999356D01*
Y568948D01*
X1000856D01*
Y568419D01*
G02X1000673Y568219I-200J-1D01*
G03X999851Y565778I114J-1397D01*
G02X999584Y565080I-267J-298D01*
G01X995297D01*
G02X995030Y565778I0J400D01*
G03X993158I-936J1044D01*
G02X992891Y565080I-267J-298D01*
G01X991951D01*
G02X991684Y565778I0J400D01*
G03X989812I-936J1044D01*
G02X989545Y565080I-267J-298D01*
G01X985265D01*
G02X984997Y565776I1J400D01*
G03X983111I-943J1038D01*
G02X982843Y565080I-269J-296D01*
G01X981919D01*
G02X981651Y565776I1J400D01*
G03X979765I-943J1038D01*
G02X979497Y565080I-269J-296D01*
G01X975226D01*
G02X974958Y565776I1J400D01*
G37*
G36*
G01X1005069Y565778D02*
G03X1005394Y567434I-936J1044D01*
G02X1005754Y568008I360J174D01*
G01X1007297D01*
G03X1008162Y568280I34J1402D01*
G02X1008798Y567958I236J-323D01*
G01Y567948D01*
X1009072D01*
G02X1009441Y567394I0J-400D01*
G03X1009755Y565761I1385J-580D01*
G02X1009470Y565080I-285J-281D01*
G01X1005336D01*
G02X1005069Y565778I0J400D01*
G37*
G36*
G01X1005360Y570812D02*
Y573352D01*
X1005189D01*
X1005057Y573702D01*
G03X1005054Y575815I-923J1055D01*
G02X1005316Y576517I262J302D01*
G01X1009512D01*
G02X1009788Y575828I0J-400D01*
G03X1009564Y573928I1038J-1086D01*
G02X1009227Y573312I-336J-216D01*
G01X1007854D01*
X1007821Y573324D01*
G03X1006018Y571521I-489J-1314D01*
G01X1006030Y571488D01*
Y570812D01*
X1005360D01*
G37*
G36*
G01X1020334Y539300D02*
X1019634Y540000D01*
Y546100D01*
X1023600D01*
X1025100Y544600D01*
X1030400D01*
X1030466Y544666D01*
G02X1031148Y544383I282J-283D01*
G01Y542417D01*
G02X1030466Y542134I-400J0D01*
G01X1029900Y542700D01*
X1027728D01*
X1027518Y542910D01*
X1025450D01*
X1024402Y541863D01*
Y541602D01*
X1022100Y539300D01*
X1020334D01*
G37*
G36*
G01X1031148Y555700D02*
X1023900D01*
X1022200Y557400D01*
X1019934D01*
X1019634Y557700D01*
Y564534D01*
X1019800Y564700D01*
X1029600D01*
X1030466Y565566D01*
G02X1031148Y565283I282J-283D01*
G01Y562448D01*
X1031100Y562400D01*
Y557100D01*
X1031148Y557052D01*
Y555700D01*
G37*
G36*
G01X1084002Y-17718D02*
Y-12100D01*
X1094100D01*
X1095002Y-11198D01*
X1095041Y-11183D01*
G03X1095885Y-10339I-553J1397D01*
G01X1095900Y-10300D01*
X1096300Y-9900D01*
Y-4000D01*
X1099400Y-900D01*
X1119600D01*
X1122700Y-4000D01*
Y-16500D01*
X1121482Y-17718D01*
X1084002D01*
G37*
G36*
G01X1069736Y-7813D02*
G03X1071809Y-5805I1326J705D01*
G02X1071725Y-5175I199J347D01*
G01X1072200Y-4700D01*
Y-4618D01*
X1072276Y-4541D01*
Y-2701D01*
G03X1072555Y-1651I-1214J885D01*
G01X1072544Y-1556D01*
X1073400Y-700D01*
X1075965D01*
G02X1076341Y-1235I0J-400D01*
G03X1079169I1414J-508D01*
G02X1079545Y-700I376J135D01*
G01X1082658D01*
G02X1083034Y-1235I0J-400D01*
G03X1085862I1414J-508D01*
G02X1086238Y-700I376J135D01*
G01X1091800D01*
X1092800Y-1700D01*
Y-10200D01*
X1092400Y-10600D01*
X1089651D01*
G02X1089261Y-10113I0J400D01*
G03X1086329I-1466J327D01*
G02X1085939Y-10600I-390J-87D01*
G01X1082980D01*
G02X1082585Y-10137I0J400D01*
G03X1079619I-1483J236D01*
G02X1079224Y-10600I-395J-63D01*
G01X1076265D01*
G02X1075875Y-10113I0J400D01*
G03X1073020Y-10357I-1466J327D01*
G01X1073070Y-10480D01*
X1072750Y-10800D01*
X1056100D01*
X1055738Y-10438D01*
X1055771Y-10324D01*
G03X1052847Y-10137I-1441J423D01*
G02X1052452Y-10600I-395J-63D01*
G01X1050700D01*
X1050300Y-10200D01*
Y-6518D01*
X1050603Y-6214D01*
X1051497D01*
X1053197Y-7914D01*
X1055603D01*
X1055744Y-7773D01*
G02X1056374Y-7857I283J-283D01*
G03X1059044Y-7727I1302J749D01*
G02X1059692Y-7609I365J-165D01*
G01X1059897Y-7814D01*
X1062703D01*
X1062876Y-7642D01*
X1063037Y-7804D01*
X1063051Y-7829D01*
G03X1065658Y-7879I1318J721D01*
G02X1066284Y-7802I343J-206D01*
G01X1066297Y-7814D01*
X1069003D01*
X1069100Y-7718D01*
G02X1069736Y-7813I283J-283D01*
G37*
G36*
G01X1049439Y27000D02*
G02X1049060Y27528I0J400D01*
G03X1046179Y27646I-1423J479D01*
G01X1046206Y27536D01*
X1045985Y27315D01*
X1045700Y27600D01*
Y36800D01*
X1046600Y37700D01*
X1049784D01*
G02X1050050Y37002I-1J-400D01*
G03X1051507Y34656I935J-1045D01*
G02X1052056Y34285I149J-371D01*
G01Y34052D01*
X1050556D01*
Y30148D01*
X1052056D01*
Y29648D01*
X1053011D01*
G02X1053304Y28976I0J-400D01*
G03X1053015Y27538I1027J-954D01*
G02X1052640Y27000I-375J-138D01*
G01X1049439D01*
G37*
G36*
G01X1055534Y27303D02*
G03X1055358Y28976I-1203J719D01*
G02X1055651Y29648I293J272D01*
G01X1056560D01*
Y30848D01*
X1057158D01*
X1057199Y30830D01*
G03Y33370I593J1270D01*
G01X1057158Y33352D01*
X1056560D01*
Y34552D01*
X1055826D01*
G02X1055494Y35175I0J400D01*
G03X1055266Y37002I-1163J783D01*
G02X1055532Y37700I267J298D01*
G01X1059823D01*
G02X1060089Y37002I-1J-400D01*
G03X1061959I935J-1045D01*
G02X1062225Y37700I267J298D01*
G01X1063170D01*
G02X1063436Y37002I-1J-400D01*
G03X1064315Y34556I935J-1045D01*
G02X1064506Y34356I-9J-200D01*
G01Y34052D01*
X1063006D01*
Y30148D01*
X1064506D01*
Y29623D01*
G02X1064315Y29423I-200J0D01*
G03X1063055Y27538I56J-1401D01*
G02X1062680Y27000I-375J-138D01*
G01X1059479D01*
G02X1059100Y27528I0J400D01*
G03X1056254I-1423J479D01*
G02X1055875Y27000I-379J-128D01*
G01X1055706D01*
G02X1055534Y27303I0J200D01*
G37*
G36*
G01X1066062Y27000D02*
G02X1065687Y27538I0J400D01*
G03X1065398Y28976I-1316J484D01*
G02X1065691Y29648I293J272D01*
G01X1069010D01*
Y30848D01*
X1070342D01*
X1070383Y30830D01*
G03Y33370I593J1270D01*
G01X1070342Y33352D01*
X1069010D01*
Y34552D01*
X1065866D01*
G02X1065534Y35175I0J400D01*
G03X1065306Y37002I-1163J783D01*
G02X1065572Y37700I267J298D01*
G01X1076556D01*
G02X1076822Y37002I-1J-400D01*
G03X1077363Y34612I935J-1045D01*
G01X1077506Y34569D01*
Y34052D01*
X1076006D01*
Y30148D01*
X1077506D01*
Y29648D01*
X1079661D01*
G02X1079964Y28987I0J-400D01*
G03X1079679Y27528I1138J-980D01*
G02X1079300Y27000I-379J-128D01*
G01X1076211D01*
G02X1075832Y27528I0J400D01*
G03X1072986I-1423J479D01*
G02X1072607Y27000I-379J-128D01*
G01X1072439D01*
G02X1072267Y27303I0J200D01*
G03X1069748Y27538I-1203J719D01*
G02X1069373Y27000I-375J-138D01*
G01X1066062D01*
G37*
G36*
G01X1082904D02*
G02X1082525Y27528I0J400D01*
G03X1081901Y29279I-1423J479D01*
G01X1081807Y29338D01*
Y29648D01*
X1082010D01*
Y30848D01*
X1082482D01*
X1082523Y30830D01*
G03Y33370I593J1270D01*
G01X1082482Y33352D01*
X1082010D01*
Y34552D01*
X1079252D01*
G02X1078920Y35175I0J400D01*
G03X1078692Y37002I-1163J783D01*
G02X1078958Y37700I267J298D01*
G01X1083249D01*
G02X1083515Y37002I-1J-400D01*
G03X1085385I935J-1045D01*
G02X1085651Y37700I267J298D01*
G01X1086596D01*
G02X1086862Y37002I-1J-400D01*
G03X1088732I935J-1045D01*
G02X1088998Y37700I267J298D01*
G01X1091500D01*
X1092600Y36600D01*
Y34552D01*
X1089864D01*
Y34052D01*
X1088364D01*
Y30148D01*
X1089864D01*
Y29648D01*
X1092600D01*
Y28300D01*
X1091300Y27000D01*
X1089488D01*
G02X1089113Y27538I0J400D01*
G03X1086481I-1316J484D01*
G02X1086106Y27000I-375J-138D01*
G01X1082904D01*
G37*
G36*
G01X1093300Y11198D02*
Y10000D01*
X1091600Y8300D01*
X1089122D01*
Y8661D01*
X1089131Y8691D01*
G03X1086552Y9766I-1334J430D01*
G01X1086537Y9738D01*
X1086468Y9669D01*
Y9571D01*
X1086459Y9542D01*
G03Y8702I1338J-420D01*
G01X1086468Y8673D01*
Y8300D01*
X1085774D01*
Y8661D01*
X1085784Y8691D01*
G03X1083205Y9766I-1334J430D01*
G01X1083190Y9738D01*
X1083122Y9669D01*
Y9571D01*
X1083112Y9542D01*
G03Y8702I1338J-420D01*
G01X1083122Y8673D01*
Y8300D01*
X1079082D01*
Y8661D01*
X1079091Y8691D01*
G03X1076512Y9766I-1334J430D01*
G01X1076497Y9738D01*
X1076428Y9669D01*
Y9571D01*
X1076419Y9542D01*
G03Y8702I1338J-420D01*
G01X1076428Y8673D01*
Y8300D01*
X1072816D01*
G02X1072427Y8794I0J400D01*
G03X1069701I-1363J328D01*
G02X1069312Y8300I-389J-94D01*
G01X1065696D01*
Y8664D01*
X1065706Y8694D01*
G03X1063126Y9766I-1335J427D01*
G01X1063111Y9738D01*
X1063044Y9670D01*
Y9574D01*
X1063034Y9545D01*
G03Y8699I1337J-423D01*
G01X1063044Y8670D01*
Y8300D01*
X1062776D01*
G02X1062387Y8794I0J400D01*
G03X1059661I-1363J328D01*
G02X1059272Y8300I-389J-94D01*
G01X1055656D01*
Y8664D01*
X1055666Y8694D01*
G03X1053086Y9766I-1335J427D01*
G01X1053071Y9738D01*
X1053004Y9670D01*
Y9574D01*
X1052994Y9545D01*
G03Y8699I1337J-423D01*
G01X1053004Y8670D01*
Y8300D01*
X1052310D01*
Y8664D01*
X1052320Y8694D01*
G03X1049740Y9766I-1335J427D01*
G01X1049725Y9738D01*
X1049658Y9670D01*
Y9574D01*
X1049648Y9545D01*
G03Y8699I1337J-423D01*
G01X1049658Y8670D01*
Y8300D01*
X1046236D01*
Y11600D01*
X1049036Y14400D01*
Y16956D01*
G03Y17128I-1399J86D01*
G01Y17300D01*
X1049800Y18064D01*
Y22800D01*
X1050300Y23300D01*
X1051700D01*
X1052236Y22764D01*
Y18100D01*
X1052536Y17800D01*
X1053004D01*
Y17509D01*
X1052994Y17480D01*
G03Y16634I1337J-423D01*
G01X1053004Y16605D01*
Y16509D01*
X1053071Y16441D01*
X1053086Y16413D01*
G03X1055666Y17485I1245J645D01*
G01X1055656Y17515D01*
Y17800D01*
X1056350D01*
Y17497D01*
X1056341Y17467D01*
G03X1059013I1336J-425D01*
G01X1059004Y17497D01*
Y17800D01*
X1063044D01*
Y17509D01*
X1063034Y17480D01*
G03Y16634I1337J-423D01*
G01X1063044Y16605D01*
Y16509D01*
X1063111Y16441D01*
X1063126Y16413D01*
G03X1065706Y17485I1245J645D01*
G01X1065696Y17515D01*
Y17800D01*
X1069738D01*
Y17515D01*
X1069729Y17485D01*
G03X1072309Y16413I1335J-427D01*
G01X1072324Y16441D01*
X1072392Y16509D01*
Y16605D01*
X1072401Y16634D01*
G03Y17480I-1337J423D01*
G01X1072392Y17509D01*
Y17800D01*
X1073082D01*
Y17497D01*
X1073073Y17467D01*
G03X1075745I1336J-425D01*
G01X1075736Y17497D01*
Y17800D01*
X1079776D01*
Y17497D01*
X1079766Y17467D01*
G03X1082438I1336J-425D01*
G01X1082428Y17497D01*
Y17800D01*
X1086468D01*
Y17514D01*
X1086459Y17484D01*
G03X1089131I1336J-425D01*
G01X1089122Y17514D01*
Y17800D01*
X1091200D01*
X1093300Y15700D01*
Y15202D01*
X1089864D01*
Y14702D01*
X1088364D01*
Y11698D01*
X1089864D01*
Y11198D01*
X1093300D01*
G37*
G36*
G01X1086468Y84008D02*
Y83675D01*
X1085774D01*
Y86686D01*
X1085795Y86728D01*
G03X1083101I-1347J664D01*
G01X1083122Y86686D01*
Y83675D01*
X1082948D01*
Y83600D01*
X1082800D01*
X1082300Y83100D01*
Y79500D01*
X1081500Y78700D01*
X1080500D01*
X1079900Y79300D01*
Y83000D01*
X1079300Y83600D01*
X1079082D01*
Y86686D01*
X1079102Y86728D01*
G03X1076408I-1347J664D01*
G01X1076428Y86686D01*
Y83674D01*
X1076256D01*
Y83600D01*
X1076000D01*
X1075500Y83100D01*
Y79400D01*
X1074700Y78600D01*
X1073900D01*
X1073200Y79300D01*
Y83200D01*
X1072800Y83600D01*
X1072566D01*
Y83674D01*
X1069564D01*
Y83600D01*
X1069400D01*
X1068900Y83100D01*
Y79100D01*
X1068400Y78600D01*
X1067100D01*
X1066500Y79200D01*
Y83200D01*
X1066100Y83600D01*
X1065874D01*
Y83675D01*
X1065698D01*
Y86692D01*
X1065719Y86733D01*
G03X1063025Y86722I-1350J659D01*
G01X1063046Y86680D01*
Y83675D01*
X1062761D01*
G02X1062386Y84213I0J400D01*
G03X1059772Y83977I-1363J501D01*
G01X1059800Y83875D01*
G02X1059600Y83675I-200J0D01*
G01X1059523D01*
Y83600D01*
X1059400D01*
X1058900Y83100D01*
Y79100D01*
X1058400Y78600D01*
X1057000D01*
X1056400Y79200D01*
Y83200D01*
X1056000Y83600D01*
X1055834D01*
Y83675D01*
X1055670D01*
Y83920D01*
X1055689Y83960D01*
G03X1052971I-1359J639D01*
G01X1052990Y83920D01*
Y83675D01*
X1052310D01*
Y86688D01*
X1052331Y86730D01*
G03X1049637Y86726I-1348J662D01*
G01X1049658Y86684D01*
Y83675D01*
X1049484D01*
Y83600D01*
X1049200D01*
X1048900Y83300D01*
Y79000D01*
X1048500Y78600D01*
X1047000D01*
X1046236Y79364D01*
Y87200D01*
X1047502Y88466D01*
X1047588Y88463D01*
G03X1049048Y90479I49J1501D01*
G01X1049036Y90512D01*
Y92900D01*
X1049668Y93532D01*
Y101268D01*
X1050000Y101600D01*
X1051600D01*
X1052200Y101000D01*
Y94200D01*
X1052700Y93700D01*
X1052830D01*
Y93682D01*
X1053004D01*
Y90670D01*
X1052983Y90628D01*
G03X1055677I1347J-664D01*
G01X1055656Y90670D01*
Y93682D01*
X1055834D01*
Y93700D01*
X1056345D01*
Y93454D01*
X1056325Y93413D01*
G03X1059035Y93396I1351J-656D01*
G01X1059016Y93437D01*
Y93682D01*
X1059180D01*
Y93700D01*
X1059600D01*
X1059900Y94000D01*
Y102300D01*
X1060200Y102600D01*
X1061700D01*
X1062100Y102200D01*
Y94000D01*
X1062400Y93700D01*
X1062870D01*
Y93682D01*
X1063029D01*
Y93437D01*
X1063010Y93396D01*
G03X1065728I1359J-639D01*
G01X1065709Y93437D01*
Y93682D01*
X1065874D01*
Y93700D01*
X1066500D01*
X1066700Y93900D01*
Y98300D01*
X1067100Y98700D01*
X1068200D01*
X1068700Y98200D01*
Y94100D01*
X1069100Y93700D01*
X1069564D01*
Y93682D01*
X1069722D01*
Y93437D01*
X1069703Y93396D01*
G03X1072421I1359J-639D01*
G01X1072402Y93437D01*
Y93682D01*
X1072566D01*
Y93700D01*
X1073082D01*
Y90670D01*
X1073062Y90628D01*
G03X1075756I1347J-664D01*
G01X1075736Y90670D01*
Y93682D01*
X1075912D01*
Y93700D01*
X1076400D01*
X1076600Y93900D01*
Y101200D01*
X1076800Y101400D01*
X1078700D01*
X1078900Y101200D01*
Y94100D01*
X1079300Y93700D01*
X1079602D01*
Y93682D01*
X1079776D01*
Y90670D01*
X1079755Y90628D01*
G03X1082449I1347J-664D01*
G01X1082428Y90670D01*
Y93682D01*
X1082606D01*
Y93700D01*
X1083100D01*
X1083300Y93900D01*
Y98400D01*
X1083600Y98700D01*
X1085200D01*
X1085600Y98300D01*
Y94100D01*
X1086000Y93700D01*
X1086296D01*
Y93682D01*
X1086468D01*
Y90670D01*
X1086448Y90628D01*
G03X1089142I1347J-664D01*
G01X1089122Y90670D01*
Y93682D01*
X1089298D01*
Y93700D01*
X1089800D01*
X1090000Y93900D01*
Y98500D01*
X1090200Y98700D01*
X1092000D01*
X1092400Y98300D01*
Y93200D01*
X1093162Y92438D01*
Y90670D01*
X1093141Y90628D01*
G03X1093793Y88633I1347J-664D01*
G01X1093900Y88577D01*
Y86101D01*
X1093793Y86045D01*
G03X1093117Y84100I695J-1331D01*
G01X1093162Y84002D01*
Y83962D01*
X1092800Y83600D01*
X1092700D01*
X1092300Y83200D01*
Y79100D01*
X1091800Y78600D01*
X1090600D01*
X1090000Y79200D01*
Y82900D01*
X1089300Y83600D01*
X1089122D01*
Y84008D01*
X1089142Y84050D01*
G03X1086448I-1347J664D01*
G01X1086468Y84008D01*
G37*
G36*
G01X1093433Y47845D02*
G03X1093088Y47002I1055J-924D01*
G01X1093084Y46926D01*
X1092220Y46062D01*
X1089539D01*
G02X1089153Y46564I1J400D01*
G03X1086441I-1356J358D01*
G02X1086055Y46062I-387J-102D01*
G01X1085774D01*
Y46461D01*
X1085784Y46491D01*
G03X1083205Y47566I-1334J430D01*
G01X1083190Y47538D01*
X1083122Y47469D01*
Y47371D01*
X1083112Y47342D01*
G03Y46502I1338J-420D01*
G01X1083122Y46473D01*
Y46062D01*
X1079082D01*
Y46461D01*
X1079091Y46491D01*
G03X1076512Y47566I-1334J430D01*
G01X1076497Y47538D01*
X1076428Y47469D01*
Y47371D01*
X1076419Y47342D01*
G03Y46502I1338J-420D01*
G01X1076428Y46473D01*
Y46062D01*
X1073369D01*
X1072467Y46964D01*
X1072461Y47037D01*
G03X1071474Y48263I-1397J-115D01*
G01X1071426Y48277D01*
X1070786Y48918D01*
G02X1071048Y49600I283J283D01*
G03X1070383Y52270I-72J1400D01*
G01X1070342Y52252D01*
X1069010D01*
Y53002D01*
X1066429D01*
X1066250Y53181D01*
Y54637D01*
X1067221Y55608D01*
X1069297D01*
G02X1069689Y55130I0J-400D01*
G03X1072439I1375J-273D01*
G02X1072831Y55608I392J78D01*
G01X1073082D01*
Y55297D01*
X1073073Y55267D01*
G03X1075745I1336J-425D01*
G01X1075736Y55297D01*
Y55608D01*
X1079776D01*
Y55297D01*
X1079766Y55267D01*
G03X1082438I1336J-425D01*
G01X1082428Y55297D01*
Y55608D01*
X1086468D01*
Y55314D01*
X1086459Y55284D01*
G03X1089131I1336J-425D01*
G01X1089122Y55314D01*
Y55608D01*
X1091411D01*
X1093433Y53586D01*
Y53002D01*
X1089864D01*
Y52502D01*
X1088364D01*
Y49498D01*
X1089864D01*
Y48998D01*
X1093433D01*
Y47845D01*
G37*
G36*
G01X1049439Y64800D02*
G02X1049060Y65328I0J400D01*
G03X1046660Y66948I-1423J479D01*
G02X1046000Y67252I-260J304D01*
G01Y74300D01*
X1046800Y75100D01*
X1049449D01*
G02X1049790Y74491I0J-400D01*
G03X1051507Y72456I1195J-734D01*
G02X1052056Y72085I149J-371D01*
G01Y71852D01*
X1050556D01*
Y67948D01*
X1052056D01*
Y67448D01*
X1053011D01*
G02X1053304Y66776I0J-400D01*
G03X1053015Y65338I1027J-954D01*
G02X1052640Y64800I-375J-138D01*
G01X1049439D01*
G37*
G36*
G01X1055534Y65103D02*
G03X1055358Y66776I-1203J719D01*
G02X1055651Y67448I293J272D01*
G01X1056560D01*
Y68648D01*
X1057158D01*
X1057199Y68630D01*
G03Y71170I593J1270D01*
G01X1057158Y71152D01*
X1056560D01*
Y72352D01*
X1055826D01*
G02X1055494Y72975I0J400D01*
G03X1055526Y74491I-1163J783D01*
G02X1055867Y75100I341J209D01*
G01X1059488D01*
G02X1059829Y74491I0J-400D01*
G03X1062219I1195J-734D01*
G02X1062560Y75100I341J209D01*
G01X1062835D01*
G02X1063176Y74491I0J-400D01*
G03X1064315Y72356I1195J-734D01*
G02X1064506Y72156I-9J-200D01*
G01Y71852D01*
X1063006D01*
Y67948D01*
X1064506D01*
Y67423D01*
G02X1064315Y67223I-200J0D01*
G03X1063055Y65338I56J-1401D01*
G02X1062680Y64800I-375J-138D01*
G01X1059479D01*
G02X1059100Y65328I0J400D01*
G03X1056254I-1423J479D01*
G02X1055875Y64800I-379J-128D01*
G01X1055706D01*
G02X1055534Y65103I0J200D01*
G37*
G36*
G01X1066062Y64800D02*
G02X1065687Y65338I0J400D01*
G03X1065398Y66776I-1316J484D01*
G02X1065691Y67448I293J272D01*
G01X1069010D01*
Y68648D01*
X1070342D01*
X1070383Y68630D01*
G03Y71170I593J1270D01*
G01X1070342Y71152D01*
X1069010D01*
Y72352D01*
X1065866D01*
G02X1065534Y72975I0J400D01*
G03X1065566Y74491I-1163J783D01*
G02X1065907Y75100I341J209D01*
G01X1069848D01*
Y74457D01*
X1069825Y74414D01*
G03X1072301Y74417I1239J-657D01*
G01X1072278Y74461D01*
Y75100D01*
X1076221D01*
G02X1076562Y74491I0J-400D01*
G03X1077363Y72412I1195J-733D01*
G01X1077506Y72369D01*
Y71852D01*
X1076006D01*
Y67948D01*
X1077506D01*
Y67448D01*
X1079661D01*
G02X1079964Y66787I0J-400D01*
G03X1079679Y65328I1138J-980D01*
G02X1079300Y64800I-379J-128D01*
G01X1076211D01*
G02X1075832Y65328I0J400D01*
G03X1072986I-1423J479D01*
G02X1072607Y64800I-379J-128D01*
G01X1072439D01*
G02X1072267Y65103I0J200D01*
G03X1069748Y65338I-1203J719D01*
G02X1069373Y64800I-375J-138D01*
G01X1066062D01*
G37*
G36*
G01X1082904D02*
G02X1082525Y65328I0J400D01*
G03X1081901Y67079I-1423J479D01*
G01X1081807Y67138D01*
Y67448D01*
X1082010D01*
Y68648D01*
X1082482D01*
X1082523Y68630D01*
G03Y71170I593J1270D01*
G01X1082482Y71152D01*
X1082010D01*
Y72352D01*
X1079252D01*
G02X1078920Y72975I0J400D01*
G03X1078952Y74491I-1163J783D01*
G02X1079293Y75100I341J209D01*
G01X1082914D01*
G02X1083255Y74491I0J-400D01*
G03X1085645I1195J-734D01*
G02X1085986Y75100I341J209D01*
G01X1086261D01*
G02X1086602Y74491I0J-400D01*
G03X1088992I1195J-734D01*
G02X1089333Y75100I341J209D01*
G01X1092300D01*
X1093400Y74000D01*
Y72352D01*
X1089864D01*
Y71852D01*
X1088364D01*
Y67948D01*
X1089864D01*
Y67448D01*
X1093400D01*
Y66706D01*
G03X1093106Y66058I1088J-884D01*
G01X1093095Y65995D01*
X1091900Y64800D01*
X1089488D01*
G02X1089113Y65338I0J400D01*
G03X1086481I-1316J484D01*
G02X1086106Y64800I-375J-138D01*
G01X1082904D01*
G37*
G36*
G01X1097800Y88800D02*
X1096800Y89800D01*
Y100900D01*
X1095992Y101708D01*
Y101784D01*
X1095916D01*
X1094002Y103698D01*
Y108282D01*
X1094000D01*
Y109200D01*
X1094050Y109250D01*
Y111450D01*
X1093300Y112200D01*
Y112500D01*
X1093623Y112823D01*
X1093710Y112820D01*
G03X1093800Y112818I105J2680D01*
G01X1097300D01*
G03X1099587Y114100I0J2681D01*
G01X1102200D01*
X1105500Y110800D01*
Y89900D01*
X1104900Y89300D01*
X1103500D01*
X1103100Y89700D01*
Y91100D01*
X1103400Y91400D01*
Y102500D01*
X1102700Y103200D01*
X1099600D01*
X1099000Y102600D01*
Y92900D01*
X1099600Y92300D01*
Y89400D01*
X1099000Y88800D01*
X1097800D01*
G37*
G36*
G01X1046926Y106518D02*
X1075526D01*
X1082507Y113500D01*
X1085014D01*
G03X1086800Y112818I1787J2000D01*
G01X1090300D01*
G03X1090474Y112824I-5J2682D01*
G02X1090900Y112425I26J-399D01*
G01Y110300D01*
X1090800Y110200D01*
Y104800D01*
X1090998Y104602D01*
Y103280D01*
X1092200D01*
Y96200D01*
X1091400Y95400D01*
X1090700D01*
X1090200Y95900D01*
Y101600D01*
X1089600Y102200D01*
X1085900D01*
X1085400Y101700D01*
Y96600D01*
X1084800Y96000D01*
X1083900D01*
X1083600Y96300D01*
Y101100D01*
X1080572Y104128D01*
X1078399D01*
G03X1076209I-1095J-1028D01*
G01X1072230D01*
G03X1070010I-1110J-1012D01*
G01X1069678D01*
X1068700Y103150D01*
Y95900D01*
X1068300Y95500D01*
X1067400D01*
X1066700Y96200D01*
Y103200D01*
X1065400Y104500D01*
X1065012D01*
X1064977Y104514D01*
G03X1063877I-550J-1398D01*
G01X1063842Y104500D01*
X1062700D01*
X1061900Y103700D01*
Y95900D01*
X1061400Y95400D01*
X1060900D01*
X1059900Y96400D01*
Y103100D01*
X1058700Y104300D01*
X1058660D01*
X1058608Y104337D01*
G03X1056810Y104300I-874J-1221D01*
G01X1051907D01*
G03X1050109Y104337I-924J-1184D01*
G01X1050057Y104300D01*
X1050000D01*
X1048600Y102900D01*
X1046100D01*
X1045400Y103600D01*
Y104993D01*
X1046926Y106518D01*
G37*
G36*
G01X1098456Y272278D02*
X1094758D01*
Y277342D01*
X1094756D01*
Y283841D01*
X1095254Y284340D01*
X1099758D01*
Y284841D01*
X1102254D01*
Y284590D01*
X1105256D01*
Y281041D01*
X1104756Y280541D01*
X1104056D01*
X1102956Y279441D01*
Y279242D01*
X1102954D01*
Y277240D01*
X1102956D01*
Y276151D01*
X1103390Y275717D01*
Y273988D01*
X1102333Y272931D01*
G02X1101650Y273232I-283J283D01*
G03X1098832Y272812I-1450J68D01*
G02X1098456Y272278I-377J-134D01*
G37*
G36*
G01X1068049Y263333D02*
X1068041Y263341D01*
X1039256D01*
X1038756Y263841D01*
Y269540D01*
X1039058D01*
Y274841D01*
X1043231D01*
X1043582Y274490D01*
Y272015D01*
X1045154Y270442D01*
Y270440D01*
X1045158D01*
X1045256Y270341D01*
X1050756D01*
X1050774Y270324D01*
X1078925D01*
X1079029Y270220D01*
Y266492D01*
X1077852Y265315D01*
Y263586D01*
X1077599Y263333D01*
X1068049D01*
G37*
G36*
G01X1040459Y332841D02*
X1039600Y333700D01*
Y336600D01*
X1042879Y339879D01*
X1051875D01*
X1051893Y339897D01*
X1053856D01*
X1053959Y340000D01*
X1080638D01*
X1081468Y339170D01*
Y337383D01*
X1081921Y336930D01*
X1084640D01*
X1084762Y336808D01*
Y333017D01*
X1084656Y332912D01*
X1079708D01*
Y332846D01*
X1077510D01*
Y332912D01*
X1072508D01*
Y332841D01*
X1070310D01*
Y332912D01*
X1065308D01*
Y332841D01*
X1063110D01*
Y332912D01*
X1058108D01*
Y332841D01*
X1055858D01*
Y332942D01*
X1050854D01*
Y332841D01*
X1048458D01*
Y332942D01*
X1043454D01*
Y332841D01*
X1040459D01*
G37*
G36*
G01X1063610Y287300D02*
Y287412D01*
X1058788D01*
X1058700Y287500D01*
Y292300D01*
X1060400Y294000D01*
X1093300D01*
X1093900Y293400D01*
Y288700D01*
X1092612Y287412D01*
X1087408D01*
Y287300D01*
X1085210D01*
Y287412D01*
X1080208D01*
Y287300D01*
X1078010D01*
Y287412D01*
X1073008D01*
Y287300D01*
X1070810D01*
Y287412D01*
X1065808D01*
Y287300D01*
X1063610D01*
G37*
G36*
G01Y303800D02*
Y304412D01*
X1058608D01*
Y304291D01*
G02X1058266Y304150I-200J0D01*
G01X1058073Y304343D01*
Y308064D01*
X1059015Y309006D01*
Y314465D01*
X1059740Y315190D01*
X1073810D01*
X1073900Y315100D01*
X1074100Y315300D01*
X1100500D01*
X1100900Y314900D01*
Y312000D01*
X1100400Y311500D01*
X1094500D01*
X1093500Y310500D01*
Y308900D01*
X1094000Y308400D01*
X1098577D01*
X1098589Y308399D01*
G03X1098923I167J1442D01*
G01X1098935Y308400D01*
X1099456D01*
X1099958Y307898D01*
Y304342D01*
X1094754D01*
Y303800D01*
X1092410D01*
Y304412D01*
X1087408D01*
Y303800D01*
X1085210D01*
Y304412D01*
X1080208D01*
Y303800D01*
X1078010D01*
Y304412D01*
X1073008D01*
Y303800D01*
X1070810D01*
Y304412D01*
X1065808D01*
Y303800D01*
X1063610D01*
G37*
G36*
G01X1080400Y504200D02*
X1080000Y504600D01*
Y508400D01*
X1079300Y509100D01*
X1079082D01*
Y512086D01*
X1079102Y512128D01*
G03X1076408I-1347J664D01*
G01X1076428Y512086D01*
Y509100D01*
X1073542D01*
X1072487Y510155D01*
Y513876D01*
X1071839Y514524D01*
X1067309D01*
X1067201Y514416D01*
X1065903Y515714D01*
X1063097D01*
X1061502Y514120D01*
X1061198D01*
X1059705Y515613D01*
Y518569D01*
X1060029Y518893D01*
X1062497D01*
G02X1062891Y518422I0J-400D01*
G03X1065847I1478J-265D01*
G02X1066241Y518893I394J71D01*
G01X1069190D01*
G02X1069584Y518422I0J-400D01*
G03X1072488Y518630I1478J-265D01*
G01X1072477Y518661D01*
Y518893D01*
X1073082D01*
Y516070D01*
X1073062Y516028D01*
G03X1075756I1347J-664D01*
G01X1075736Y516070D01*
Y518893D01*
X1079776D01*
Y516070D01*
X1079755Y516028D01*
G03X1082449I1347J-664D01*
G01X1082428Y516070D01*
Y518893D01*
X1086468D01*
Y516070D01*
X1086448Y516028D01*
G03X1089142I1347J-664D01*
G01X1089122Y516070D01*
Y518893D01*
X1091660D01*
X1092631Y517922D01*
Y505131D01*
X1091700Y504200D01*
X1090500D01*
X1089600Y505100D01*
Y508600D01*
X1089298Y508902D01*
Y509076D01*
X1089124D01*
X1089122Y509078D01*
Y509408D01*
X1089142Y509450D01*
G03X1086448I-1347J664D01*
G01X1086468Y509408D01*
Y509100D01*
X1085774D01*
Y512086D01*
X1085795Y512128D01*
G03X1083101I-1347J664D01*
G01X1083122Y512086D01*
Y509100D01*
X1082900D01*
X1082500Y508700D01*
Y504700D01*
X1082000Y504200D01*
X1080400D01*
G37*
G36*
G01X1049145Y492200D02*
G03X1047150Y493559I-2346J-1300D01*
G01X1047083Y493567D01*
X1046850Y493800D01*
Y498350D01*
X1046802Y498398D01*
Y498702D01*
X1046500D01*
Y510800D01*
X1046900Y511200D01*
X1048200D01*
X1048800Y510600D01*
Y501300D01*
X1049700Y500400D01*
X1056200D01*
X1056600Y500800D01*
Y513082D01*
X1057103Y513586D01*
X1058214D01*
X1058700Y513100D01*
Y501100D01*
X1059500Y500300D01*
X1066200D01*
X1066700Y500800D01*
Y510600D01*
X1067400Y511300D01*
X1068000D01*
X1068600Y510700D01*
Y501100D01*
X1069200Y500500D01*
X1073000D01*
X1073400Y500900D01*
Y511000D01*
X1074100Y511700D01*
X1075100D01*
X1076000Y510800D01*
Y500317D01*
X1082970D01*
G02X1083355Y499808I0J-400D01*
G03X1086301Y499461I1445J-408D01*
G02X1086700Y499877I400J16D01*
G01X1091370D01*
X1091810Y499437D01*
Y492950D01*
X1090930Y492070D01*
X1064298D01*
X1061628Y489400D01*
X1052000D01*
X1051904Y489496D01*
Y491827D01*
X1051531Y492200D01*
X1051530Y492199D01*
X1051001D01*
X1051000Y492200D01*
X1049145D01*
G37*
G36*
G01X1092634Y587798D02*
Y585433D01*
X1091972Y584771D01*
X1089513D01*
G02X1089132Y585293I0J400D01*
G03X1086557Y585067I-1335J429D01*
G01X1086580Y585023D01*
Y584771D01*
X1085774D01*
Y585261D01*
X1085784Y585291D01*
G03X1083205Y586366I-1334J430D01*
G01X1083190Y586338D01*
X1083122Y586269D01*
Y586171D01*
X1083112Y586142D01*
G03Y585302I1338J-420D01*
G01X1083122Y585273D01*
Y584771D01*
X1079082D01*
Y585261D01*
X1079091Y585291D01*
G03X1076512Y586366I-1334J430D01*
G01X1076497Y586338D01*
X1076428Y586269D01*
Y586171D01*
X1076419Y586142D01*
G03Y585302I1338J-420D01*
G01X1076428Y585273D01*
Y584771D01*
X1073013D01*
X1072600Y585184D01*
Y586400D01*
X1071900Y587100D01*
X1071404D01*
X1070650Y587853D01*
G02X1070780Y588505I283J282D01*
G03X1070207Y591202I-537J1295D01*
G01X1069010D01*
Y591802D01*
X1064506D01*
Y591302D01*
X1063006D01*
Y588714D01*
X1059458D01*
G02X1059089Y589267I1J400D01*
G03X1057757Y591202I-1297J533D01*
G01X1056560D01*
Y591802D01*
X1052056D01*
Y591302D01*
X1050556D01*
Y588714D01*
X1047214D01*
Y591003D01*
X1045977Y592241D01*
Y592354D01*
G02X1046657Y592640I400J0D01*
G03X1048973Y594067I980J1002D01*
G01X1048964Y594097D01*
Y594443D01*
X1053004D01*
Y594109D01*
X1052994Y594080D01*
G03Y593234I1337J-423D01*
G01X1053004Y593205D01*
Y593109D01*
X1053071Y593041D01*
X1053086Y593013D01*
G03X1055666Y594085I1245J645D01*
G01X1055656Y594115D01*
Y594443D01*
X1056350D01*
Y594097D01*
X1056341Y594067D01*
G03X1059013I1336J-425D01*
G01X1059004Y594097D01*
Y594443D01*
X1063044D01*
Y594109D01*
X1063034Y594080D01*
G03Y593234I1337J-423D01*
G01X1063044Y593205D01*
Y593109D01*
X1063111Y593041D01*
X1063126Y593013D01*
G03X1065706Y594085I1245J645D01*
G01X1065696Y594115D01*
Y594443D01*
X1069304D01*
G02X1069695Y593957I0J-400D01*
G03X1072369Y594170I1369J-300D01*
G01X1072355Y594205D01*
Y594443D01*
X1073017D01*
Y594207D01*
X1073004Y594172D01*
G03X1075877Y593959I1405J-530D01*
G02X1076268Y594443I391J84D01*
G01X1079776D01*
Y594097D01*
X1079766Y594067D01*
G03X1082438I1336J-425D01*
G01X1082428Y594097D01*
Y594443D01*
X1086468D01*
Y594114D01*
X1086459Y594084D01*
G03X1089131I1336J-425D01*
G01X1089122Y594114D01*
Y594443D01*
X1091837D01*
X1092634Y593646D01*
Y591802D01*
X1089864D01*
Y591302D01*
X1088364D01*
Y588298D01*
X1089864D01*
Y587798D01*
X1092634D01*
G37*
G36*
G01X1049322Y565524D02*
G02X1048967Y566110I-1J400D01*
G03X1046642Y567932I-1330J697D01*
G02X1045977Y568232I-265J300D01*
G01Y574648D01*
X1047162Y575833D01*
X1049315D01*
G02X1049685Y575283I-1J-400D01*
G03X1051507Y573456I1300J-526D01*
G02X1052056Y573085I149J-371D01*
G01Y572852D01*
X1050556D01*
Y568948D01*
X1052056D01*
Y568448D01*
X1053011D01*
G02X1053304Y567776I0J-400D01*
G03X1053116Y566123I1027J-954D01*
G02X1052769Y565524I-347J-199D01*
G01X1049322D01*
G37*
G36*
G01X1055893D02*
G02X1055546Y566123I0J400D01*
G03X1055358Y567776I-1215J699D01*
G02X1055651Y568448I293J272D01*
G01X1056560D01*
Y569498D01*
X1057757D01*
G03Y572302I35J1402D01*
G01X1056560D01*
Y573352D01*
X1055826D01*
G02X1055494Y573975I0J400D01*
G03X1055631Y575283I-1163J783D01*
G02X1056001Y575833I371J150D01*
G01X1059354D01*
G02X1059724Y575283I-1J-400D01*
G03X1062324I1300J-526D01*
G02X1062694Y575833I371J150D01*
G01X1062701D01*
G02X1063071Y575283I-1J-400D01*
G03X1064315Y573356I1300J-526D01*
G02X1064506Y573156I-9J-200D01*
G01Y572852D01*
X1063006D01*
Y568948D01*
X1064506D01*
Y568423D01*
G02X1064315Y568223I-200J0D01*
G03X1063156Y566123I56J-1401D01*
G02X1062809Y565524I-347J-199D01*
G01X1059362D01*
G02X1059007Y566110I-1J400D01*
G03X1056347I-1330J697D01*
G02X1055992Y565524I-354J-186D01*
G01X1055893D01*
G37*
G36*
G01X1065933D02*
G02X1065586Y566123I0J400D01*
G03X1065398Y567776I-1215J699D01*
G02X1065691Y568448I293J272D01*
G01X1069010D01*
Y569498D01*
X1070941D01*
G03Y572302I35J1402D01*
G01X1069010D01*
Y573352D01*
X1065866D01*
G02X1065534Y573975I0J400D01*
G03X1065671Y575283I-1163J783D01*
G02X1066041Y575833I371J150D01*
G01X1076087D01*
G02X1076457Y575283I-1J-400D01*
G03X1077363Y573412I1300J-525D01*
G01X1077506Y573369D01*
Y572852D01*
X1076006D01*
Y568948D01*
X1077506D01*
Y568448D01*
X1079661D01*
G02X1079964Y567787I0J-400D01*
G03X1079772Y566110I1138J-980D01*
G02X1079417Y565524I-354J-186D01*
G01X1076094D01*
G02X1075739Y566110I-1J400D01*
G03X1073079I-1330J697D01*
G02X1072724Y565524I-354J-186D01*
G01X1072626D01*
G02X1072279Y566123I0J400D01*
G03X1069849I-1215J699D01*
G02X1069502Y565524I-347J-199D01*
G01X1065933D01*
G37*
G36*
G01X1082787D02*
G02X1082432Y566110I-1J400D01*
G03X1081901Y568079I-1330J697D01*
G01X1081807Y568138D01*
Y568448D01*
X1082010D01*
Y569498D01*
X1083081D01*
G03Y572302I35J1402D01*
G01X1082010D01*
Y573352D01*
X1079252D01*
G02X1078920Y573975I0J400D01*
G03X1079057Y575283I-1163J783D01*
G02X1079427Y575833I371J150D01*
G01X1082780D01*
G02X1083150Y575283I-1J-400D01*
G03X1085750I1300J-526D01*
G02X1086120Y575833I371J150D01*
G01X1086127D01*
G02X1086497Y575283I-1J-400D01*
G03X1089097I1300J-526D01*
G02X1089467Y575833I371J150D01*
G01X1091837D01*
X1092634Y575036D01*
Y573352D01*
X1089864D01*
Y572852D01*
X1088364D01*
Y568948D01*
X1089864D01*
Y568448D01*
X1092634D01*
Y566265D01*
X1091893Y565524D01*
X1089474D01*
G02X1089121Y566113I0J400D01*
G03X1086473I-1324J709D01*
G02X1086120Y565524I-353J-189D01*
G01X1082787D01*
G37*
G36*
G01X1073457Y546922D02*
X1073030Y547349D01*
Y548993D01*
X1071820Y550203D01*
X1070902D01*
Y550588D01*
X1071086Y550602D01*
G03X1070941Y553402I-110J1398D01*
G01X1069010D01*
Y554002D01*
X1064506D01*
Y553502D01*
X1063006D01*
Y551052D01*
X1059508D01*
G02X1059127Y551573I0J400D01*
G03X1057757Y553402I-1335J427D01*
G01X1056560D01*
Y554002D01*
X1052056D01*
Y553502D01*
X1050556D01*
Y551052D01*
X1047287D01*
X1047214Y551124D01*
Y551737D01*
X1045977Y552975D01*
Y554554D01*
G02X1046657Y554840I400J0D01*
G03X1048973Y556267I980J1002D01*
G01X1048964Y556297D01*
Y556643D01*
X1053004D01*
Y556309D01*
X1052994Y556280D01*
G03Y555434I1337J-423D01*
G01X1053004Y555405D01*
Y555309D01*
X1053071Y555241D01*
X1053086Y555213D01*
G03X1055666Y556285I1245J645D01*
G01X1055656Y556315D01*
Y556643D01*
X1056350D01*
Y556297D01*
X1056341Y556267D01*
G03X1059013I1336J-425D01*
G01X1059004Y556297D01*
Y556643D01*
X1063044D01*
Y556309D01*
X1063034Y556280D01*
G03Y555434I1337J-423D01*
G01X1063044Y555405D01*
Y555309D01*
X1063111Y555241D01*
X1063126Y555213D01*
G03X1065706Y556285I1245J645D01*
G01X1065696Y556315D01*
Y556643D01*
X1069304D01*
G02X1069695Y556157I0J-400D01*
G03X1072433I1369J-300D01*
G02X1072824Y556643I391J86D01*
G01X1073082D01*
Y556297D01*
X1073073Y556267D01*
G03X1075745I1336J-425D01*
G01X1075736Y556297D01*
Y556643D01*
X1079776D01*
Y556297D01*
X1079766Y556267D01*
G03X1082438I1336J-425D01*
G01X1082428Y556297D01*
Y556643D01*
X1086468D01*
Y556314D01*
X1086459Y556284D01*
G03X1089131I1336J-425D01*
G01X1089122Y556314D01*
Y556643D01*
X1091837D01*
X1092634Y555846D01*
Y554002D01*
X1089864D01*
Y553502D01*
X1088364D01*
Y550498D01*
X1089864D01*
Y549998D01*
X1092634D01*
Y547711D01*
X1091845Y546922D01*
X1089122D01*
Y547461D01*
X1089131Y547491D01*
G03X1086552Y548566I-1334J430D01*
G01X1086537Y548538D01*
X1086468Y548469D01*
Y548371D01*
X1086459Y548342D01*
G03Y547502I1338J-420D01*
G01X1086468Y547473D01*
Y546922D01*
X1085774D01*
Y547461D01*
X1085784Y547491D01*
G03X1083205Y548566I-1334J430D01*
G01X1083190Y548538D01*
X1083122Y548469D01*
Y548371D01*
X1083112Y548342D01*
G03Y547502I1338J-420D01*
G01X1083122Y547473D01*
Y546922D01*
X1079082D01*
Y547461D01*
X1079091Y547491D01*
G03X1076512Y548566I-1334J430D01*
G01X1076497Y548538D01*
X1076428Y548469D01*
Y548371D01*
X1076419Y548342D01*
G03Y547502I1338J-420D01*
G01X1076428Y547473D01*
Y546922D01*
X1073457D01*
G37*
G36*
G01X1049322Y527724D02*
G02X1048967Y528310I-1J400D01*
G03X1046135Y529034I-1330J697D01*
G01X1046134Y528953D01*
X1045935Y528755D01*
X1045649Y529041D01*
X1045644Y529117D01*
G03X1044212Y530478I-1449J-91D01*
G01X1044200Y530490D01*
Y535071D01*
X1044815Y535686D01*
X1044846Y535701D01*
G03X1045560Y536415I-643J1357D01*
G01X1045575Y536446D01*
X1047162Y538033D01*
X1049315D01*
G02X1049685Y537483I-1J-400D01*
G03X1049822Y536175I1300J-525D01*
G02X1049490Y535552I-332J-223D01*
G01X1049306D01*
Y535052D01*
X1047806D01*
Y531148D01*
X1049306D01*
Y530648D01*
X1052877D01*
G02X1053183Y529991I0J-400D01*
G03X1053007Y528313I1148J-969D01*
G02X1052654Y527724I-353J-189D01*
G01X1049322D01*
G37*
G36*
G01X1059362D02*
G02X1059007Y528310I-1J400D01*
G03X1056359Y529727I-1330J697D01*
G02X1055655Y529731I-351J192D01*
G03X1054235Y530521I-1324J-709D01*
G02X1053810Y530920I-25J399D01*
G01Y531698D01*
X1057757D01*
G03Y534502I35J1402D01*
G01X1053810D01*
Y535159D01*
G02X1054236Y535558I400J0D01*
G03X1055631Y537483I95J1399D01*
G02X1056001Y538033I371J150D01*
G01X1059354D01*
G02X1059724Y537483I-1J-400D01*
G03X1062324I1300J-526D01*
G02X1062694Y538033I371J150D01*
G01X1062701D01*
G02X1063071Y537483I-1J-400D01*
G03X1064315Y535556I1300J-526D01*
G02X1064506Y535356I-9J-200D01*
G01Y535052D01*
X1063006D01*
Y531148D01*
X1064506D01*
Y530648D01*
X1069010D01*
Y531698D01*
X1070941D01*
G03Y534502I35J1402D01*
G01X1069010D01*
Y535552D01*
X1065866D01*
G02X1065534Y536175I0J400D01*
G03X1065671Y537483I-1163J783D01*
G02X1066041Y538033I371J150D01*
G01X1076087D01*
G02X1076457Y537483I-1J-400D01*
G03X1077363Y535612I1300J-525D01*
G01X1077506Y535569D01*
Y535052D01*
X1076006D01*
Y531148D01*
X1077506D01*
Y530648D01*
X1082010D01*
Y531698D01*
X1083285D01*
X1083330Y531674D01*
G03X1084968Y533921I673J1230D01*
G01X1084388Y534502D01*
X1082010D01*
Y535552D01*
X1079252D01*
G02X1078920Y536175I0J400D01*
G03X1079057Y537483I-1163J783D01*
G02X1079427Y538033I371J150D01*
G01X1082780D01*
G02X1083150Y537483I-1J-400D01*
G03X1085750I1300J-526D01*
G02X1086120Y538033I371J150D01*
G01X1086127D01*
G02X1086497Y537483I-1J-400D01*
G03X1089097I1300J-526D01*
G02X1089467Y538033I371J150D01*
G01X1091837D01*
X1092634Y537236D01*
Y535552D01*
X1091364D01*
Y535052D01*
X1089864D01*
Y531148D01*
X1091364D01*
Y530648D01*
X1092634D01*
Y528465D01*
X1091893Y527724D01*
X1072626D01*
G02X1072279Y528323I0J400D01*
G03X1069849I-1215J699D01*
G02X1069502Y527724I-347J-199D01*
G01X1059362D01*
G37*
G36*
G01X1101300Y610900D02*
X1096900Y615300D01*
X1093900D01*
X1093600Y615600D01*
Y620000D01*
X1094200Y620600D01*
X1107900D01*
X1109400Y619100D01*
Y611800D01*
X1108500Y610900D01*
X1105523D01*
X1105467Y611006D01*
G03X1102815I-1326J-706D01*
G01X1102759Y610900D01*
X1101300D01*
G37*
G36*
G01X1062929Y606865D02*
G03X1065763Y606732I1440J427D01*
G02X1066417Y606866I371J-149D01*
G01X1066497Y606786D01*
X1069003D01*
X1069035Y606817D01*
G02X1069684Y606694I283J-283D01*
G03X1071660Y608670I1378J598D01*
G02X1071537Y609319I160J366D01*
G01X1072276Y610059D01*
Y611442D01*
X1073840D01*
X1076497Y608786D01*
X1077497D01*
X1079497Y606786D01*
X1083003D01*
X1085722Y609504D01*
G02X1086381Y609357I283J-283D01*
G03X1089258Y609525I1414J507D01*
G01X1089294Y609680D01*
X1092634D01*
Y604065D01*
X1091893Y603324D01*
X1089476D01*
G02X1089122Y603911I0J400D01*
G03X1086468I-1327J703D01*
G02X1086114Y603324I-354J-187D01*
G01X1082839D01*
G02X1082474Y603887I0J400D01*
G03X1079730I-1372J612D01*
G02X1079365Y603324I-365J-163D01*
G01X1076090D01*
G02X1075736Y603911I0J400D01*
G03X1073082I-1327J703D01*
G02X1072728Y603324I-354J-187D01*
G01X1056067D01*
G02X1055702Y603887I0J400D01*
G03X1052958I-1372J612D01*
G02X1052593Y603324I-365J-163D01*
G01X1049374D01*
G02X1049009Y603887I0J400D01*
G03X1046642Y605624I-1372J612D01*
G02X1045977Y605924I-265J300D01*
G01Y606823D01*
G02X1046318Y606964I200J-1D01*
G01X1046497Y606786D01*
X1049003D01*
X1050503Y608286D01*
X1051497D01*
X1052997Y606786D01*
X1056256D01*
X1056310Y606669D01*
G03X1059110Y606844I1367J623D01*
G02X1059774Y607008I382J-119D01*
G01X1059997Y606786D01*
X1062014D01*
X1062263Y607034D01*
G02X1062929Y606865I283J-283D01*
G37*
G36*
G01X1078765Y611545D02*
G03X1076345Y613175I-1010J1112D01*
G02X1075687Y613031I-375J138D01*
G01X1074846Y613872D01*
X1071796D01*
X1071752Y613894D01*
G03X1069814Y611725I-690J-1334D01*
G01X1069848Y611674D01*
Y611065D01*
X1067997Y609214D01*
X1067503D01*
X1066003Y610714D01*
X1062508D01*
X1062354Y610560D01*
X1062202Y610712D01*
X1062193Y610724D01*
G03X1059841Y610707I-1170J-860D01*
G01X1059831Y610693D01*
X1059678Y610540D01*
X1059503Y610714D01*
X1056497D01*
X1056280Y610497D01*
G02X1055646Y610587I-283J283D01*
G03X1053118Y610751I-1316J-723D01*
G02X1052513Y610705I-322J237D01*
G01X1052503Y610714D01*
X1049497D01*
X1047997Y609214D01*
X1047503D01*
X1046003Y610714D01*
X1045977D01*
Y616207D01*
X1051081Y621311D01*
X1062500D01*
X1063000Y620811D01*
Y615600D01*
X1063030Y615570D01*
Y615454D01*
X1063145D01*
X1063200Y615400D01*
X1065530D01*
Y614954D01*
X1070534D01*
Y615634D01*
X1070700Y615800D01*
Y618854D01*
X1072294Y620448D01*
X1076530D01*
Y615454D01*
X1079030D01*
Y614954D01*
X1084034D01*
Y618688D01*
X1085894Y620548D01*
X1090052D01*
X1090400Y620200D01*
Y616134D01*
X1090530Y616004D01*
Y615454D01*
X1091080D01*
X1092634Y613900D01*
Y612108D01*
X1090609D01*
X1089003Y613714D01*
X1086497D01*
X1086272Y613489D01*
G02X1085665Y613538I-283J283D01*
G03X1083567Y611440I-1217J-881D01*
G02X1083616Y610833I-234J-324D01*
G01X1081997Y609214D01*
X1080503D01*
X1078751Y610966D01*
G02X1078765Y611545I283J283D01*
G37*
G36*
G01X1096415Y37706D02*
X1101841D01*
X1102950Y36597D01*
Y34615D01*
G03X1102913Y32834I1191J-916D01*
G01X1102950Y32783D01*
Y32400D01*
X1103450Y31900D01*
X1105000D01*
X1105600Y31300D01*
Y29400D01*
X1104503Y28303D01*
X1102950D01*
X1102797Y28150D01*
X1102622Y28325D01*
X1102607Y28370D01*
G03X1099731Y27507I-1426J-472D01*
G02X1099345Y27003I-386J-104D01*
G01X1096633D01*
X1095870Y27766D01*
X1095881Y27862D01*
G03X1095319Y29151I-1393J160D01*
G01Y34826D01*
G03X1095662Y36727I-829J1131D01*
G01X1095572Y36863D01*
X1096415Y37706D01*
G37*
G36*
G01X1096818Y64831D02*
X1095891Y65758D01*
X1095890Y65839D01*
G03X1095504Y66788I-1402J-17D01*
G01Y73882D01*
X1096727Y75105D01*
X1102039D01*
X1102597Y74547D01*
Y70438D01*
X1103635Y69400D01*
X1104300D01*
X1105400Y68300D01*
Y67000D01*
X1103998Y65598D01*
X1102691D01*
X1102680Y65786D01*
G03X1099725Y65329I-1499J-87D01*
G02X1099338Y64831I-388J-98D01*
G01X1096818D01*
G37*
G36*
G01X1132628Y286110D02*
G02X1132229Y286485I0J400D01*
G03X1129711Y287379I-1449J-89D01*
G02X1129134Y287366I-295J270D01*
G01X1128736Y287764D01*
X1128776Y287882D01*
G03X1126935Y289723I-1376J465D01*
G01X1126817Y289683D01*
X1125600Y290900D01*
Y299196D01*
X1125764Y299361D01*
Y299780D01*
X1127131Y301146D01*
X1128463D01*
X1128817Y301500D01*
G02X1129463Y301385I283J-283D01*
G03X1131880Y302944I1317J611D01*
G02X1131900Y303488I303J261D01*
G01X1132206Y303794D01*
X1132389Y303611D01*
X1132401Y303555D01*
G03X1134824Y305622I1759J392D01*
G02X1134689Y306277I148J372D01*
G01X1136000Y307588D01*
Y308338D01*
G02X1136646Y308653I400J0D01*
G03Y310941I894J1144D01*
G02X1136000Y311256I-246J315D01*
G01Y311812D01*
G02X1136607Y312154I400J0D01*
G03X1139340Y313771I933J1542D01*
G02X1139954Y314126I400J17D01*
G03X1139120Y315572I966J1521D01*
G02X1138506Y315217I-400J-17D01*
G03X1136607Y315238I-966J-1521D01*
G02X1136000Y315580I-207J342D01*
G01Y316137D01*
G02X1136646Y316452I400J0D01*
G03X1137319Y319031I894J1144D01*
G02X1136858Y319426I-61J395D01*
G01Y319666D01*
G02X1137319Y320061I400J0D01*
G03X1136646Y322640I221J1435D01*
G02X1136000Y322955I-246J315D01*
G01Y323937D01*
G02X1136646Y324252I400J0D01*
G03Y326540I894J1144D01*
G02X1136000Y326855I-246J315D01*
G01Y327837D01*
G02X1136646Y328152I400J0D01*
G03Y330440I894J1144D01*
G02X1136000Y330755I-246J315D01*
G01Y331737D01*
G02X1136646Y332052I400J0D01*
G03Y334340I894J1144D01*
G02X1136000Y334655I-246J315D01*
G01Y335637D01*
G02X1136646Y335952I400J0D01*
G03Y338240I894J1144D01*
G02X1136000Y338555I-246J315D01*
G01Y339537D01*
G02X1136646Y339852I400J0D01*
G03Y342140I894J1144D01*
G02X1136000Y342455I-246J315D01*
G01Y342500D01*
X1135613Y342887D01*
X1135612Y342968D01*
G03X1134181Y344399I-1452J-21D01*
G01X1134100Y344400D01*
X1133786Y344714D01*
G02X1134088Y345397I282J283D01*
G03X1132710Y346775I72J1450D01*
G02X1132027Y346473I-400J-20D01*
G01X1131526Y346974D01*
G02X1131587Y347589I283J282D01*
G03X1129573Y349603I-807J1207D01*
G02X1128958Y349542I-333J222D01*
G01X1128629Y349871D01*
X1128705Y350003D01*
G03X1126656Y352052I-1305J744D01*
G01X1126524Y351976D01*
X1125423Y353077D01*
X1125408Y353124D01*
G03X1124449Y354083I-1387J-428D01*
G01X1124402Y354098D01*
X1124018Y354482D01*
G02X1124240Y355161I282J283D01*
G03X1122586Y356815I-219J1435D01*
G02X1121907Y356593I-396J60D01*
G01X1121605Y356895D01*
G02X1121619Y357473I283J282D01*
G03X1119452Y359380I-978J1073D01*
G01X1119442Y359366D01*
X1119288Y359212D01*
X1119000Y359500D01*
Y360628D01*
G02X1119625Y360958I400J0D01*
G03X1121607Y360926I1015J1489D01*
G02X1122221Y360571I214J-338D01*
G03X1123055Y362017I1800J-75D01*
G02X1122441Y362372I-214J338D01*
G03X1119344Y363698I-1800J75D01*
G01X1119285Y363637D01*
X1119000D01*
Y363923D01*
X1119006Y363947D01*
G03Y364845I-1745J449D01*
G01X1119000Y364869D01*
Y364972D01*
G02X1119668Y365269I400J0D01*
G03Y367425I973J1078D01*
G02X1119000Y367722I-268J297D01*
G01Y368872D01*
G02X1119668Y369169I400J0D01*
G03Y371325I973J1078D01*
G02X1119000Y371622I-268J297D01*
G01Y372327D01*
G02X1119625Y372657I400J0D01*
G03Y375635I1016J1489D01*
G02X1119000Y375965I-225J330D01*
G01Y376672D01*
G02X1119668Y376969I400J0D01*
G03Y379125I973J1078D01*
G02X1119000Y379422I-268J297D01*
G01Y379523D01*
X1119006Y379547D01*
G03Y380445I-1745J449D01*
G01X1119000Y380469D01*
Y380572D01*
G02X1119668Y380869I400J0D01*
G03Y383025I973J1078D01*
G02X1119000Y383322I-268J297D01*
G01Y383423D01*
X1119006Y383447D01*
G03Y384345I-1745J449D01*
G01X1119000Y384369D01*
Y384472D01*
G02X1119668Y384769I400J0D01*
G03Y386925I973J1078D01*
G02X1119000Y387222I-268J297D01*
G01Y387323D01*
X1119006Y387347D01*
G03Y388245I-1745J449D01*
G01X1119000Y388269D01*
Y388557D01*
X1119285D01*
X1119344Y388496D01*
G03X1119625Y391236I1297J1251D01*
G02X1119000Y391566I-225J330D01*
G01Y392272D01*
G02X1119668Y392569I400J0D01*
G03Y394725I973J1078D01*
G02X1119000Y395022I-268J297D01*
G01Y396000D01*
X1121000Y398000D01*
X1139069D01*
G02X1139469Y397588I0J-400D01*
G03X1142371I1451J-42D01*
G02X1142771Y398000I400J12D01*
G01X1143294D01*
X1143343Y397969D01*
G03X1145257I957J1527D01*
G01X1145306Y398000D01*
X1145829D01*
G02X1146229Y397588I0J-400D01*
G03X1148951Y398247I1451J-43D01*
G01X1148879Y398379D01*
X1150342Y399842D01*
X1155878D01*
X1155919Y399822D01*
G03X1157479I780J1625D01*
G01X1157520Y399842D01*
X1160380D01*
X1160421Y399822D01*
G03X1162876Y400781I780J1625D01*
G01X1162891Y400820D01*
X1164001Y401930D01*
X1165160D01*
X1165516Y402286D01*
X1165522Y402291D01*
G03X1165685Y402454I-942J1105D01*
G01X1165690Y402460D01*
X1167123Y403893D01*
X1168760D01*
X1170726Y401927D01*
X1171945D01*
X1173899Y403881D01*
X1175726D01*
X1178190Y406345D01*
X1193655D01*
X1194106Y405894D01*
X1194103Y405809D01*
G03X1195591Y404321I1452J-36D01*
G01X1195676Y404324D01*
X1207000Y393000D01*
Y344949D01*
X1202683Y340632D01*
X1201283D01*
X1200300Y339649D01*
Y323888D01*
X1199524Y323112D01*
X1199178D01*
X1199138Y323131D01*
G03X1197413Y323017I-758J-1635D01*
G02X1196799Y323372I-214J338D01*
G03X1195912Y321892I-1800J73D01*
G01X1196045Y321971D01*
X1196296Y321720D01*
X1195590Y321014D01*
X1194391D01*
X1193482Y320105D01*
Y316684D01*
X1191960Y315162D01*
X1191859Y315179D01*
G03X1190136Y313456I-240J-1483D01*
G01X1190153Y313355D01*
X1189419Y312621D01*
X1189277Y312763D01*
X1189276D01*
G03X1187223Y310710I-1037J-1016D01*
G01Y310709D01*
X1187365Y310567D01*
X1186899Y310101D01*
G02X1186236Y310257I-283J282D01*
G03X1184399Y308420I-1377J-460D01*
G02X1184555Y307757I-126J-380D01*
G01X1182075Y305277D01*
X1181957Y305318D01*
G03X1180108Y303469I-478J-1371D01*
G01X1180149Y303351D01*
X1179754Y302956D01*
G02X1179175Y302971I-282J283D01*
G03X1177124Y300920I-1076J-975D01*
G02X1177139Y300341I-268J-297D01*
G01X1176834Y300036D01*
G02X1176155Y300260I-283J283D01*
G03X1174506Y298611I-1436J-213D01*
G02X1174730Y297932I-59J-396D01*
G01X1174350Y297552D01*
X1174302Y297538D01*
G03X1173328Y296564I417J-1391D01*
G01X1173314Y296516D01*
X1172184Y295386D01*
X1172052Y295461D01*
G03X1170074Y293483I-713J-1265D01*
G01X1170149Y293351D01*
X1169786Y292988D01*
G02X1169170Y293050I-283J283D01*
G03X1167157Y291037I-1210J-803D01*
G02X1167219Y290421I-221J-333D01*
G01X1166712Y289914D01*
G02X1166030Y290218I-283J283D01*
G03X1163213Y289805I-1450J77D01*
G02X1162837Y289270I-376J-135D01*
G01X1162385D01*
G03X1160015I-1185J-923D01*
G01X1159563D01*
G02X1159187Y289805I0J400D01*
G03X1156453I-1367J491D01*
G02X1156077Y289270I-376J-135D01*
G01X1155625D01*
G03X1153255I-1185J-923D01*
G01X1152803D01*
G02X1152427Y289805I0J400D01*
G03X1149693I-1367J491D01*
G02X1149317Y289270I-376J-135D01*
G01X1148865D01*
G03X1146495I-1185J-923D01*
G01X1146096D01*
G02X1145718Y289802I0J400D01*
G03X1142987Y289567I-1418J494D01*
G02X1142812Y289270I-175J-97D01*
G01X1142750D01*
X1142708Y289228D01*
G02X1142108Y289266I-283J282D01*
G03X1140001Y287159I-1188J-919D01*
G02X1140039Y286559I-244J-317D01*
G01X1139590Y286110D01*
X1139439D01*
G02X1139039Y286486I-1J400D01*
G03X1136041I-1499J-90D01*
G02X1135641Y286110I-399J24D01*
G01X1132628D01*
G37*
G36*
G01X1101153Y302846D02*
X1100839Y303160D01*
Y303454D01*
X1100960Y303574D01*
Y308313D01*
X1100500Y308772D01*
Y309600D01*
X1102208Y311308D01*
Y316792D01*
X1102755Y317340D01*
X1107756D01*
Y313841D01*
X1106756D01*
X1104726Y311811D01*
X1104756Y311782D01*
Y308341D01*
X1104976Y308122D01*
Y302846D01*
X1101153D01*
G37*
G36*
G01X1097153Y565516D02*
X1096338Y566331D01*
Y575044D01*
X1097128Y575834D01*
X1104287D01*
X1105153Y574968D01*
Y574301D01*
G02X1104624Y573922I-400J0D01*
G03Y571078I-483J-1422D01*
G02X1105153Y570699I129J-379D01*
G01Y566483D01*
X1104186Y565516D01*
X1102914D01*
G02X1102550Y566081I0J400D01*
G03X1099812I-1369J618D01*
G02X1099448Y565516I-364J-165D01*
G01X1097153D01*
G37*
G36*
G01X1097294Y527669D02*
X1096479Y528484D01*
Y537197D01*
X1097269Y537987D01*
X1104428D01*
X1105294Y537121D01*
Y536447D01*
G02X1104736Y536079I-400J-1D01*
G03Y533321I-595J-1379D01*
G02X1105294Y532953I158J-367D01*
G01Y528636D01*
X1104327Y527669D01*
X1102892D01*
G02X1102532Y528244I0J400D01*
G03X1099830I-1351J655D01*
G02X1099470Y527669I-360J-175D01*
G01X1097294D01*
G37*
G36*
G01X1274000Y-15500D02*
X1269500Y-11000D01*
X1266872D01*
G02X1266502Y-10449I0J400D01*
G03X1266467Y-9274I-1345J548D01*
G02X1266827Y-8702I361J172D01*
G01X1268360D01*
Y-8002D01*
X1269461D01*
X1270351Y-7112D01*
X1270384Y-7097D01*
G03X1268714Y-4935I-584J1275D01*
G01X1268654Y-5008D01*
X1268360D01*
Y-4698D01*
X1263856D01*
Y-5198D01*
X1262356D01*
Y-8202D01*
X1263856D01*
Y-9254D01*
X1263838Y-9294D01*
G03X1263812Y-10449I1319J-607D01*
G02X1263442Y-11000I-370J-151D01*
G01X1256833D01*
G02X1256463Y-10449I0J400D01*
G03X1253773I-1345J548D01*
G02X1253403Y-11000I-370J-151D01*
G01X1253097D01*
G02X1252931Y-10688I0J200D01*
G03X1252355Y-8626I-1160J787D01*
G01X1252322Y-8611D01*
X1252253Y-8543D01*
G02X1252395Y-8202I142J141D01*
G01X1253360D01*
Y-5198D01*
X1251860D01*
Y-4698D01*
X1250000D01*
Y13300D01*
X1247300Y16000D01*
Y26249D01*
G02X1247861Y26615I400J0D01*
G03X1249700Y27315I564J1284D01*
G01X1249715Y27348D01*
X1249910Y27543D01*
Y29998D01*
X1250860D01*
Y30498D01*
X1252360D01*
Y33502D01*
X1250860D01*
Y34002D01*
X1249910D01*
Y36405D01*
X1249726Y36588D01*
Y37772D01*
X1249928D01*
Y45874D01*
X1249726D01*
Y46435D01*
X1249739Y46468D01*
G03X1247861Y48241I-1314J489D01*
G02X1247300Y48607I-161J366D01*
G01Y63200D01*
X1248200Y64100D01*
X1253200D01*
X1253500Y63800D01*
X1253618D01*
Y55882D01*
X1253904D01*
Y55597D01*
X1253875Y55549D01*
G03X1256361I1243J-750D01*
G01X1256332Y55597D01*
Y55882D01*
X1256622D01*
Y63984D01*
X1256423D01*
G02X1256141Y64668I0J400D01*
G03X1254555Y67037I-1023J1031D01*
G02X1254000Y67406I-155J369D01*
G01Y67900D01*
X1253600Y68300D01*
X1252500D01*
X1252302Y68498D01*
X1252360D01*
Y71502D01*
X1252300D01*
Y71700D01*
X1251800Y72200D01*
X1249910D01*
Y74205D01*
X1249726Y74388D01*
Y75572D01*
X1249928D01*
Y83674D01*
X1249726D01*
Y84235D01*
X1249739Y84268D01*
G03X1247861Y86041I-1314J489D01*
G02X1247300Y86407I-161J366D01*
G01Y103100D01*
X1248700Y104500D01*
X1253085D01*
G03X1255544Y105846I1215J700D01*
G01X1255476Y105976D01*
X1259400Y109900D01*
Y115576D01*
X1260000Y116176D01*
X1260039D01*
G03X1260932Y116166I461J1324D01*
G01X1260962Y116176D01*
X1268470D01*
X1268488Y116158D01*
X1269638D01*
Y115872D01*
X1272640D01*
Y116176D01*
X1273400D01*
X1273595Y116372D01*
X1273640D01*
Y118252D01*
X1275230D01*
X1275478Y118500D01*
X1275600D01*
X1275800Y118300D01*
Y117000D01*
X1276624Y116176D01*
X1277080D01*
X1277090Y116175D01*
G03X1277370I140J1395D01*
G01X1277380Y116176D01*
X1281556D01*
X1287880Y122500D01*
X1315000D01*
X1315500Y122000D01*
Y91000D01*
X1309226Y84726D01*
X1309184Y84711D01*
G03X1308289Y83816I516J-1411D01*
G01X1308274Y83774D01*
X1308000Y83500D01*
X1300240D01*
X1300198Y83645D01*
G03X1297606Y82265I-1444J-411D01*
G01X1297724Y82124D01*
X1296000Y80400D01*
Y56800D01*
X1294612Y55412D01*
Y49159D01*
X1295651Y48120D01*
X1295666Y48089D01*
G03X1298143Y48000I1262J611D01*
G01X1301500D01*
X1301560Y47940D01*
Y45102D01*
X1300098D01*
Y44599D01*
X1299602Y44102D01*
X1299598D01*
Y44098D01*
X1298000Y42500D01*
Y38618D01*
G02X1297451Y38247I-400J0D01*
G03Y35553I-543J-1347D01*
G02X1298000Y35182I149J-371D01*
G01Y32002D01*
X1295998D01*
Y32000D01*
X1295535D01*
X1294000Y30465D01*
Y2622D01*
G02X1293404Y2273I-400J0D01*
G03Y-257I-712J-1265D01*
G02X1294000Y-606I196J-349D01*
G01Y-10652D01*
G02X1293801Y-10852I-200J0D01*
G03X1291920Y-11637I15J-2681D01*
G01X1288846Y-14710D01*
Y-15020D01*
X1288430Y-15437D01*
X1288303Y-15379D01*
G03X1286929Y-15469I-603J-1321D01*
G01X1286880Y-15500D01*
X1286672D01*
G02X1286290Y-14979I-1J400D01*
G03X1283737Y-13526I-1431J454D01*
G02X1283188Y-13573I-299J266D01*
G03X1280962Y-13978I-936J-1174D01*
G02X1280275I-344J205D01*
G03X1277316Y-15040I-1375J-822D01*
G02X1276921Y-15500I-395J-60D01*
G01X1274000D01*
G37*
G36*
G01X1310852Y164008D02*
X1315196Y159664D01*
Y148606D01*
X1314490Y147900D01*
X1301426D01*
X1299500Y145974D01*
X1282426D01*
X1279396Y149004D01*
X1279381Y149043D01*
G03X1277119Y149640I-1351J-533D01*
G01X1276387D01*
X1275046Y148300D01*
X1266059D01*
X1266016Y148321D01*
G03X1264712I-652J-1297D01*
G01X1264669Y148300D01*
X1263869D01*
G03X1261269I-1300J-1099D01*
G01X1252898D01*
X1247552Y153646D01*
Y155397D01*
X1244874Y158076D01*
X1227022D01*
X1225814Y159283D01*
Y185454D01*
X1226540Y186180D01*
X1242729D01*
X1251821Y177088D01*
X1251700Y176947D01*
G03X1253747Y174900I1100J-947D01*
G01X1253888Y175021D01*
X1257944Y170965D01*
X1257986D01*
Y169146D01*
G03X1260414I1214J-796D01*
G01Y170965D01*
X1262086D01*
Y170336D01*
X1262052Y170285D01*
G03X1264548I1248J-835D01*
G01X1264514Y170336D01*
Y170965D01*
X1265363D01*
G02X1265728Y170400I1J-400D01*
G03X1268372I1322J-600D01*
G02X1268737Y170965I364J165D01*
G01X1284441D01*
X1284486Y170828D01*
G03X1284488Y170821I3606J1026D01*
G03X1287919Y168196I3580J1124D01*
G01X1287997Y168193D01*
X1289033Y167157D01*
X1307703D01*
X1308301Y166559D01*
G02X1308293Y165985I-283J-283D01*
G03X1310187Y163788I997J-1055D01*
G03X1310722Y163942I-127J1447D01*
G01X1310852Y164008D01*
G37*
G36*
G01X1317153Y163600D02*
G02X1316785Y164158I0J400D01*
G03X1313920Y166205I-1655J712D01*
G02X1313368Y166219I-269J296D01*
G01X1311284Y168303D01*
X1307685D01*
G02X1307391Y168975I-1J400D01*
G03X1305378Y170926I-1028J953D01*
G02X1304818Y170925I-281J285D01*
G03X1302806Y168974I-980J-1003D01*
G02X1302511Y168303I-295J-271D01*
G01X1301647D01*
G02X1301348Y168969I0J400D01*
G03X1299252I-1048J931D01*
G02X1298953Y168303I-299J-266D01*
G01X1290197D01*
X1289896Y168604D01*
X1290053Y168761D01*
X1290072Y168773D01*
G03X1285022Y174135I-2004J3172D01*
G02X1284414Y174086I-325J234D01*
G01X1282080Y176420D01*
X1261920D01*
X1233354Y204986D01*
Y216721D01*
X1235238Y218604D01*
X1236179D01*
X1237896Y220322D01*
X1238700D01*
X1243716Y225338D01*
X1246377D01*
X1250378Y229340D01*
X1259160D01*
X1290100Y198400D01*
X1321300D01*
X1331050Y188650D01*
X1356350D01*
X1366800Y178200D01*
X1371198D01*
Y178198D01*
X1380602D01*
X1382500Y176300D01*
Y164900D01*
X1381200Y163600D01*
X1317153D01*
G37*
G36*
G01X1263500Y485000D02*
X1259400Y489100D01*
Y494000D01*
X1257080Y496320D01*
X1253380D01*
X1253120Y496580D01*
Y498130D01*
X1252410Y498840D01*
X1250260D01*
X1250000Y499100D01*
Y514300D01*
X1247300Y517000D01*
Y526000D01*
X1248100Y526800D01*
X1250271D01*
Y519082D01*
X1250470D01*
Y518521D01*
X1250457Y518488D01*
G03X1253085I1314J-489D01*
G01X1253072Y518521D01*
Y519082D01*
X1253906D01*
Y518798D01*
X1253877Y518750D01*
G03X1256363I1243J-750D01*
G01X1256334Y518798D01*
Y519082D01*
X1256622D01*
Y527186D01*
X1253452D01*
G02X1253169Y527869I0J400D01*
G01X1254300Y529000D01*
Y530400D01*
X1252700Y532000D01*
Y534700D01*
X1252300Y535100D01*
X1249500D01*
X1249253Y535347D01*
G02X1249289Y535945I283J283D01*
G03X1249376Y538079I-864J1104D01*
G02X1249648Y538772I272J293D01*
G01X1249928D01*
Y546876D01*
X1249726D01*
Y547435D01*
X1249739Y547468D01*
G03X1247861Y549241I-1314J489D01*
G02X1247300Y549607I-161J366D01*
G01Y564200D01*
X1248200Y565100D01*
X1253200D01*
X1253500Y564800D01*
X1253618D01*
Y556882D01*
X1253906D01*
Y555940D01*
G03X1256334I1214J-796D01*
G01Y556882D01*
X1256622D01*
Y564986D01*
X1254335D01*
X1254232Y565232D01*
X1254300Y565300D01*
Y567100D01*
X1252650Y568750D01*
Y572850D01*
X1252300Y573200D01*
X1249724D01*
G02X1249436Y573877I0J400D01*
G03X1249376Y575879I-1011J972D01*
G02X1249648Y576572I272J293D01*
G01X1249928D01*
Y584676D01*
X1249726D01*
Y585235D01*
X1249739Y585268D01*
G03X1247861Y587041I-1314J489D01*
G02X1247300Y587407I-161J366D01*
G01Y601400D01*
X1246582Y602118D01*
Y602786D01*
X1245914D01*
X1243000Y605700D01*
Y612049D01*
X1243017Y612088D01*
G03Y613210I-1285J561D01*
G01X1243000Y613249D01*
Y619400D01*
X1243221Y619622D01*
X1280561D01*
X1283400Y616782D01*
Y613094D01*
G03Y604016I4003J-4539D01*
G01Y594218D01*
G03X1282832Y585713I4003J-4539D01*
G02X1282545Y585051I-302J-262D01*
G03X1281566Y582581I55J-1451D01*
G02Y582019I-285J-281D01*
G03X1282914Y579582I1034J-1019D01*
G02X1283400Y579192I86J-390D01*
G01Y575294D01*
G03Y566216I4003J-4539D01*
G01Y556418D01*
G03X1283334Y547399I4003J-4539D01*
G01X1283400Y547339D01*
Y546200D01*
X1285200Y544400D01*
X1295500D01*
X1300900Y539000D01*
X1312100D01*
X1313900Y537200D01*
Y523000D01*
X1318300Y518600D01*
Y503900D01*
X1316783Y502383D01*
X1316699Y502385D01*
G03X1315763Y502048I-24J-1402D01*
G01X1315707Y502000D01*
X1315258D01*
X1315201Y502050D01*
G03X1313289Y502000I-929J-1050D01*
G01X1312755D01*
G03X1310789I-983J-1000D01*
G01X1293990D01*
X1282970Y490980D01*
X1279870D01*
G02X1279472Y491420I0J400D01*
G03X1276484I-1494J151D01*
G02X1276086Y490980I-398J-40D01*
G01X1273267D01*
X1272834Y491414D01*
X1268796D01*
X1267065Y493144D01*
X1266202D01*
Y493644D01*
X1263198D01*
Y490642D01*
X1263698D01*
Y489642D01*
X1265702D01*
Y490642D01*
X1266202D01*
Y490692D01*
G02X1266543Y490834I200J0D01*
G01X1267966Y489410D01*
X1268500D01*
Y487945D01*
X1268394Y487889D01*
G03X1268258Y485493I656J-1239D01*
G01X1268273Y485483D01*
X1268428Y485328D01*
X1268100Y485000D01*
X1263500D01*
G37*
G36*
G01X1340093Y-20793D02*
X1337000Y-17700D01*
Y37293D01*
X1341571Y41864D01*
X1347219D01*
G02X1347548Y41236I0J-400D01*
G03X1350304Y39240I1397J-972D01*
G02X1350894Y39294I320J-241D01*
G03X1353154Y41241I1014J1108D01*
G02X1353486Y41864I332J223D01*
G01X1363701D01*
X1364398Y41167D01*
Y33335D01*
X1363397Y32334D01*
Y12977D01*
X1363398Y12976D01*
Y12698D01*
X1363676D01*
X1364662Y11712D01*
Y1948D01*
X1363298Y584D01*
Y-1606D01*
X1362988D01*
Y-6608D01*
X1363298D01*
Y-8106D01*
X1362988D01*
Y-13108D01*
X1363298D01*
Y-14706D01*
X1362988D01*
Y-19749D01*
X1361944Y-20793D01*
X1340093D01*
G37*
G36*
G01X1329500Y41000D02*
Y-16600D01*
X1328100Y-18000D01*
X1304957D01*
G03X1302591I-1183J-842D01*
G01X1301500D01*
X1300306Y-16806D01*
X1300436Y-16665D01*
G03X1298384Y-14613I-1067J985D01*
G01X1298243Y-14743D01*
X1297000Y-13500D01*
Y15900D01*
X1298700Y17600D01*
X1304500D01*
X1305700Y18800D01*
Y21647D01*
X1307322Y23268D01*
Y24522D01*
X1308100Y25300D01*
Y40200D01*
X1307534Y40766D01*
Y41283D01*
X1307100Y41718D01*
Y48400D01*
X1310200Y51500D01*
X1321331D01*
X1323065Y49765D01*
G03X1324492Y49371I1061J1062D01*
G01X1324602Y49398D01*
X1324750Y49250D01*
X1333250D01*
X1333500Y49000D01*
Y45000D01*
X1329500Y41000D01*
G37*
G36*
G01X1326786Y72616D02*
X1326531Y72361D01*
X1326311Y72142D01*
X1325902Y71733D01*
Y70786D01*
G03X1326137Y69962I1565J1D01*
G03X1326386Y69655I1330J824D01*
G02X1326399Y69111I-287J-279D01*
G03X1325949Y67798I1101J-1111D01*
G03X1326398Y66889I1551J201D01*
G02X1326415Y66339I-281J-284D01*
G03X1326025Y65015I1085J-1039D01*
G03X1328878Y65899I1475J286D01*
G02X1329226Y66436I376J138D01*
G01X1330100D01*
G03X1330451Y66475I4J1564D01*
G03X1330514Y66491I-353J1524D01*
G01X1330540Y66498D01*
X1331602D01*
Y66998D01*
X1332098D01*
Y66498D01*
X1335102D01*
Y72578D01*
X1335744Y73220D01*
X1335993Y72971D01*
X1335919Y72838D01*
G03X1336472Y70573I1481J-838D01*
G03X1337005Y70344I929J1427D01*
G03X1337221Y73693I395J1656D01*
G02X1336897Y74373I-41J398D01*
G01X1337912Y75388D01*
G03X1338279Y76912I-1062J1062D01*
G02X1338631Y77436I380J125D01*
G01X1344988D01*
X1345053Y77500D01*
X1346513D01*
X1350794Y81781D01*
X1350920Y81724D01*
G03X1352776Y83580I580J1276D01*
G01X1352719Y83706D01*
X1354892Y85879D01*
G02X1355522Y85795I283J-282D01*
G03X1358610Y86087I1478J844D01*
G03X1358655Y87036I-1610J552D01*
G03X1358505Y87434I-1655J-396D01*
G02X1358864Y88010I359J176D01*
G01X1359243D01*
G02X1359566Y87375I0J-400D01*
G03X1361834I1134J-825D01*
G02X1362157Y88010I323J235D01*
G01X1366321D01*
G02X1366627Y87353I0J-400D01*
G03X1368773I1073J-903D01*
G02X1369079Y88010I306J257D01*
G01X1369398D01*
X1370636Y86772D01*
X1370620Y86671D01*
G03X1371557Y84869I1680J-271D01*
G01Y79464D01*
X1370693Y78600D01*
X1368350D01*
X1367550Y77800D01*
Y57050D01*
X1362850Y52350D01*
X1345098D01*
G02X1344748Y52944I0J400D01*
G03X1341772I-1488J826D01*
G02X1341422Y52350I-350J-194D01*
G01X1328770D01*
G03X1326547Y52708I-1269J-800D01*
G01X1326407Y52593D01*
X1323500Y55500D01*
X1299500D01*
X1297500Y57500D01*
Y72172D01*
G02X1297995Y72560I400J-1D01*
G03Y75440I427J1440D01*
G02X1297500Y75828I-95J389D01*
G01Y76000D01*
X1299000Y77500D01*
X1303841D01*
G03X1304670Y77262I830J1327D01*
G01X1304685D01*
G03X1305514Y77500I-1J1565D01*
G01X1314907D01*
X1314972Y77436D01*
X1334774D01*
G02X1335029Y76753I-28J-399D01*
G01X1332098Y73822D01*
Y72512D01*
X1331602D01*
Y73012D01*
X1330566D01*
X1330514Y73019D01*
X1330502Y73022D01*
G03X1330100Y73074I-400J-1512D01*
G01X1327892D01*
G03X1326786Y72616I0J-1564D01*
G37*
G36*
G01X1319250Y98254D02*
X1318700Y98804D01*
Y108948D01*
X1318702D01*
Y113952D01*
X1318700D01*
Y116948D01*
X1318702D01*
Y121952D01*
X1318700D01*
Y124000D01*
X1318200Y124500D01*
X1303408D01*
X1303384Y124633D01*
G03X1300416I-1484J-233D01*
G01X1300392Y124500D01*
X1284500D01*
X1282500Y126500D01*
Y141500D01*
X1285436Y144436D01*
X1294287D01*
X1294311Y144263D01*
G03X1296721Y143489I1389J187D01*
G02X1297298Y143479I284J-282D01*
G03X1298663Y143021I1102J1021D01*
G03X1299892Y144331I-263J1479D01*
G01X1299900Y144400D01*
X1301900Y146400D01*
X1302696D01*
Y146378D01*
X1304698D01*
Y146400D01*
X1306196D01*
Y146378D01*
X1308198D01*
Y146400D01*
X1308601D01*
G02X1308837Y146323I0J-400D01*
G01X1311363D01*
G02X1311599Y146400I236J-323D01*
G01X1315180D01*
X1317408Y148628D01*
Y160298D01*
X1318810Y161700D01*
X1382100D01*
X1383600Y163200D01*
Y176700D01*
X1381800Y178500D01*
X1381716D01*
X1381015Y179202D01*
X1371700D01*
Y188800D01*
X1372200Y189300D01*
X1382390D01*
X1391800Y179890D01*
Y148900D01*
X1386900Y144000D01*
X1377900D01*
X1376902Y143002D01*
X1376498D01*
Y131585D01*
X1376700Y131384D01*
Y130750D01*
X1378150Y129300D01*
X1386900D01*
X1387900Y128300D01*
Y120000D01*
X1385400Y117500D01*
X1384502D01*
Y117502D01*
X1379498D01*
Y117500D01*
X1379100D01*
X1378300Y116700D01*
Y113505D01*
X1377402Y112607D01*
X1373409D01*
X1373408Y112608D01*
X1370058D01*
X1366050Y108600D01*
Y104497D01*
X1364714Y103161D01*
X1349004D01*
X1347316Y104849D01*
Y108342D01*
X1346335Y109323D01*
X1336130D01*
X1327112Y100305D01*
G02X1326451Y100457I-283J283D01*
G03X1324392Y101196I-1326J-456D01*
G03X1324202Y98946I733J-1195D01*
G02X1323928Y98254I-274J-292D01*
G01X1319250D01*
G37*
G36*
G01X1297250Y202920D02*
X1296630Y203540D01*
Y217998D01*
X1297002D01*
Y220002D01*
X1296630D01*
Y220170D01*
X1294470Y222330D01*
Y223620D01*
X1294670Y223820D01*
X1302880D01*
X1306518Y220182D01*
X1320662D01*
X1321549Y219295D01*
Y216051D01*
X1321903Y215697D01*
X1321911Y215686D01*
G03X1322185Y215412I1119J845D01*
G01X1322196Y215404D01*
X1325110Y212490D01*
Y206810D01*
X1321220Y202920D01*
X1297250D01*
G37*
G36*
G01X1317000Y362000D02*
X1315506Y363494D01*
Y371723D01*
X1315726Y372272D01*
X1315506Y379168D01*
Y415841D01*
X1312100Y419247D01*
Y420750D01*
X1314950Y423600D01*
X1338400D01*
X1341562Y420438D01*
Y391326D01*
X1339093Y388857D01*
Y371248D01*
X1329845Y362000D01*
X1317000D01*
G37*
G36*
G01X1346500Y366100D02*
X1344700Y367900D01*
Y416400D01*
X1344650Y416450D01*
Y422200D01*
X1341877Y424973D01*
X1314528D01*
X1314030Y425472D01*
X1307316D01*
X1301456Y431331D01*
G02X1301465Y431905I283J283D01*
G03X1299342Y434028I-1027J1096D01*
G02X1298768Y434019I-291J274D01*
G01X1298288Y434499D01*
Y443634D01*
X1302677Y448023D01*
X1329152D01*
X1332624Y451495D01*
Y458664D01*
X1331411Y459877D01*
X1331007D01*
X1330988Y459896D01*
X1330318D01*
X1329101Y461114D01*
Y462437D01*
G02X1329484Y462836I400J0D01*
G03Y465838I-65J1501D01*
G02X1329101Y466237I17J399D01*
G01Y467437D01*
G02X1329484Y467836I400J0D01*
G03Y470838I-65J1501D01*
G02X1329101Y471237I17J399D01*
G01Y489601D01*
X1329125Y489625D01*
Y495825D01*
X1330100Y496800D01*
X1340766D01*
X1340784Y496797D01*
G03X1341316I266J1478D01*
G01X1341334Y496800D01*
X1344516D01*
X1344531Y496798D01*
G03X1344991I230J1484D01*
G01X1345006Y496800D01*
X1349640D01*
X1351086Y495354D01*
Y477879D01*
X1352570Y476394D01*
Y474030D01*
X1353106Y473494D01*
X1353121Y473465D01*
G03X1353786Y472800I1341J676D01*
G01X1353815Y472785D01*
X1361496Y465104D01*
G02Y464539I-283J-282D01*
G03X1363621Y462414I1064J-1061D01*
G02X1364186I282J-283D01*
G01X1365550Y461050D01*
Y456450D01*
X1368300Y453700D01*
Y447450D01*
X1367252Y446402D01*
X1361761D01*
G02X1361392Y446957I0J400D01*
G03X1359262Y446376I-1292J543D01*
G02X1359306Y445773I-239J-321D01*
G01X1359283Y445750D01*
Y425617D01*
X1361853Y423047D01*
X1382347D01*
X1383800Y424500D01*
X1390100D01*
X1391300Y423300D01*
Y410516D01*
X1390900Y410116D01*
X1360914D01*
X1359986Y409188D01*
Y403377D01*
X1360375Y402988D01*
X1365910D01*
X1366718Y402180D01*
Y396512D01*
X1365800Y395594D01*
Y389202D01*
X1365698D01*
Y384198D01*
X1365800D01*
Y382702D01*
X1365798D01*
Y377698D01*
X1365800D01*
Y376002D01*
X1365698D01*
Y370998D01*
X1365800D01*
Y366500D01*
X1365400Y366100D01*
X1346500D01*
G37*
G36*
G01X1298500Y450400D02*
X1297876Y451024D01*
Y482512D01*
X1298947Y483583D01*
X1299059Y483551D01*
G03X1300688Y485709I391J1399D01*
G01Y495829D01*
X1301759Y496900D01*
X1319500D01*
X1321023Y495377D01*
Y479067D01*
G02X1320427Y478718I-400J0D01*
G03Y476276I-689J-1221D01*
G02X1321023Y475927I196J-349D01*
G01Y473874D01*
G02X1320418Y473531I-400J0D01*
G03Y471123I-719J-1204D01*
G02X1321023Y470780I205J-343D01*
G01Y465927D01*
X1320865Y465893D01*
G03Y463055I307J-1419D01*
G01X1321023Y463021D01*
Y460918D01*
X1323046Y458895D01*
X1330573D01*
X1331397Y458071D01*
Y451839D01*
X1329958Y450400D01*
X1298500D01*
G37*
G36*
G01X1344206Y510644D02*
X1343350Y511500D01*
Y519050D01*
X1341650Y520750D01*
X1320250D01*
X1317100Y523900D01*
Y535000D01*
X1320500Y538400D01*
X1339800D01*
X1342550Y541150D01*
X1352950D01*
Y541100D01*
X1380500D01*
X1381800Y539800D01*
Y534700D01*
X1382900Y533600D01*
X1386900D01*
X1386936Y533564D01*
Y529636D01*
X1386802Y529502D01*
X1381998D01*
Y529500D01*
X1379002D01*
Y529502D01*
X1373998D01*
Y529500D01*
X1373300D01*
X1372302Y528502D01*
X1370498D01*
Y528500D01*
X1367914D01*
Y529150D01*
X1362912D01*
Y528500D01*
X1354578D01*
X1353302Y527224D01*
Y520269D01*
X1353623Y519948D01*
Y514840D01*
X1352373Y513590D01*
Y513288D01*
X1352370D01*
Y511286D01*
X1352373D01*
Y510907D01*
X1352110Y510644D01*
X1344206D01*
G37*
G36*
G01X1325208Y497867D02*
X1324200Y498875D01*
Y512600D01*
X1326074Y514474D01*
X1337610D01*
X1337686Y514398D01*
X1340886D01*
X1342100Y513185D01*
Y510700D01*
X1341500Y510100D01*
X1338312D01*
X1337233Y511179D01*
X1332387D01*
X1330989Y509781D01*
Y505221D01*
X1332949Y503261D01*
X1347761D01*
X1353886Y509386D01*
Y513400D01*
X1354486Y514000D01*
X1359600D01*
X1360490Y513110D01*
Y508603D01*
X1351086Y499198D01*
Y498686D01*
X1350267Y497867D01*
X1346663D01*
G02X1346263Y498270I0J400D01*
G03X1343259I-1502J12D01*
G02X1342859Y497867I-400J-3D01*
G01X1342539D01*
Y498079D01*
X1342541Y498091D01*
G03X1339548Y498269I-1491J183D01*
G02X1339148Y497867I-400J-2D01*
G01X1325208D01*
G37*
G36*
G01X1331500Y548400D02*
X1329204Y550696D01*
Y564208D01*
X1330750Y565754D01*
Y616050D01*
X1335700Y621000D01*
X1368700D01*
X1369350Y620350D01*
Y618297D01*
G02X1368735Y617960I-400J0D01*
G03X1368250Y618102I-486J-760D01*
G01X1366650D01*
G03X1365748Y617200I0J-902D01*
G01Y615600D01*
G03X1366650Y614698I902J0D01*
G01X1367261D01*
X1367505Y614455D01*
X1366975Y613925D01*
X1367000Y613900D01*
Y589300D01*
X1368450Y587850D01*
Y584150D01*
X1367436Y583136D01*
Y574964D01*
X1367498Y574902D01*
Y573654D01*
X1367500D01*
Y571658D01*
X1367498D01*
Y566654D01*
X1367500D01*
Y565158D01*
X1367498D01*
Y560154D01*
X1367500D01*
Y559996D01*
X1368738Y558758D01*
Y552738D01*
X1368500Y552500D01*
X1362600D01*
X1358500Y548400D01*
X1331500D01*
G37*
G36*
G01X1297814Y549847D02*
Y575944D01*
X1296052Y577706D01*
G02X1296066Y578285I283J283D01*
G03X1295758Y580649I-976J1075D01*
G01X1295650Y580705D01*
Y600750D01*
X1298500Y603600D01*
Y610300D01*
X1303448Y615248D01*
X1306002D01*
Y616000D01*
X1307500D01*
X1310000Y618500D01*
X1310824D01*
G03X1312928I1052J1001D01*
G01X1313424D01*
G03X1315528I1052J1001D01*
G01X1328000D01*
X1329500Y617000D01*
Y566500D01*
X1325500Y562500D01*
Y550900D01*
X1323550Y548950D01*
X1320157D01*
X1320059Y549048D01*
X1298613D01*
X1297814Y549847D01*
G37*
G36*
G01X1367700Y-19900D02*
X1366300Y-18500D01*
Y1174D01*
X1368224D01*
G03X1369907Y-41I2365J1502D01*
G02X1370196Y-530I-98J-388D01*
G03X1370500Y-1874I1454J-378D01*
G02X1370487Y-2403I-306J-257D01*
G03X1370457Y-4411I1102J-1021D01*
G02Y-4937I-302J-263D01*
G03X1372721I1132J-987D01*
G02Y-4411I302J263D01*
G03X1372739Y-2457I-1132J988D01*
G02X1372752Y-1928I306J257D01*
G03X1373027Y-1508I-1102J1021D01*
G02X1373620Y-1339I366J-160D01*
G03X1377134Y-1071I1591J2306D01*
G02X1377793Y-1252I274J-291D01*
G03X1377932Y-1636I2886J827D01*
G03X1381189Y-6565I2076J-2169D01*
G03X1382952Y-4394I961J1021D01*
G03X1382754Y-2591I-2944J589D01*
G03X1382952Y1538I-2076J2169D01*
G03X1382372Y5117I-2652J1407D01*
G03X1378451Y6893I-2153J464D01*
G02X1377890Y6811I-321J239D01*
G03X1377028Y7259I-1797J-2405D01*
G03X1375150Y8930I-1352J371D01*
G02X1374600Y9300I-150J371D01*
G01Y10600D01*
X1372700Y12500D01*
X1366402D01*
Y17702D01*
X1366350D01*
Y19198D01*
X1366402D01*
Y24202D01*
X1366350D01*
Y25698D01*
X1366402D01*
Y30702D01*
X1366350D01*
Y31700D01*
X1367548Y32898D01*
X1368698D01*
Y32498D01*
X1369248D01*
X1369300Y32461D01*
G03X1370185Y32043I1599J2239D01*
G02X1370464Y31540I-104J-386D01*
G03X1370768Y30113I1436J-440D01*
G02Y29587I-302J-263D01*
G03Y27613I1132J-987D01*
G02Y27087I-302J-263D01*
G03X1373032I1132J-987D01*
G02Y27613I302J263D01*
G03Y29587I-1132J987D01*
G02Y30113I302J263D01*
G03X1372966Y32158I-1132J987D01*
G01X1372908Y32216D01*
Y32498D01*
X1373102D01*
Y33050D01*
G03X1373194Y33180I-2199J1654D01*
G01X1376350D01*
X1377310Y34140D01*
Y36761D01*
X1377479Y36788D01*
G03X1379058Y41947I-470J2965D01*
G02X1379299Y42638I273J292D01*
G03X1381508Y44897I-189J2395D01*
G02X1381721Y45085I200J-11D01*
G03X1382244Y47819I96J1399D01*
G02X1382083Y48483I122J381D01*
G01X1384800Y51200D01*
X1384900D01*
X1386564Y52864D01*
Y60648D01*
X1383700Y63512D01*
Y78500D01*
X1386700Y81500D01*
X1400400D01*
X1400900Y81000D01*
Y79700D01*
X1403100Y77500D01*
Y52902D01*
G02X1402700Y52502I-400J0D01*
G03Y49698I0J-1402D01*
G02X1403100Y49298I0J-400D01*
G01Y48030D01*
G03Y38202I3446J-4914D01*
G01Y31263D01*
X1397356Y25519D01*
Y15858D01*
X1394080Y12582D01*
Y3580D01*
X1389700Y-800D01*
Y-4180D01*
G02X1389077Y-4512I-400J0D01*
G03Y-6838I-783J-1163D01*
G02X1389700Y-7170I223J-332D01*
G01Y-18500D01*
X1388300Y-19900D01*
X1367700D01*
G37*
G36*
G01X1388560Y87235D02*
X1388508Y87287D01*
Y87852D01*
X1388532D01*
Y92856D01*
X1388508D01*
Y101852D01*
X1388532D01*
Y106250D01*
X1399150D01*
X1399424Y106524D01*
X1399440D01*
X1401502Y108585D01*
Y108602D01*
X1401900Y109000D01*
Y110900D01*
X1402600Y111600D01*
X1411900D01*
X1413000Y110500D01*
Y99100D01*
X1410400Y96500D01*
X1402508D01*
X1393738Y87730D01*
X1393692D01*
X1393197Y87235D01*
X1388560D01*
G37*
G36*
G01X1415673Y98294D02*
X1446408D01*
X1447245Y97456D01*
Y77466D01*
X1446079Y76300D01*
X1406700D01*
X1402200Y80800D01*
Y94000D01*
X1402800Y94600D01*
X1411979D01*
X1415673Y98294D01*
G37*
G36*
G01X1381888Y87550D02*
X1381500Y87938D01*
Y93283D01*
X1379610Y95173D01*
X1379600D01*
X1379473Y95300D01*
X1371700D01*
X1367129Y99871D01*
Y107729D01*
X1369900Y110500D01*
X1379100D01*
X1379500Y110900D01*
Y114000D01*
X1379998Y114498D01*
X1384502D01*
Y114500D01*
X1385000D01*
X1385900Y115400D01*
X1396564D01*
X1396593Y115235D01*
G03X1396803Y114412I5906J1069D01*
G02X1396589Y113923I-380J-125D01*
G03X1398223Y111578I605J-1320D01*
G02X1398756Y111609I284J-282D01*
G03X1400500Y110641I3744J4691D01*
G01Y109000D01*
X1399025Y107525D01*
X1386276D01*
X1385606Y106856D01*
X1385530D01*
Y101852D01*
X1385577D01*
Y92856D01*
X1385530D01*
Y87761D01*
X1385318Y87550D01*
X1381888D01*
G37*
G36*
G01X1391100Y121100D02*
X1389500Y122700D01*
Y128500D01*
X1387500Y130500D01*
X1379000D01*
X1377500Y132000D01*
Y142000D01*
X1410800D01*
X1415500Y137300D01*
Y123846D01*
X1402928D01*
X1402645Y124129D01*
X1402650Y124218D01*
G03X1401228Y125752I-1450J82D01*
G02X1400839Y126205I7J400D01*
G03X1399372Y124948I-1439J195D01*
G02X1399761Y124495I-7J-400D01*
G03X1399957Y123550I1439J-194D01*
G01X1399986Y123502D01*
Y123353D01*
X1400055Y123283D01*
G02X1399914Y122942I-142J-141D01*
G01X1399838D01*
X1399733Y122837D01*
X1399700Y122822D01*
G03X1398978Y122100I600J-1322D01*
G01X1398963Y122067D01*
X1397996Y121100D01*
X1391100D01*
G37*
G36*
G01X1384700Y330900D02*
X1384302Y331298D01*
Y333002D01*
X1384300D01*
Y333457D01*
X1385042Y334198D01*
X1385302D01*
Y334458D01*
X1385305Y334462D01*
Y339815D01*
X1384302Y340818D01*
Y342302D01*
X1384500Y342500D01*
X1389000D01*
X1389550Y341950D01*
Y333059D01*
X1389189Y332698D01*
X1387882D01*
X1387030Y331846D01*
Y331291D01*
X1386639Y330900D01*
X1384700D01*
G37*
G36*
G01X1357200Y351300D02*
X1357400Y351500D01*
X1371450D01*
Y337450D01*
X1371200Y337200D01*
X1357400D01*
X1357200Y337400D01*
Y351300D01*
G37*
G36*
G01X1380500Y328000D02*
X1379300Y329200D01*
Y331726D01*
G03X1378883Y334217I-1334J1057D01*
G01X1377550Y335550D01*
Y336450D01*
X1375885Y338115D01*
X1372887D01*
X1372552Y338450D01*
Y339054D01*
X1372959Y339462D01*
X1375852D01*
Y339500D01*
X1377400D01*
X1378600Y338300D01*
X1378900D01*
X1380700Y336500D01*
X1383700D01*
X1383800Y336400D01*
Y336002D01*
X1383798D01*
Y334398D01*
X1382700Y333300D01*
Y328200D01*
X1382500Y328000D01*
X1380500D01*
G37*
G36*
G01X1396752Y362004D02*
X1395133Y363624D01*
X1391068D01*
Y365219D01*
X1392819Y366970D01*
X1401059D01*
X1403298Y369209D01*
Y381038D01*
X1404188Y381928D01*
X1406886D01*
X1406958Y381856D01*
X1407648D01*
X1408179Y381325D01*
Y364903D01*
X1405280Y362004D01*
X1396752D01*
G37*
G36*
G01X1372385Y390656D02*
G02X1372781Y390199I0J-400D01*
G03X1373118Y389018I1487J-214D01*
G02X1373105Y388489I-306J-257D01*
G03X1373075Y386481I1102J-1021D01*
G02Y385955I-302J-263D01*
G03X1375339I1132J-987D01*
G02Y386481I302J263D01*
G03X1375357Y388435I-1132J988D01*
G02X1375370Y388964I306J257D01*
G03X1374986Y391305I-1102J1021D01*
G02X1374894Y391939I191J351D01*
G01X1375279Y392324D01*
Y394853D01*
G03X1375627Y397691I-78J1450D01*
G02X1375381Y398238I118J382D01*
G03X1372768Y400270I-1551J702D01*
G01X1372628Y400158D01*
X1372252Y400534D01*
G02X1372247Y401094I283J283D01*
G03X1370702Y403464I-1047J1006D01*
G01X1370582Y403420D01*
X1369910Y404092D01*
X1361493D01*
X1361120Y404465D01*
Y408850D01*
X1361368Y409098D01*
X1364310D01*
G03X1364496I93J1398D01*
G01X1366753D01*
X1366769Y409096D01*
G03X1367199I215J1385D01*
G01X1367215Y409098D01*
X1377560D01*
X1377584Y409092D01*
G03X1378272I344J1359D01*
G01X1378296Y409098D01*
X1380205D01*
X1380221Y409095D01*
G03X1380677I228J1384D01*
G01X1380693Y409098D01*
X1382562D01*
X1382581Y409094D01*
G03X1383117I268J1377D01*
G01X1383136Y409098D01*
X1387841D01*
X1387857Y409095D01*
G03X1388313I228J1384D01*
G01X1388329Y409098D01*
X1398090D01*
X1399445Y407743D01*
G03X1402092Y403288I5978J538D01*
G01Y369419D01*
X1400644Y367972D01*
X1392404D01*
X1392020Y367587D01*
X1383430D01*
X1383408Y367762D01*
G03X1380626I-1391J-178D01*
G01X1380604Y367587D01*
X1371169D01*
X1368750Y370006D01*
Y377698D01*
X1368802D01*
Y382702D01*
X1368750D01*
Y389822D01*
X1369584Y390656D01*
X1372385D01*
G37*
G36*
G01X1361847Y424653D02*
X1360700Y425800D01*
Y442798D01*
X1360802D01*
Y444801D01*
X1361400Y445400D01*
X1377870D01*
X1379070Y444200D01*
X1379330D01*
X1379341Y444190D01*
X1380360D01*
X1381540Y443010D01*
Y440590D01*
X1383150Y438980D01*
X1383682D01*
X1383707Y438956D01*
X1388993D01*
X1391500Y436448D01*
Y426883D01*
X1390717Y426100D01*
X1388502D01*
Y426102D01*
X1386498D01*
Y426100D01*
X1382947D01*
X1381500Y424653D01*
X1361847D01*
G37*
G36*
G01X1368892Y514584D02*
X1362961Y520515D01*
X1354472D01*
X1354304Y520684D01*
Y526809D01*
X1354780Y527286D01*
X1362912D01*
Y526148D01*
X1367914D01*
Y527286D01*
X1370498D01*
Y526998D01*
X1372502D01*
Y527286D01*
X1373998D01*
Y526498D01*
X1379002D01*
Y527286D01*
X1381998D01*
Y526498D01*
X1384869D01*
X1387236Y524132D01*
Y518952D01*
X1386719Y518435D01*
X1382142D01*
X1378291Y514584D01*
X1368892D01*
G37*
G36*
G01X1395663Y548989D02*
X1393093Y551559D01*
Y573293D01*
X1396732Y576932D01*
X1396760D01*
X1397208Y577380D01*
X1412732D01*
X1413180Y576932D01*
X1413403D01*
Y576725D01*
X1413402Y576719D01*
G03X1414122Y575368I1449J-95D01*
G02X1414098Y574664I-201J-346D01*
G03X1413695Y572358I645J-1301D01*
G02Y571805I-289J-277D01*
G03X1415659Y569674I1049J-1003D01*
G02X1416186Y569654I252J-311D01*
G03X1418216Y569692I996J1057D01*
G02X1418784Y569695I285J-280D01*
G03X1420904Y569770I1025J1028D01*
G02X1421487Y569791I301J-263D01*
G03X1423361Y571999I1021J1033D01*
G02Y572647I234J324D01*
G03X1423117Y575141I-852J1176D01*
G02Y575505I84J182D01*
G03X1423294Y575602I-607J1318D01*
G01X1423430Y575689D01*
X1427192Y571927D01*
X1439413D01*
X1446100Y578614D01*
Y596882D01*
X1451370D01*
X1454072Y594180D01*
X1459917D01*
X1461885Y596148D01*
Y603318D01*
X1464114Y605547D01*
X1470353D01*
X1471600Y604300D01*
X1476450D01*
X1477735Y603015D01*
X1497705D01*
X1499360Y601360D01*
Y589240D01*
X1501200Y587400D01*
Y568626D01*
X1498619Y566045D01*
X1470255D01*
X1470251Y566049D01*
X1468541D01*
X1467179Y567411D01*
X1446011D01*
X1444418Y565818D01*
Y557226D01*
X1440919Y553727D01*
X1436491D01*
X1436447Y553771D01*
X1433435D01*
X1428653Y548989D01*
X1395663D01*
G37*
G36*
G01X1371550Y552531D02*
X1370450Y553631D01*
Y560154D01*
X1370502D01*
Y565158D01*
X1370450D01*
Y566654D01*
X1370502D01*
Y571658D01*
X1370450D01*
Y573654D01*
X1370502D01*
Y578658D01*
X1370450D01*
Y579120D01*
X1371330Y580000D01*
X1376396D01*
X1376554Y580158D01*
Y582026D01*
X1380207Y585679D01*
Y588984D01*
X1379175Y590016D01*
X1376682D01*
X1376021Y589355D01*
X1376017Y589352D01*
G03X1375897Y589235I1686J-1849D01*
G01X1375896Y589233D01*
X1375564Y588902D01*
X1374700D01*
G03X1374432Y588887I6J-2502D01*
G01X1374422Y588886D01*
X1372812D01*
X1372393Y589305D01*
X1370395D01*
X1370102Y589598D01*
Y594578D01*
X1370000D01*
Y596074D01*
X1370102D01*
Y601078D01*
X1370000D01*
Y603298D01*
X1370402D01*
Y608700D01*
X1374000D01*
X1374400Y608300D01*
Y606729D01*
G03Y606583I1500J-73D01*
G01Y604229D01*
G03Y604083I1500J-73D01*
G01Y603370D01*
X1375150Y602620D01*
X1381440D01*
X1383090Y600970D01*
X1389300D01*
X1398070Y592200D01*
X1427100D01*
X1437910Y603010D01*
Y612538D01*
X1438873Y613501D01*
X1462855D01*
X1463134Y613222D01*
Y611538D01*
X1463300Y611372D01*
Y608318D01*
X1463140Y608286D01*
G03X1462458Y605891I279J-1374D01*
G02X1462467Y605317I-274J-291D01*
G01X1460884Y603733D01*
Y603584D01*
X1460000Y602700D01*
Y595907D01*
X1459713Y595620D01*
X1454448D01*
X1452411Y597657D01*
X1452011D01*
X1451785Y597884D01*
X1445098D01*
Y597430D01*
X1444728Y597059D01*
Y580128D01*
X1438200Y573600D01*
X1427130D01*
X1423962Y576768D01*
X1423961Y576849D01*
G03X1423336Y578017I-1452J-26D01*
G02X1423328Y578668I228J328D01*
G03X1421482Y578836I-828J1132D01*
G02X1421192Y578161I-290J-275D01*
G01X1420011D01*
X1419998Y578163D01*
G03X1419620I-189J-1440D01*
G01X1419607Y578161D01*
X1416108D01*
G02X1415818Y578836I0J400D01*
G03X1414184Y578541I-1018J964D01*
G01X1414296Y578486D01*
Y578161D01*
X1413700D01*
X1413111Y578750D01*
X1396650D01*
X1392705Y574805D01*
G02X1392023Y575065I-283J283D01*
G03X1390478Y576381I-1400J-79D01*
G02X1390087Y576973I-41J398D01*
G03X1386900Y577876I-1487J828D01*
G02X1386361Y577519I-400J18D01*
G03X1385695Y577683I-1046J-2814D01*
G02X1385364Y578200I50J397D01*
G03X1385078Y580638I-2864J900D01*
G03X1380855Y582884I-2004J1325D01*
G02X1380177Y582784I-369J153D01*
G03X1379188Y580418I-1124J-920D01*
G02X1379610Y579912I37J-398D01*
G03X1379551Y579664I2888J-818D01*
G01X1379520Y579502D01*
X1377598D01*
Y578952D01*
X1377104D01*
X1377045Y579013D01*
G03X1374850Y576962I-1084J-1040D01*
G02X1374859Y576432I-295J-270D01*
G03X1374868Y574469I1141J-976D01*
G02Y573943I-302J-263D01*
G03X1377295Y572195I1132J-987D01*
G02X1377841Y572338I345J-202D01*
G03X1379100Y571998I1259J2161D01*
G01X1382636D01*
X1383095Y572457D01*
X1383151Y572470D01*
G03X1383278Y572501I-648J2931D01*
G03X1388092Y573562I2038J2204D01*
G03X1389021Y574015I-107J1398D01*
G02X1389607Y574020I295J-270D01*
G03X1391008Y573638I1016J966D01*
G01X1391121Y573670D01*
X1391346Y573446D01*
X1390986Y573086D01*
Y553789D01*
X1389728Y552531D01*
X1371550D01*
G37*
G36*
G01X1405800Y71700D02*
X1407700Y73600D01*
X1447000D01*
X1448500Y72100D01*
Y60600D01*
X1445368Y57468D01*
X1432155D01*
X1428887Y54200D01*
X1416100D01*
X1413400Y51500D01*
X1406300D01*
X1405800Y52000D01*
Y71700D01*
G37*
G36*
G01X1462472Y401181D02*
X1462223Y401430D01*
X1462210D01*
X1460960Y402679D01*
Y406398D01*
X1461102D01*
Y409402D01*
X1460960D01*
Y411398D01*
X1461102D01*
Y414402D01*
X1460960D01*
Y415160D01*
X1462200Y416400D01*
X1472652D01*
X1473380Y415672D01*
X1473832Y415219D01*
Y413751D01*
G02X1473271Y413385I-400J0D01*
G03X1471715Y413133I-583J-1330D01*
G02X1471157Y413154I-268J297D01*
G03X1471079Y411074I-1051J-1002D01*
G02X1471637Y411053I268J-297D01*
G03X1473271Y410725I1051J1002D01*
G02X1473832Y410359I161J-366D01*
G01Y407295D01*
X1471832Y405295D01*
Y401782D01*
X1471230Y401181D01*
X1469779D01*
G02X1469415Y401747I0J400D01*
G03X1466863Y403293I-1367J623D01*
G02X1466233I-315J246D01*
G03X1463681Y401747I-1185J-923D01*
G02X1463317Y401181I-364J-166D01*
G01X1462472D01*
G37*
G36*
G01X1437632Y400075D02*
X1436015Y401692D01*
Y412615D01*
X1437930Y414530D01*
X1445050D01*
X1445170Y414650D01*
X1448586D01*
X1448748Y414488D01*
Y411498D01*
X1448753D01*
Y409502D01*
X1448748D01*
Y406730D01*
X1445806Y403786D01*
X1445796D01*
Y403776D01*
X1445783Y403764D01*
Y400623D01*
X1445235Y400075D01*
X1437632D01*
G37*
G36*
G01X1443300Y378900D02*
X1449700D01*
Y397300D01*
X1443300D01*
Y378900D01*
G37*
G36*
G01X1464830Y365534D02*
X1463059Y367306D01*
X1458210D01*
X1456533Y368983D01*
Y370751D01*
X1456676Y370894D01*
X1459866D01*
Y370892D01*
X1461753D01*
X1462111Y370533D01*
X1467248D01*
Y368498D01*
X1467249D01*
Y367502D01*
X1467248D01*
Y365982D01*
X1467144Y365878D01*
X1466405D01*
X1466062Y365534D01*
X1464830D01*
G37*
G36*
G01X1448617Y399954D02*
X1447805Y400766D01*
Y403920D01*
X1450383Y406498D01*
X1450752D01*
Y409502D01*
X1450618D01*
Y411498D01*
X1450752D01*
Y414502D01*
X1450618D01*
Y423974D01*
X1457628Y430984D01*
X1457903D01*
G02X1458077Y430686I0J-200D01*
G03X1460626Y430454I1223J-686D01*
G02X1461005Y430984I378J130D01*
G01X1475812D01*
X1476517Y431689D01*
X1477648D01*
Y429176D01*
X1480652D01*
Y429726D01*
X1482122D01*
X1482747Y429101D01*
X1482760D01*
X1482818Y429043D01*
X1484546D01*
X1486792Y431290D01*
X1488074D01*
Y431840D01*
X1488374D01*
X1488593Y432058D01*
X1490718D01*
X1490801Y432040D01*
X1490820Y432032D01*
G03X1492191Y432115I605J1374D01*
G01X1493585D01*
X1495321Y430379D01*
X1511634D01*
X1511956Y430701D01*
Y434144D01*
X1511300Y434800D01*
X1509500D01*
X1508800Y435500D01*
Y435900D01*
X1509000Y436100D01*
Y436878D01*
X1509952D01*
Y437573D01*
X1509000Y437572D01*
Y438300D01*
X1508600Y438700D01*
Y442100D01*
X1509003Y442503D01*
X1509103D01*
X1509372Y442233D01*
X1509907Y441698D01*
X1510100D01*
Y441500D01*
X1510400Y441200D01*
X1510628D01*
Y441198D01*
X1511122D01*
X1511123Y441200D01*
X1511200D01*
X1511252Y441252D01*
Y441698D01*
X1511577D01*
X1512091Y442212D01*
X1512644D01*
X1513158Y441698D01*
X1513462D01*
Y441338D01*
X1513540Y441260D01*
X1513579Y441198D01*
X1514272D01*
X1514273Y441200D01*
X1514400D01*
X1514532Y441332D01*
Y441698D01*
X1514673D01*
X1515307Y442332D01*
X1515704D01*
X1516338Y441698D01*
X1516508D01*
Y441545D01*
X1516729Y441198D01*
X1517502D01*
X1518404Y440296D01*
Y439619D01*
X1519467Y438556D01*
X1519878D01*
Y438048D01*
X1520573D01*
X1520572Y438556D01*
X1522982D01*
Y438064D01*
X1523017Y438029D01*
X1523741D01*
X1523949Y438237D01*
Y438556D01*
X1524171D01*
X1524214Y438598D01*
X1524215D01*
X1524715Y439098D01*
X1525194D01*
X1525736Y438556D01*
X1525946D01*
Y438274D01*
X1526066Y438154D01*
X1526181Y438038D01*
X1526868D01*
X1526960Y438130D01*
Y438556D01*
X1527326D01*
X1527867Y439098D01*
X1530072D01*
X1531179D01*
X1531181Y439096D01*
X1531532D01*
X1532073Y438556D01*
X1532257D01*
Y438184D01*
X1532401Y438040D01*
X1533251D01*
X1533398Y438187D01*
Y438556D01*
X1533584D01*
X1534166Y439138D01*
X1534633D01*
X1535215Y438556D01*
X1535506D01*
Y438171D01*
X1535633Y438044D01*
X1536239D01*
X1536859Y437424D01*
Y436927D01*
G03X1536287Y436366I691J-1277D01*
G01X1535978D01*
X1535800Y436188D01*
Y433651D01*
X1538025Y431426D01*
X1540195D01*
X1541570Y430051D01*
Y428939D01*
X1541062Y428431D01*
X1540128D01*
X1539949Y428252D01*
Y428122D01*
X1539948D01*
Y427407D01*
X1540346Y427010D01*
X1541057D01*
X1541377Y426690D01*
Y425806D01*
X1541051Y425480D01*
X1540800D01*
Y425473D01*
X1540237D01*
X1539936Y425172D01*
Y424122D01*
X1540084Y423974D01*
X1540814D01*
X1541499Y423289D01*
Y422668D01*
X1540987Y422156D01*
X1540314D01*
X1539674Y422796D01*
X1539462D01*
X1539461Y422797D01*
X1538579D01*
X1538520Y422738D01*
X1538519D01*
X1538008Y422227D01*
X1537092D01*
X1536616Y422703D01*
Y423684D01*
X1536400Y423900D01*
X1535700D01*
X1535425Y423625D01*
Y422847D01*
X1535028Y422450D01*
X1533926D01*
X1533568Y422808D01*
X1532402D01*
X1532390Y422796D01*
X1532277D01*
X1531738Y422257D01*
X1530596D01*
X1530102Y422751D01*
Y429981D01*
X1529672Y430411D01*
X1529590D01*
X1529589Y430410D01*
X1526782D01*
X1526520Y430672D01*
Y434272D01*
X1526092Y434700D01*
X1520700D01*
X1520400Y434400D01*
Y434102D01*
X1519748D01*
Y431098D01*
X1520400D01*
Y430700D01*
X1520398Y430698D01*
X1520400D01*
Y429819D01*
X1519678Y429096D01*
X1519677D01*
X1518931Y428350D01*
X1518260D01*
X1517898Y428121D01*
Y427300D01*
X1518064Y427134D01*
X1518997D01*
X1519308Y426823D01*
Y425577D01*
X1519123Y425392D01*
X1517992D01*
X1517875Y425275D01*
Y424025D01*
X1518100Y423800D01*
X1518955D01*
X1519296Y423459D01*
Y422455D01*
X1518892Y422050D01*
X1518070D01*
X1517885Y421865D01*
Y421134D01*
G03X1517260Y420320I765J-1234D01*
G01X1517245Y420271D01*
X1516816Y419842D01*
Y419319D01*
X1516390Y418893D01*
X1514010D01*
X1513560Y418443D01*
Y417476D01*
X1512385Y416302D01*
X1512215D01*
X1511615Y416902D01*
X1511497D01*
Y417231D01*
X1511181Y417547D01*
X1510413D01*
X1510067Y417201D01*
Y416983D01*
X1509485Y416402D01*
X1508815D01*
X1508315Y416902D01*
X1508266D01*
Y417352D01*
X1508023Y417595D01*
X1506621D01*
X1506618Y417592D01*
X1506333D01*
X1505916Y418009D01*
X1501554D01*
X1501533Y418014D01*
G03X1500905I-314J-1418D01*
G01X1500884Y418009D01*
X1500171D01*
X1498412Y416250D01*
X1496586D01*
G02X1496321Y416949I0J400D01*
G03X1494329I-996J1125D01*
G02X1494064Y416250I-265J-299D01*
G01X1492686D01*
G02X1492421Y416949I0J400D01*
G03X1490429I-996J1125D01*
G02X1490164Y416250I-265J-299D01*
G01X1488786D01*
G02X1488521Y416949I0J400D01*
G03X1486529I-996J1125D01*
G02X1486264Y416250I-265J-299D01*
G01X1482323D01*
X1482303Y416254D01*
G03X1481697I-303J-1471D01*
G01X1481677Y416250D01*
X1474218D01*
X1473833Y416636D01*
X1473067Y417402D01*
X1460455D01*
X1459234Y416181D01*
Y414402D01*
X1459098D01*
Y411398D01*
X1459234D01*
Y409402D01*
X1459098D01*
Y406398D01*
X1459234D01*
Y400334D01*
X1458854Y399954D01*
X1448617D01*
G37*
G36*
G01X1437000Y417100D02*
X1446769D01*
X1447237Y417568D01*
Y429328D01*
X1446865Y429700D01*
X1437000D01*
Y417100D01*
G37*
G36*
G01X1457830Y520095D02*
X1457274Y520651D01*
Y527425D01*
X1458192Y528343D01*
X1464075D01*
X1464400Y528018D01*
Y525512D01*
X1464083Y525195D01*
X1464082D01*
X1463951Y525064D01*
X1462436D01*
X1462131Y524759D01*
Y520549D01*
X1461684Y520102D01*
X1459598D01*
Y520095D01*
X1457830D01*
G37*
G36*
G01X1469915Y504742D02*
X1466037Y508620D01*
X1466047Y508715D01*
G03X1465786Y509730I-1494J157D01*
G01X1465750Y509781D01*
Y510200D01*
X1461684Y514266D01*
X1458801D01*
X1458205Y514862D01*
Y518014D01*
X1458735Y518544D01*
X1462380D01*
X1462996Y517929D01*
X1466881D01*
X1467240Y517570D01*
Y516310D01*
X1469690Y513860D01*
Y508520D01*
X1471150Y507060D01*
X1474000D01*
X1475350Y508410D01*
Y513550D01*
X1475850Y514050D01*
X1478740D01*
X1480240Y515550D01*
Y516424D01*
X1480268Y516452D01*
Y518813D01*
X1480728Y519272D01*
X1482698D01*
Y519198D01*
X1484702D01*
Y519272D01*
X1485353D01*
X1485412Y519296D01*
Y519912D01*
X1487600Y522100D01*
X1492715D01*
G03X1492910Y521838I1215J700D01*
G02X1492757Y521501I-145J-137D01*
G03X1492664Y521502I-63J-1501D01*
G01X1490660D01*
X1490628Y521513D01*
G03X1488532Y519673I-528J-1513D01*
G02X1488200Y519196I-392J-81D01*
G03X1489804Y517958I210J-1386D01*
G02X1490182Y518400I398J42D01*
G03X1490628Y518487I-81J1600D01*
G01X1490660Y518498D01*
X1492664D01*
G03X1493960Y520818I36J1502D01*
G02X1494214Y521427I336J218D01*
G03X1495090Y522012I-284J1373D01*
G01X1495149Y522100D01*
X1495400D01*
X1496074Y521426D01*
X1500458D01*
X1500485Y521398D01*
X1507615D01*
X1507642Y521426D01*
X1508437D01*
X1510511Y523500D01*
X1515626D01*
X1519316Y527190D01*
Y540033D01*
X1519428Y540144D01*
Y546111D01*
X1518137Y547402D01*
X1517928D01*
X1517730Y547600D01*
X1513200D01*
X1512000Y548800D01*
Y557244D01*
X1512018Y557283D01*
G03Y558437I-1278J577D01*
G01X1512000Y558476D01*
Y562100D01*
X1513620Y563720D01*
X1516494D01*
G02X1516829Y563100I1J-400D01*
G03X1519171I1171J-770D01*
G02X1519506Y563720I334J220D01*
G01X1535852D01*
X1537075Y564943D01*
Y569560D01*
X1537645Y570130D01*
X1549570D01*
X1550700Y569000D01*
Y563960D01*
X1556870Y557790D01*
X1570082D01*
Y557758D01*
X1573086D01*
Y557790D01*
X1575018D01*
Y557748D01*
X1577532D01*
X1578060Y557220D01*
X1578040Y557200D01*
Y554120D01*
X1561550Y537630D01*
X1555849D01*
X1539693Y521474D01*
X1527102D01*
X1523943Y518314D01*
X1523797D01*
X1519532Y514050D01*
Y513904D01*
X1513292Y507664D01*
G02X1512611Y507910I-283J283D01*
G03X1511174Y509182I-1396J-129D01*
G02X1510831Y509806I-12J400D01*
G03X1509549Y512147I-1246J839D01*
G01X1509546Y512146D01*
X1507545D01*
X1507513Y512158D01*
G03X1505549Y509935I-528J-1513D01*
G02X1505383Y509408I-359J-177D01*
G03X1507306Y508822I677J-1228D01*
G02X1507429Y509106I178J92D01*
G03X1507513Y509132I-432J1543D01*
G01X1507545Y509144D01*
X1509546D01*
X1509549Y509143D01*
G03X1509671Y509145I36J1502D01*
G02X1510031Y508532I22J-399D01*
G03X1511086Y506385I1184J-751D01*
G02X1511332Y505704I-37J-398D01*
G01X1510370Y504742D01*
X1503285D01*
G02X1502887Y505108I0J400D01*
G03X1500093I-1397J-120D01*
G02X1499695Y504742I-398J34D01*
G01X1499060D01*
G02X1498662Y505182I0J400D01*
G03X1498444Y506084I-1395J140D01*
G02X1498680Y506688I336J217D01*
G03X1498805Y506726I-403J1551D01*
G01X1498837Y506738D01*
X1500838D01*
X1500841Y506737D01*
G03Y509741I36J1502D01*
G01X1500838Y509740D01*
X1498837D01*
X1498805Y509752D01*
G03X1497001Y507270I-528J-1513D01*
G02X1496813Y506649I-318J-243D01*
G03X1495872Y505182I454J-1326D01*
G02X1495474Y504742I-398J-40D01*
G01X1469915D01*
G37*
G36*
G01X1471540Y508150D02*
X1470760Y508930D01*
Y514540D01*
X1468550Y516750D01*
Y518563D01*
X1468400Y518713D01*
X1468378D01*
X1467050Y520041D01*
X1463263D01*
Y523852D01*
X1463465Y524054D01*
X1465454D01*
X1466500Y525100D01*
Y525298D01*
X1466552D01*
Y528446D01*
X1470131D01*
X1470605Y527972D01*
Y523795D01*
X1473769Y520631D01*
X1475598D01*
Y520598D01*
X1477602D01*
Y520631D01*
X1478586D01*
X1479267Y519950D01*
Y516867D01*
X1477900Y515500D01*
X1475180D01*
X1474240Y514560D01*
Y508820D01*
X1473570Y508150D01*
X1471540D01*
G37*
G36*
G01X1459000Y536500D02*
X1457874Y537626D01*
Y543927D01*
X1458971Y545024D01*
X1462472D01*
X1462498Y544998D01*
Y541998D01*
X1462731D01*
Y540277D01*
X1461998Y539545D01*
Y536998D01*
X1461502Y536502D01*
X1459498D01*
Y536500D01*
X1459000D01*
G37*
G36*
G01X1479195Y530095D02*
X1479100Y530000D01*
X1470640D01*
X1468840Y531800D01*
Y534160D01*
X1466859Y536141D01*
X1463359D01*
X1463000Y536500D01*
Y539130D01*
X1464503Y540633D01*
Y545008D01*
X1464630Y545135D01*
X1467878D01*
X1468073Y544940D01*
Y541617D01*
X1470174Y539516D01*
Y536240D01*
X1471541Y534873D01*
X1478721D01*
X1479195Y534399D01*
Y530095D01*
G37*
G36*
G01X1458331Y529829D02*
X1457342Y530818D01*
Y534362D01*
X1457980Y535000D01*
X1459498D01*
Y534998D01*
X1461502D01*
Y535000D01*
X1462145D01*
X1463148Y533997D01*
X1467583D01*
X1467832Y533748D01*
Y530071D01*
X1467590Y529829D01*
X1458331D01*
G37*
G36*
G01X1497845Y539755D02*
X1497479Y540121D01*
Y542594D01*
X1495573Y544500D01*
X1491800D01*
X1490900Y545400D01*
Y546900D01*
X1489776Y548024D01*
X1485998D01*
X1483476Y545502D01*
X1480337D01*
X1479293Y544458D01*
Y542321D01*
X1478974Y542002D01*
X1475998D01*
Y542000D01*
X1474002D01*
Y542002D01*
X1470902D01*
X1470464Y542440D01*
Y545225D01*
X1468289Y547400D01*
X1458645D01*
X1455082Y543837D01*
X1451149D01*
X1450325Y544661D01*
G02X1450460Y545315I283J283D01*
G03X1448870Y547665I-538J1349D01*
G02X1448298Y547658I-289J276D01*
G01X1445700Y550256D01*
Y564863D01*
X1446337Y565500D01*
X1466961D01*
X1469253Y563208D01*
X1507169D01*
X1509000Y561377D01*
Y547700D01*
X1510300Y546400D01*
X1517722D01*
X1518426Y545696D01*
Y540559D01*
X1517622Y539755D01*
X1497845D01*
G37*
G36*
G01X1438336Y615602D02*
X1437581Y616357D01*
Y623629D01*
X1438529Y624577D01*
X1464037D01*
X1464387Y624227D01*
Y619730D01*
G03Y617398I947J-1166D01*
G01Y616067D01*
X1463922Y615602D01*
X1438336D01*
G37*
G36*
G01X1535434Y85242D02*
X1533781D01*
X1530785Y88238D01*
X1525968D01*
X1525956Y88425D01*
G03X1525713Y89129I-1399J-89D01*
G01Y91392D01*
G02X1526241Y91771I400J0D01*
G03X1528263Y93688I503J1494D01*
G01X1528256Y93714D01*
Y97481D01*
X1528276Y97523D01*
G03X1526000Y99796I-1532J742D01*
G01X1525959Y99776D01*
X1525713D01*
Y100061D01*
X1525113Y100661D01*
X1524113D01*
X1523613Y101161D01*
Y104232D01*
X1524010D01*
X1525398Y102843D01*
G03X1528061Y104256I1115J1115D01*
G01X1528056Y104281D01*
X1528111Y105200D01*
X1534300D01*
X1535500Y104000D01*
Y102556D01*
X1535434D01*
Y100552D01*
X1535500D01*
Y99356D01*
X1535434D01*
Y97352D01*
X1535500D01*
Y96156D01*
X1535434D01*
Y94152D01*
X1535500D01*
Y92956D01*
X1535434D01*
Y90952D01*
X1535500D01*
Y89756D01*
X1535434D01*
Y87752D01*
X1535500D01*
Y86356D01*
X1535434D01*
Y85242D01*
G37*
G36*
G01X1495732Y342700D02*
X1492671D01*
X1492100Y343271D01*
Y344600D01*
X1492200Y344700D01*
X1505500D01*
X1506100Y344100D01*
Y340710D01*
X1505582Y340192D01*
X1505551D01*
X1505344Y339985D01*
X1503615D01*
X1500900Y342700D01*
X1499900D01*
G03X1499758I-71J-1450D01*
G01X1495883D01*
G03X1495737I-73J-1500D01*
G01X1495732D01*
G37*
G36*
G01X1523900Y402700D02*
X1523600Y403000D01*
Y403408D01*
X1523662Y403467D01*
G03X1521165Y404906I-1037J1087D01*
G01X1521152Y404852D01*
X1520960Y404660D01*
X1518909D01*
X1518697Y404872D01*
X1518884Y405058D01*
X1518946Y405069D01*
G03X1519550Y407677I-246J1431D01*
G02X1519501Y408285I234J325D01*
G01X1521495Y410279D01*
X1523002D01*
Y410278D01*
X1524099D01*
Y410279D01*
X1524740D01*
X1526430Y408589D01*
X1526641D01*
G02X1527037Y408134I0J-400D01*
G03X1529913I1438J-200D01*
G02X1530309Y408589I396J55D01*
G01X1530417D01*
X1532684Y410856D01*
Y411917D01*
X1533117Y412350D01*
X1533511D01*
X1533563Y412313D01*
G03X1535286Y412350I836J1187D01*
G01X1536750D01*
X1539615Y409485D01*
X1539619Y409480D01*
G03X1539730Y409369I1081J970D01*
G01X1539735Y409365D01*
X1540106Y408994D01*
X1541311D01*
X1542162Y409845D01*
Y411053D01*
X1541305Y411910D01*
X1540913D01*
X1540446Y412377D01*
Y412573D01*
X1539673Y413346D01*
X1539479D01*
Y414346D01*
X1539453Y414372D01*
X1538794D01*
X1538753Y414413D01*
G03X1538363Y414803I-1203J-813D01*
G01X1538300Y414866D01*
Y415035D01*
X1538864Y415598D01*
X1539585D01*
X1540414Y414770D01*
X1540420D01*
X1543234Y411956D01*
X1544903D01*
X1545663Y412716D01*
X1546242D01*
X1546826Y412132D01*
X1548060D01*
X1548828Y412900D01*
X1551400D01*
X1551475Y412976D01*
X1551785D01*
X1552062Y413253D01*
X1552125Y413264D01*
G03X1553091Y413901I-250J1430D01*
G01X1554559D01*
G03X1556991I1216J793D01*
G01X1558459D01*
G03X1560707Y415715I1217J792D01*
G01X1560567Y415856D01*
X1561355Y416644D01*
X1561452Y416632D01*
G03X1562904Y417388I172J1442D01*
G01X1562961Y417493D01*
X1564135D01*
X1564190Y417385D01*
G03X1566860I1335J689D01*
G01X1566915Y417493D01*
X1568035D01*
X1568090Y417385D01*
G03X1570458Y416984I1335J689D01*
G01X1571500D01*
X1571606Y416878D01*
G02X1571334Y416195I-283J-283D01*
G03X1572696Y415410I42J-1501D01*
G02X1573047Y416000I352J190D01*
G01X1575800D01*
X1576800Y417000D01*
Y421222D01*
X1578308Y422730D01*
X1578852D01*
X1578858Y422735D01*
X1582084D01*
X1585345Y419474D01*
X1588138D01*
X1588869Y418742D01*
Y418718D01*
X1589126Y418461D01*
X1602673D01*
X1603996Y419784D01*
Y421914D01*
G03Y424028I-996J1057D01*
G01Y425064D01*
X1607768Y428836D01*
Y443837D01*
X1609448Y445518D01*
X1610034D01*
X1611146Y446630D01*
Y454063D01*
X1611142Y454069D01*
Y455032D01*
X1610737Y455437D01*
X1611400Y456100D01*
X1619200D01*
X1619900Y455400D01*
Y453100D01*
X1619500Y452700D01*
Y451200D01*
X1620400Y450300D01*
X1622800D01*
X1623412Y449688D01*
Y427625D01*
X1623546Y427490D01*
Y411245D01*
X1623412Y411110D01*
Y408804D01*
X1621617Y407010D01*
X1596736D01*
G03X1594915Y407051I-936J-1110D01*
G01X1594861Y407010D01*
X1594781D01*
X1592693Y404922D01*
G02X1592062Y405008I-283J283D01*
G03X1589045Y404903I-1481J-838D01*
G02X1588530Y404707I-361J173D01*
G03X1587112Y404540I-561J-1339D01*
G01X1587059Y404502D01*
X1586985D01*
X1585583Y403100D01*
X1584371D01*
G02X1584120Y403811I0J400D01*
G03X1582296I-912J1130D01*
G02X1582045Y403100I-251J-311D01*
G01X1581502D01*
Y403102D01*
X1578498D01*
Y403100D01*
X1576802D01*
Y403102D01*
X1573798D01*
Y403100D01*
X1573316D01*
X1573157Y403260D01*
X1571047D01*
G02X1570696Y403853I-1J400D01*
G03X1567981Y404703I-1271J702D01*
G01X1567962Y404523D01*
X1559474D01*
X1559148Y404849D01*
X1559135Y404903D01*
G03X1556281Y404703I-1410J-349D01*
G01X1556262Y404523D01*
X1551412D01*
X1551387Y404695D01*
G03X1548991Y403400I-1437J-205D01*
G02X1548726Y402700I-265J-300D01*
G01X1523900D01*
G37*
G36*
G01X1517222Y442700D02*
Y442702D01*
X1516752D01*
X1516728Y442725D01*
G03X1516292Y443167I-1228J-775D01*
G01X1516275Y443178D01*
X1516119Y443334D01*
X1515940D01*
X1515912Y443342D01*
G03X1515088I-412J-1392D01*
G01X1515060Y443334D01*
X1514892D01*
X1514754Y443196D01*
X1514734Y443184D01*
G03X1514258Y442702I767J-1233D01*
G01X1513592D01*
G03X1511108I-1242J-752D01*
G01X1510442D01*
G03X1509750Y443294I-1242J-752D01*
G01X1509713Y443309D01*
X1508071Y444951D01*
Y447887D01*
X1509799Y449615D01*
X1513861D01*
G02X1514206Y449012I0J-400D01*
G03X1516767Y447444I1294J-762D01*
G02X1517439Y447450I338J-215D01*
G03X1518342Y446831I1212J800D01*
G01X1518500Y446797D01*
Y443600D01*
X1517600Y442700D01*
X1517222D01*
G37*
G36*
G01X1530602Y440100D02*
X1527453D01*
X1526911Y439558D01*
X1526188D01*
G03X1524342Y440118I-1238J-758D01*
G01X1524302Y440100D01*
X1524300D01*
X1524297Y440097D01*
X1524271Y440083D01*
G03X1523711Y439557I679J-1284D01*
G01X1519889D01*
G03X1519405Y440040I-1239J-757D01*
G01Y443005D01*
X1520277Y443877D01*
X1521015D01*
X1521062Y443849D01*
G03X1523041Y444346I738J1251D01*
G01X1523709D01*
G03X1524303Y443800I1241J754D01*
G01X1524333Y443785D01*
X1524609Y443509D01*
X1525491D01*
X1525500Y443500D01*
X1526100D01*
X1526900Y444300D01*
X1529100D01*
X1530400Y443000D01*
X1534300D01*
X1535167Y443867D01*
X1535185Y443878D01*
G03X1535539Y444200I-787J1220D01*
G01X1536400D01*
X1536465Y444135D01*
X1536469Y444130D01*
G03X1536580Y444019I1081J970D01*
G01X1536585Y444015D01*
X1536700Y443900D01*
X1536730D01*
X1536779Y443869D01*
G03X1538321I771J1231D01*
G01X1538370Y443900D01*
X1538500D01*
X1538800Y444200D01*
X1539400D01*
X1540000Y443600D01*
X1541450D01*
X1541630Y443420D01*
X1542515Y442535D01*
X1542475Y442418D01*
G03X1543056Y440734I1375J-468D01*
G01Y439944D01*
G03X1542774Y439651I895J-1143D01*
G01X1542764Y439638D01*
X1542678Y439552D01*
X1541942D01*
G03X1541298Y440123I-1242J-752D01*
G01X1541265Y440138D01*
X1541156Y440247D01*
X1541148D01*
X1540606Y440789D01*
X1537558D01*
X1536830Y440061D01*
X1536809Y440049D01*
G03X1536311Y439557I741J-1249D01*
G01X1535639D01*
G03X1535154Y440041I-1239J-757D01*
G01X1535134Y440053D01*
X1535048Y440139D01*
X1534963D01*
X1534928Y440153D01*
G03X1533872I-528J-1353D01*
G01X1533837Y440139D01*
X1533751D01*
X1533664Y440052D01*
X1533643Y440039D01*
G03X1533161Y439557I757J-1239D01*
G01X1532489D01*
G03X1532023Y440029I-1239J-757D01*
G01X1532004Y440041D01*
X1531947Y440098D01*
X1531902D01*
X1531862Y440117D01*
G03X1530642Y440118I-611J-1317D01*
G01X1530602Y440100D01*
G37*
G36*
G01X1516346Y417109D02*
Y416446D01*
X1515422Y415522D01*
X1514748Y415521D01*
Y414848D01*
X1514733Y414833D01*
G03X1514267Y414367I767J-1233D01*
G01X1512300Y412400D01*
X1508300D01*
X1506800Y413900D01*
Y415500D01*
X1507200Y415900D01*
X1507900D01*
X1508400Y415400D01*
X1508664D01*
X1508698Y415388D01*
G03X1509702I502J1362D01*
G01X1509736Y415400D01*
X1509900D01*
X1510165Y415665D01*
X1510170Y415669D01*
G03X1510281Y415780I-970J1081D01*
G01X1510285Y415785D01*
X1510400Y415900D01*
X1511173D01*
G03X1511565Y415528I1178J849D01*
G01X1511583Y415517D01*
X1511800Y415300D01*
X1512279D01*
G03X1512421I71J1450D01*
G01X1512800D01*
X1512910Y415410D01*
X1512943Y415425D01*
G03X1513675Y416157I-593J1325D01*
G01X1513690Y416190D01*
X1515065Y417565D01*
X1515890D01*
X1516346Y417109D01*
G37*
G36*
G01X1495820Y431380D02*
X1494700Y432500D01*
Y436077D01*
X1494721Y436119D01*
G03Y437453I-1346J667D01*
G01X1494700Y437495D01*
Y440300D01*
X1496200Y441800D01*
X1497778D01*
G02X1498082Y441141I-1J-400D01*
G03X1500688Y440508I1143J-975D01*
G02X1501077Y440998I389J90D01*
G01X1504304D01*
X1504352Y440867D01*
G03X1506870Y440488I1363J501D01*
G02X1507471Y440529I318J-242D01*
G01X1507598Y440402D01*
Y438285D01*
X1507998Y437885D01*
Y436515D01*
X1507798Y436315D01*
Y436030D01*
X1507792Y436006D01*
G03Y435294I1408J-356D01*
G01X1507798Y435270D01*
Y435085D01*
X1507920Y434963D01*
X1507934Y434939D01*
G03X1508230Y434569I1267J710D01*
G01X1508235Y434565D01*
X1508800Y434000D01*
X1508884D01*
X1509085Y433798D01*
X1509800D01*
Y431380D01*
X1495820D01*
G37*
G36*
G01X1523628Y419200D02*
G02X1523233Y419665I0J400D01*
G03X1520589Y420700I-1433J235D01*
G02X1519917Y420706I-334J221D01*
G03X1519741Y420933I-1270J-803D01*
G02X1519748Y421490I290J275D01*
G01X1520298Y422041D01*
Y423874D01*
X1519660Y424511D01*
X1520310Y425160D01*
Y427408D01*
X1519857Y427860D01*
X1521402Y429404D01*
Y430002D01*
X1521500Y430100D01*
Y431098D01*
X1521752D01*
Y433452D01*
X1521998Y433698D01*
X1525518D01*
Y431194D01*
G02X1525082Y430796I-400J0D01*
G03X1524186Y428115I-132J-1446D01*
G02Y427435I-210J-340D01*
G03Y424965I764J-1235D01*
G02Y424285I-210J-340D01*
G03X1525714I764J-1235D01*
G02Y424965I210J340D01*
G03Y427435I-764J1235D01*
G02Y428115I210J340D01*
G03X1526223Y428652I-765J1234D01*
G01X1526280Y428756D01*
X1526598D01*
Y428348D01*
X1529100D01*
Y422336D01*
X1530181Y421256D01*
X1532266D01*
X1532817Y421806D01*
X1533153D01*
X1533511Y421448D01*
X1535443D01*
X1535794Y421800D01*
X1536001D01*
X1536575Y421226D01*
X1538424D01*
X1538738Y421540D01*
X1539302D01*
X1539687Y421154D01*
X1541402D01*
X1542500Y422253D01*
Y423704D01*
X1541900Y424304D01*
Y424913D01*
X1542378Y425391D01*
Y427105D01*
X1541804Y427679D01*
X1542572Y428446D01*
Y430466D01*
X1542400Y430637D01*
Y430700D01*
X1540628Y432472D01*
X1538458D01*
X1536802Y434128D01*
Y435412D01*
X1537836Y436447D01*
X1538528Y435755D01*
Y434726D01*
X1539193Y434060D01*
X1539831D01*
X1539922Y433968D01*
X1541497D01*
X1542011Y433454D01*
X1545040D01*
Y432200D01*
X1545566Y431674D01*
Y427218D01*
X1545123Y426775D01*
Y425589D01*
X1544320Y424785D01*
Y424726D01*
X1543723Y424129D01*
Y419460D01*
X1543544Y419280D01*
X1540784D01*
X1539860Y420204D01*
X1539695D01*
X1539520Y420380D01*
Y420600D01*
X1539472Y420648D01*
X1539471Y420652D01*
X1539468D01*
X1539450Y420670D01*
X1538572D01*
X1538237Y420335D01*
Y420255D01*
X1537495Y419514D01*
X1534601D01*
X1534039Y420076D01*
X1533998D01*
X1533296Y420777D01*
X1532382D01*
X1532055Y420450D01*
Y420150D01*
X1531105Y419200D01*
X1529810D01*
X1529490Y419520D01*
X1527490D01*
X1527170Y419200D01*
X1523628D01*
G37*
G36*
G01X1527582Y415057D02*
X1524257D01*
X1521200Y412000D01*
Y411400D01*
X1518300Y408500D01*
X1516100D01*
X1514500Y410100D01*
Y411848D01*
G02X1515030Y412226I400J0D01*
G03X1516520Y414634I470J1374D01*
G02X1516518Y415201I281J284D01*
G01X1517216Y415900D01*
X1517469D01*
X1517529Y415827D01*
G03X1517865Y415528I1122J922D01*
G01X1517883Y415517D01*
X1518000Y415400D01*
X1518114D01*
X1518148Y415388D01*
G03X1520064Y416422I502J1362D01*
G01X1520077Y416477D01*
X1520100Y416500D01*
Y416679D01*
G03Y416821I-1450J71D01*
G01Y417400D01*
X1520856Y418156D01*
X1527271D01*
X1527450Y417977D01*
X1531298D01*
X1531947Y418626D01*
X1531970Y418639D01*
G03X1532444Y419074I-720J1261D01*
G01X1533206D01*
G03X1534800Y418504I1194J826D01*
G01X1534827Y418512D01*
X1537123D01*
X1537150Y418504D01*
G03X1538792Y419148I400J1396D01*
G01X1539458D01*
G03X1540017Y418619I1242J752D01*
G01X1540043Y418605D01*
X1540369Y418279D01*
X1543770D01*
Y417660D01*
X1544500D01*
X1544954Y417206D01*
Y413423D01*
X1544488Y412957D01*
X1543649D01*
X1540835Y415771D01*
X1540829D01*
X1540000Y416600D01*
X1538449D01*
X1536906Y415057D01*
X1528618D01*
X1528585Y415069D01*
G03X1527615I-485J-1369D01*
G01X1527582Y415057D01*
G37*
G36*
G01X1508923Y404279D02*
G02X1508524Y404653I0J400D01*
G03X1505825Y405458I-1499J-99D01*
G02X1505223Y405416I-319J241D01*
G01X1504860Y405779D01*
Y406282D01*
G02X1505062Y406482I200J0D01*
G03X1505092Y409386I13J1452D01*
G01X1505010Y409387D01*
X1504804Y409594D01*
Y411688D01*
X1504786D01*
X1503885Y412588D01*
Y412605D01*
X1503223Y413267D01*
Y413992D01*
X1503458Y414227D01*
X1505588D01*
X1505798Y414017D01*
Y413485D01*
X1508007Y411277D01*
G03X1510435Y409686I1193J-828D01*
G02X1511115I340J-210D01*
G03X1513303Y409354I1235J764D01*
G02X1513848Y409335I262J-302D01*
G01X1515685Y407498D01*
X1516947D01*
G02X1517326Y406969I1J-400D01*
G03X1518052Y405200I1374J-470D01*
G01X1518163Y405145D01*
Y404822D01*
X1517651D01*
X1517109Y404279D01*
X1516140D01*
X1515598Y404822D01*
X1515357D01*
X1514473Y405706D01*
X1511810D01*
G03X1509476Y404652I-885J-1152D01*
G02X1509077Y404279I-399J27D01*
G01X1508923D01*
G37*
G36*
G01X1501000Y442000D02*
X1500000Y443000D01*
Y445639D01*
G03X1500210Y448060I-775J1287D01*
G02X1500177Y448324I132J151D01*
G03X1500785Y450566I-2875J1983D01*
G03X1500181Y452292I-3510J-260D01*
G02X1500214Y452556I165J113D01*
G03X1500203Y454826I-989J1130D01*
G02X1500168Y455091I130J152D01*
G03X1500452Y455590I-2892J1976D01*
G02X1500699Y455694I181J-85D01*
G03Y458438I476J1372D01*
G02X1500452Y458542I-66J189D01*
G03X1500207Y458982I-3175J-1480D01*
G01X1500118Y459118D01*
X1501100Y460100D01*
G02X1501759Y459953I283J-283D01*
G03X1504261Y461351I1366J494D01*
G02X1504573Y462000I313J249D01*
G01X1505985D01*
G03X1506109Y461811I2990J1826D01*
G02X1506076Y461545I-164J-115D01*
G03X1508451Y460175I949J-1099D01*
G02X1508666Y460337I197J-37D01*
G03X1509284I309J3489D01*
G02X1509499Y460175I18J-199D01*
G03X1511874Y461545I1426J271D01*
G02X1511841Y461812I130J152D01*
G03X1511964Y462000I-2869J2011D01*
G01X1513377D01*
G02X1513689Y461351I-1J-400D01*
G03X1515961I1136J-905D01*
G02X1516273Y462000I313J249D01*
G01X1517277D01*
G02X1517589Y461351I-1J-400D01*
G03X1519861I1136J-905D01*
G02X1520173Y462000I313J249D01*
G01X1521177D01*
G02X1521489Y461351I-1J-400D01*
G03X1523761I1136J-905D01*
G02X1524073Y462000I313J249D01*
G01X1524500D01*
X1525167Y461333D01*
Y460961D01*
X1525156Y460929D01*
G03Y459963I1369J-483D01*
G01X1525167Y459931D01*
Y458732D01*
X1526314Y457585D01*
Y453426D01*
X1526718Y453022D01*
Y450882D01*
X1527321Y450279D01*
X1527899D01*
X1528379Y449798D01*
X1531815D01*
X1531817Y449800D01*
X1532337D01*
X1532824Y450287D01*
X1533386Y449724D01*
X1538110D01*
X1538185Y449800D01*
X1538400D01*
X1538900Y450300D01*
X1539484D01*
X1539885Y449898D01*
X1541415D01*
X1541416Y449900D01*
X1542100D01*
X1542800Y449200D01*
X1544768D01*
Y447436D01*
X1544872D01*
Y447060D01*
X1544591Y446779D01*
X1544260D01*
X1544025Y446544D01*
X1543936Y446549D01*
G03X1542401Y445191I-86J-1449D01*
G01X1542396Y445115D01*
X1541882Y444602D01*
X1540415D01*
X1539889Y445127D01*
Y445519D01*
X1539477Y445931D01*
X1538747D01*
X1538478Y445662D01*
Y445294D01*
X1538085Y444902D01*
X1537115D01*
X1536815Y445202D01*
X1536683D01*
Y445605D01*
X1536424Y445864D01*
X1535416D01*
X1535138Y445586D01*
Y445254D01*
X1533954Y444070D01*
X1530746D01*
X1529515Y445302D01*
X1529468D01*
X1529102Y445668D01*
Y445852D01*
X1527098D01*
Y445800D01*
X1526900D01*
X1525620Y444520D01*
X1525014D01*
X1524187Y445348D01*
X1523924D01*
Y445746D01*
X1523812Y445858D01*
X1523097D01*
G03X1522500Y446429I-1297J-758D01*
G01Y446978D01*
G03X1522564Y449485I-700J1272D01*
G02Y450165I210J340D01*
G03X1520581Y452189I-764J1235D01*
G02X1519906Y452195I-336J218D01*
G03X1517382Y452085I-1231J-770D01*
G02X1516672Y452080I-356J182D01*
G03X1513968Y451099I-1283J-679D01*
G02X1513577Y450616I-391J-83D01*
G01X1509384D01*
X1507070Y448302D01*
Y445287D01*
G02X1506404Y444987I-400J-1D01*
G03X1504501Y442794I-962J-1087D01*
G02X1504560Y442248I-260J-304D01*
G03X1504408Y442000I1156J-879D01*
G01X1501000D01*
G37*
G36*
G01X1476200Y403500D02*
X1475200Y404500D01*
Y408900D01*
X1476500Y410200D01*
X1480700D01*
G03X1483300I1300J646D01*
G01X1486594D01*
G03X1488456I931J1114D01*
G01X1490494D01*
G03X1492356I931J1114D01*
G01X1494394D01*
G03X1496256I931J1114D01*
G01X1498294D01*
G03X1498566Y410020I932J1113D01*
G01X1498594Y410006D01*
X1499100Y409500D01*
Y406060D01*
X1498938Y406028D01*
G03X1497749Y404273I287J-1474D01*
G01X1497769Y404169D01*
X1497100Y403500D01*
X1493158D01*
G02X1492783Y404041I-1J400D01*
G03X1490067I-1358J513D01*
G02X1489692Y403500I-374J-141D01*
G01X1489258D01*
G02X1488883Y404041I-1J400D01*
G03X1486167I-1358J513D01*
G02X1485792Y403500I-374J-141D01*
G01X1476200D01*
G37*
G36*
G01X1479144Y528079D02*
Y523313D01*
X1477988Y522157D01*
X1474043D01*
X1472050Y524150D01*
Y528245D01*
X1472226Y528421D01*
X1476801D01*
X1476986Y528236D01*
X1478987D01*
X1479144Y528079D01*
G37*
G36*
G01X1510200Y525000D02*
X1510002Y525198D01*
Y527002D01*
X1510000D01*
Y528300D01*
X1509000Y529300D01*
X1492100D01*
X1491000Y530400D01*
Y536500D01*
X1492200Y537700D01*
X1493798D01*
Y537698D01*
X1495802D01*
Y537700D01*
X1516561D01*
X1517969Y536292D01*
Y527443D01*
X1515526Y525000D01*
X1510200D01*
G37*
G36*
G01X1480930Y520695D02*
X1480374Y521251D01*
Y528025D01*
X1481292Y528943D01*
X1484695D01*
X1484864Y528774D01*
Y525624D01*
X1485231Y525257D01*
Y521149D01*
X1484784Y520702D01*
X1482698D01*
Y520695D01*
X1480930D01*
G37*
G36*
G01X1500900Y522400D02*
X1499900Y523400D01*
X1495700D01*
X1494900Y524200D01*
X1494000D01*
G03X1493860I-70J-1400D01*
G01X1487800D01*
X1487000Y525000D01*
Y528846D01*
X1487200Y529046D01*
X1490340D01*
X1490343Y529043D01*
X1490457D01*
X1491300Y528200D01*
X1507800D01*
X1508500Y527500D01*
Y527002D01*
X1508498D01*
Y524998D01*
X1508500D01*
Y523700D01*
X1507200Y522400D01*
X1500900D01*
G37*
G36*
G01X1581600Y554000D02*
X1579620Y555980D01*
Y557980D01*
X1578022Y559578D01*
Y559752D01*
X1575018D01*
Y559670D01*
X1573086D01*
Y559760D01*
X1570082D01*
Y559670D01*
X1557420D01*
X1552000Y565090D01*
Y570430D01*
X1550840Y571590D01*
X1535979D01*
X1534989Y570600D01*
Y566848D01*
X1533600Y565459D01*
X1508457D01*
X1505502Y568415D01*
Y587600D01*
G03X1504977Y588481I-1002J0D01*
G01X1504951Y588495D01*
X1504100Y589346D01*
Y600087D01*
X1503611Y600576D01*
Y602826D01*
X1503708Y602923D01*
X1506867D01*
X1508044Y604100D01*
X1530400D01*
X1534161Y600339D01*
Y599362D01*
X1534316Y599207D01*
G02X1534230Y598576I-283J-283D01*
G03X1536276Y596530I738J-1308D01*
G02X1536907Y596616I348J-197D01*
G01X1539758Y593765D01*
X1539759Y593683D01*
G03X1542893Y592365I1851J17D01*
G01X1545465D01*
X1547290Y590540D01*
X1551655D01*
X1551711Y590432D01*
G03X1552550Y589720I1289J668D01*
G01X1552595Y589705D01*
X1553356Y588944D01*
G02X1553344Y588366I-282J-283D01*
G03X1555466Y586244I1014J-1108D01*
G02X1556044Y586256I295J-270D01*
G01X1557600Y584700D01*
X1564287D01*
G03X1566491I1102J1021D01*
G01X1577100D01*
X1582648Y579152D01*
Y579009D01*
G03X1584500Y577158I1851J0D01*
G01X1584643D01*
X1587270Y574530D01*
Y567706D01*
X1587268D01*
Y562702D01*
X1587270D01*
Y560706D01*
X1587268D01*
Y555702D01*
X1587270D01*
Y554500D01*
X1586814Y554044D01*
X1583447D01*
G03X1582777Y554002I2J-5401D01*
G01X1582765Y554000D01*
X1581600D01*
G37*
G36*
G01X1479216Y535794D02*
X1479136Y535874D01*
X1471956D01*
X1471176Y536655D01*
Y539864D01*
X1479420D01*
X1480291Y540735D01*
Y541903D01*
X1480294Y541906D01*
Y543950D01*
X1480788Y544443D01*
X1484195D01*
X1484448Y544190D01*
Y541198D01*
X1484731D01*
Y536425D01*
X1484511Y536205D01*
X1482101D01*
X1481690Y535794D01*
X1479216D01*
G37*
G36*
G01X1485863Y536141D02*
Y540580D01*
X1486450Y541167D01*
Y541398D01*
X1486452D01*
Y544202D01*
X1486450D01*
Y546589D01*
X1486861Y547000D01*
X1489384D01*
X1489898Y546485D01*
Y544985D01*
X1490219Y544665D01*
Y544451D01*
X1491418Y543252D01*
X1495348D01*
X1496200Y542400D01*
Y539202D01*
X1493798D01*
Y538702D01*
X1491785D01*
X1491784Y538700D01*
X1490600D01*
X1489900Y538000D01*
Y536400D01*
X1489641Y536141D01*
X1485863D01*
G37*
G36*
G01X1480859Y530141D02*
X1480202Y530798D01*
Y533780D01*
X1481100Y534678D01*
X1484947D01*
X1485596Y534029D01*
X1489531D01*
X1489680Y533880D01*
Y530511D01*
X1489310Y530141D01*
X1480859D01*
G37*
G36*
G01X1482702Y605700D02*
Y606100D01*
X1477899D01*
X1477700Y606300D01*
Y607400D01*
X1477590Y607510D01*
Y610000D01*
X1477600Y610010D01*
Y610253D01*
X1477832D01*
X1477862Y610243D01*
G03X1479256Y610489I467J1428D01*
G02X1479767Y610475I247J-314D01*
G03X1482238Y611871I993J1127D01*
G02X1482514Y612325I393J72D01*
G03X1484235Y614244I-736J2391D01*
G01X1484266Y614406D01*
X1489814D01*
X1491728Y616320D01*
Y619383D01*
X1492569Y620224D01*
X1497289D01*
X1498800Y618713D01*
Y608555D01*
X1498772Y608528D01*
Y607172D01*
X1497300Y605700D01*
X1496202D01*
Y606140D01*
X1491198D01*
Y605700D01*
X1489702D01*
Y606100D01*
X1484698D01*
Y605700D01*
X1482702D01*
G37*
G36*
G01X1534440Y621200D02*
X1535400Y620240D01*
Y615103D01*
G02X1534988Y614703I-400J0D01*
G03X1534043Y612231I-40J-1401D01*
G02X1534039Y611616I-258J-306D01*
G03X1534984Y609131I889J-1084D01*
G02X1535400Y608731I16J-400D01*
G01Y604000D01*
X1535000Y603600D01*
X1533100D01*
X1531500Y605200D01*
Y606500D01*
X1530800Y607200D01*
X1512150D01*
X1511850Y607500D01*
Y610200D01*
X1512310Y610660D01*
X1517700D01*
X1518643Y611603D01*
Y612667D01*
X1520353Y614377D01*
X1526967D01*
X1528000Y615410D01*
Y620558D01*
X1528642Y621200D01*
X1534440D01*
G37*
G36*
G01X1557952Y80119D02*
Y82202D01*
X1557852D01*
Y87852D01*
X1558500Y88500D01*
Y94000D01*
X1557704Y94796D01*
X1557700Y94873D01*
G03X1555541Y96150I-1500J-73D01*
G01X1555413Y96087D01*
X1553500Y98000D01*
Y99000D01*
X1554000Y99500D01*
X1554027D01*
G03X1555192Y99485I600J1377D01*
G01X1555228Y99500D01*
X1557535D01*
X1557571Y99485D01*
G03X1558701I565J1392D01*
G01X1558737Y99500D01*
X1559500D01*
X1563076Y95924D01*
Y84601D01*
X1558593Y80119D01*
X1557952D01*
G37*
G36*
G01X1542126Y89313D02*
Y86933D01*
X1540122Y84930D01*
X1537034D01*
X1536938Y85026D01*
Y86356D01*
X1536913D01*
Y87752D01*
X1536938D01*
Y89756D01*
X1536913D01*
Y90952D01*
X1536938D01*
Y92956D01*
X1536913D01*
Y94152D01*
X1536938D01*
Y96156D01*
X1536913D01*
Y97352D01*
X1536938D01*
Y99356D01*
X1536913D01*
Y100552D01*
X1536938D01*
Y102545D01*
X1537092Y102700D01*
X1540202D01*
X1543013Y99889D01*
Y93304D01*
X1542703Y92994D01*
Y91933D01*
X1542700Y91916D01*
G03Y91404I1480J-256D01*
G01X1542703Y91387D01*
Y90369D01*
X1542890Y90182D01*
Y90078D01*
X1542126Y89313D01*
G37*
G36*
G01X1532381Y158757D02*
X1535143D01*
X1535800Y158100D01*
Y156566D01*
X1535748D01*
Y154564D01*
X1535800D01*
Y153066D01*
X1535748D01*
Y151064D01*
X1535800D01*
Y149566D01*
X1535748D01*
Y147548D01*
X1535239Y147039D01*
X1533559D01*
X1533535Y147212D01*
G03X1533091Y148106I-1550J-212D01*
G01X1532150Y149048D01*
Y154266D01*
X1532269Y154319D01*
G03Y156881I-569J1281D01*
G01X1532150Y156934D01*
Y158054D01*
X1532160Y158085D01*
G03X1532318Y158694I-4316J1445D01*
G01X1532381Y158757D01*
G37*
G36*
G01X1543222Y156643D02*
Y153491D01*
X1542659Y152928D01*
G02X1542376I-142J141D01*
G03X1540567Y150678I-1026J-1028D01*
G01Y150172D01*
X1540521Y150117D01*
G03X1540567Y147890I1310J-1087D01*
G01Y142997D01*
X1539786Y142216D01*
X1538000D01*
X1537264Y142952D01*
Y157536D01*
X1537605Y157876D01*
X1541989D01*
X1543222Y156643D01*
G37*
G36*
G01X1584331Y111411D02*
X1583219Y112523D01*
Y117990D01*
X1583526Y118298D01*
X1586566D01*
Y118510D01*
X1587194Y119138D01*
Y122268D01*
X1588426Y123500D01*
X1592342D01*
X1592700Y123142D01*
Y117300D01*
X1592400Y117000D01*
X1591900D01*
X1591600Y116700D01*
Y114400D01*
X1592614Y113386D01*
Y111586D01*
X1592438Y111411D01*
X1584331D01*
G37*
G36*
G01X1573900Y212460D02*
X1572210Y214150D01*
X1564250D01*
X1563750Y214650D01*
Y217150D01*
X1564600Y218000D01*
X1573498D01*
Y217998D01*
X1575502D01*
Y218000D01*
X1576900D01*
X1578900Y220000D01*
X1584800D01*
X1584822Y219978D01*
Y213023D01*
X1584372Y212572D01*
X1582188D01*
Y212460D01*
X1580542D01*
Y212592D01*
X1578538D01*
Y212460D01*
X1577042D01*
Y212592D01*
X1575038D01*
Y212460D01*
X1573900D01*
G37*
G36*
G01X1586550Y298950D02*
X1597200D01*
X1597984Y298166D01*
X1597998Y298118D01*
G03X1598041Y297980I15058J4616D01*
G01X1598050Y297951D01*
Y287946D01*
X1575564D01*
X1573554Y289956D01*
X1572043D01*
X1571957Y290042D01*
X1571227D01*
X1565957Y295312D01*
X1565002D01*
Y297052D01*
X1565000D01*
Y298500D01*
X1565650Y299150D01*
X1574950D01*
X1576100Y298000D01*
Y293502D01*
X1574598D01*
Y293002D01*
X1573598D01*
Y290998D01*
X1574598D01*
Y290498D01*
X1576100D01*
Y290250D01*
X1577700Y288650D01*
X1579500D01*
X1580850Y290000D01*
X1581198D01*
Y289998D01*
X1583002D01*
Y290000D01*
X1583998D01*
Y289998D01*
X1586002D01*
Y290000D01*
X1586300D01*
X1587100Y290800D01*
Y294950D01*
X1586250Y295800D01*
Y298650D01*
X1586550Y298950D01*
G37*
G36*
G01X1581502Y401100D02*
X1590824D01*
X1594645Y404921D01*
X1594786Y404792D01*
G03X1596996Y404991I1014J1108D01*
G01X1607798D01*
Y404948D01*
X1610652D01*
X1611500Y404100D01*
Y398000D01*
X1611100Y397600D01*
X1596610D01*
X1593820Y394810D01*
X1580008D01*
X1579366Y395452D01*
X1576433D01*
X1570854Y401030D01*
Y401970D01*
X1570986Y402102D01*
X1571142Y402258D01*
X1572742D01*
X1573798Y401201D01*
Y401098D01*
X1576802D01*
Y401100D01*
X1578498D01*
Y401098D01*
X1581502D01*
Y401100D01*
G37*
G36*
G01X1588010Y420524D02*
X1587055Y421479D01*
X1587046Y421544D01*
G03X1586980Y421813I-1486J-222D01*
G02X1587400Y422341I378J130D01*
G03X1589060Y423786I159J1494D01*
G02X1589447Y424173I400J-13D01*
G03X1587895Y425723I-51J1501D01*
G02X1587508Y425336I-400J13D01*
G03X1586285Y423039I51J-1501D01*
G02X1586051Y422744I-169J-106D01*
G03X1585780Y422810I-489J-1420D01*
G01X1585715Y422819D01*
X1583782Y424752D01*
Y426096D01*
G02X1584193Y426496I400J0D01*
G03X1582821Y428286I40J1451D01*
G02X1582326Y427994I-389J93D01*
G03X1582313Y427997I-333J-1413D01*
G01X1582261Y428011D01*
X1582069Y428203D01*
X1578534D01*
X1577478Y429259D01*
X1572686D01*
X1572527Y429100D01*
X1570784D01*
X1570383Y429502D01*
X1564349D01*
G03X1562801I-774J-1288D01*
G01X1555415D01*
X1553402Y431515D01*
Y433728D01*
X1554052Y433729D01*
Y434422D01*
X1553402D01*
Y434915D01*
X1553200Y435116D01*
Y435300D01*
X1553944Y436044D01*
Y436060D01*
X1555692Y437808D01*
X1565731D01*
G02X1566107Y437274I-1J-400D01*
G03X1568843I1368J-488D01*
G02X1569219Y437808I377J134D01*
G01X1569631D01*
G02X1570007Y437274I-1J-400D01*
G03X1572762Y436358I1367J-488D01*
G02X1573427Y436523I382J-118D01*
G01X1573850Y436100D01*
X1574498D01*
Y435998D01*
X1576502D01*
Y436100D01*
X1578312D01*
Y435762D01*
X1581316D01*
Y436100D01*
X1581662D01*
X1585811Y431951D01*
X1585826Y431920D01*
G03X1586132Y431487I1412J673D01*
G01X1586510Y431109D01*
Y431095D01*
X1588669Y428936D01*
X1595906D01*
G03X1597694I894J1564D01*
G01X1601352D01*
X1601852Y428436D01*
X1602099D01*
X1602534Y428000D01*
Y424405D01*
X1602412Y424353D01*
G03Y421589I588J-1382D01*
G01X1602534Y421537D01*
Y420772D01*
X1602286Y420524D01*
X1588010D01*
G37*
G36*
G01X1539325Y454000D02*
G03X1540917Y453160I1328J588D01*
G01X1541021Y453179D01*
X1541300Y452900D01*
Y451200D01*
X1541000Y450900D01*
X1540300D01*
X1539664Y451536D01*
Y451993D01*
X1539491Y452166D01*
X1538722D01*
X1538569Y452013D01*
Y451600D01*
X1537695Y450726D01*
X1533801D01*
X1533366Y451161D01*
Y452007D01*
X1533213Y452160D01*
X1532448D01*
X1532262Y451974D01*
Y451142D01*
X1531922Y450802D01*
X1531402D01*
X1531400Y450800D01*
X1528794D01*
X1528232Y451362D01*
Y451968D01*
X1528230Y451970D01*
Y453014D01*
X1528320Y453104D01*
G03X1528942Y453331I-174J1442D01*
G01X1530094D01*
X1530763Y454000D01*
X1531532D01*
G03X1533166I817J1200D01*
G01X1535483D01*
G03X1537117I817J1200D01*
G01X1539325D01*
G37*
G36*
G01X1545874Y450010D02*
Y450202D01*
X1543248D01*
X1542302Y451149D01*
Y453315D01*
X1542200Y453416D01*
Y454985D01*
X1542419Y455204D01*
X1544470D01*
Y452998D01*
X1545352D01*
X1545470Y452879D01*
Y452498D01*
X1548474D01*
Y452851D01*
X1548767D01*
X1548827Y452780D01*
G03X1550708Y454945I1112J934D01*
G02X1550637Y455567I212J339D01*
G01X1550981Y455911D01*
X1551115Y455828D01*
G03X1553233Y456551I760J1238D01*
G01X1553282Y456680D01*
X1554368D01*
X1554417Y456551D01*
G03X1557133I1358J515D01*
G01X1557182Y456680D01*
X1558268D01*
X1558317Y456551D01*
G03X1561033I1358J515D01*
G01X1561082Y456680D01*
X1562168D01*
X1562217Y456551D01*
G03X1564933I1358J515D01*
G01X1564982Y456680D01*
X1566068D01*
X1566117Y456551D01*
G03X1568833I1358J515D01*
G01X1568882Y456680D01*
X1569620D01*
X1570700Y455600D01*
X1572000D01*
X1572900Y456500D01*
Y458400D01*
X1573400Y458900D01*
X1575200D01*
X1575400Y458700D01*
Y457000D01*
X1576120Y456280D01*
X1578580D01*
X1578800Y456060D01*
Y454038D01*
X1576780D01*
Y453570D01*
X1574878D01*
Y454142D01*
X1572876D01*
Y453395D01*
X1572623Y453142D01*
X1572376D01*
Y452896D01*
X1571290Y451810D01*
Y451770D01*
X1569530Y450010D01*
X1569324D01*
G02X1568925Y450388I0J400D01*
G03X1566025I-1450J-82D01*
G02X1565626Y450010I-399J22D01*
G01X1565474D01*
G02X1565075Y450388I0J400D01*
G03X1562075I-1500J-82D01*
G02X1561676Y450010I-399J22D01*
G01X1561434D01*
G02X1561037Y450458I0J400D01*
G03X1558153I-1442J173D01*
G02X1557756Y450010I-397J-48D01*
G01X1553724D01*
G02X1553325Y450388I0J400D01*
G03X1550425I-1450J-82D01*
G02X1550026Y450010I-399J22D01*
G01X1545874D01*
G37*
G36*
G01X1597567Y457228D02*
G02X1597023Y456855I-400J0D01*
G03X1597661Y454628I-523J-1355D01*
G02X1598206Y454718I320J-240D01*
G01X1598604D01*
Y454698D01*
X1603608D01*
Y454718D01*
X1605112D01*
Y454694D01*
X1610062D01*
X1610140Y454617D01*
Y453706D01*
X1610145Y453700D01*
Y447045D01*
X1609619Y446519D01*
X1601797D01*
X1601746Y446644D01*
G03X1599054I-1346J-544D01*
G01X1599003Y446519D01*
X1592968D01*
X1589278Y450209D01*
G02X1589366Y450840I283J282D01*
G03X1589696Y451091I-736J1310D01*
G02X1590267Y451088I284J-282D01*
G03X1590280Y453194I1077J1046D01*
G02X1589709Y453197I-284J282D01*
G03X1587587Y453230I-1078J-1046D01*
G02X1587141Y453153I-279J287D01*
G03X1584687Y453136I-1222J-785D01*
G02X1584233Y453213I-172J361D01*
G03X1581777Y452434I-1025J-1028D01*
G02X1581121Y452200I-394J68D01*
G01X1580140D01*
Y458546D01*
X1581034Y459441D01*
Y460799D01*
G03X1581485Y461160I-664J1291D01*
G01X1584129D01*
G03X1584271I71J1450D01*
G01X1585040D01*
X1585640Y461760D01*
Y462423D01*
X1585641Y462435D01*
G03Y462785I-1441J175D01*
G01X1585640Y462797D01*
Y464128D01*
X1585740Y464228D01*
X1587728D01*
X1587940Y464017D01*
Y463410D01*
X1588204Y463146D01*
Y462249D01*
X1588960Y461493D01*
X1597234D01*
X1597300Y461426D01*
Y457835D01*
X1597567Y457569D01*
Y457228D01*
G37*
G36*
G01X1553393Y415216D02*
X1553012Y415597D01*
G03X1552786Y415825I-1138J-902D01*
G01X1552777Y415832D01*
X1550152Y418458D01*
Y418792D01*
X1549817D01*
X1549709Y418900D01*
X1548700D01*
X1546675Y420925D01*
X1546772Y421160D01*
Y424164D01*
X1546738D01*
X1546636Y424410D01*
X1546844Y424618D01*
X1548509D01*
X1548542Y424459D01*
G03X1549837Y426199I1422J294D01*
G01X1549744Y426191D01*
X1549414Y426522D01*
X1546568D01*
Y434054D01*
X1546165Y434456D01*
X1545523D01*
G02X1545162Y435027I0J400D01*
G03X1544931Y436620I-1312J623D01*
G02X1545228Y437287I297J267D01*
G01X1548406D01*
X1550393Y435300D01*
X1551600D01*
X1552400Y434500D01*
Y431100D01*
X1555000Y428500D01*
X1561727D01*
G02X1562126Y428125I0J-400D01*
G03X1565024I1449J89D01*
G02X1565423Y428500I399J-25D01*
G01X1569968D01*
X1571224Y427244D01*
X1577088D01*
X1577355Y426977D01*
Y423247D01*
X1576108Y422000D01*
X1572780D01*
X1572725Y422112D01*
G03X1569949Y420981I-1350J-658D01*
G01X1569988Y420864D01*
X1568424Y419300D01*
X1566393D01*
G03X1564657I-868J-1226D01*
G01X1562403D01*
G03X1560349Y417381I-778J-1226D01*
G01X1560420Y417250D01*
X1559255Y416085D01*
X1559210Y416070D01*
G03X1558369Y415329I465J-1376D01*
G01X1558314Y415216D01*
X1557136D01*
X1557081Y415329D01*
G03X1554469I-1306J-635D01*
G01X1554414Y415216D01*
X1553393D01*
G37*
G36*
G01X1542426Y434456D02*
X1541912Y434970D01*
X1540337D01*
X1539706Y435601D01*
Y435993D01*
X1537219Y438480D01*
Y439034D01*
X1537641Y439456D01*
X1540523D01*
X1540733Y439246D01*
X1540741D01*
X1541528Y438458D01*
X1541928D01*
Y438048D01*
X1542708D01*
G03X1543403Y437455I1242J752D01*
G01X1543440Y437440D01*
X1543650Y437230D01*
X1543473Y437053D01*
X1543426Y437039D01*
G03X1542690Y434776I424J-1389D01*
G01X1542731Y434723D01*
Y434456D01*
X1542426D01*
G37*
G36*
G01X1587263Y435043D02*
X1585004Y437302D01*
X1584536Y437769D01*
X1577614D01*
X1577345Y437500D01*
X1576502D01*
Y437502D01*
X1574340D01*
X1572976Y438865D01*
X1571043D01*
G02X1570694Y439460I0J400D01*
G03X1568156I-1269J706D01*
G02X1567807Y438865I-349J-195D01*
G01X1567143D01*
G02X1566794Y439460I0J400D01*
G03X1564256I-1269J706D01*
G02X1563907Y438865I-349J-195D01*
G01X1563300D01*
G02X1562948Y439454I0J400D01*
G03X1560302I-1323J712D01*
G02X1559950Y438865I-352J-189D01*
G01X1559400D01*
G02X1559048Y439454I0J400D01*
G03X1556402I-1323J712D01*
G02X1556050Y438865I-352J-189D01*
G01X1555325D01*
X1552388Y435928D01*
X1552015Y436302D01*
X1550808D01*
X1548821Y438288D01*
X1544008D01*
X1543419Y438877D01*
X1544058Y439515D01*
Y441459D01*
X1543578Y441939D01*
Y443000D01*
X1545109D01*
X1545417Y442692D01*
X1548870D01*
X1549417Y443239D01*
X1550061Y442594D01*
X1550713D01*
G03X1551738Y445042I1162J952D01*
G02X1551302Y445440I-36J398D01*
G01Y446464D01*
X1551311Y446493D01*
G03Y447359I-1386J433D01*
G01X1551302Y447388D01*
Y448529D01*
X1551643Y448870D01*
X1551736Y448861D01*
G03X1552488Y448990I139J1445D01*
G01X1552528Y449008D01*
X1562818D01*
G03X1564332I757J1298D01*
G01X1566185D01*
G02X1566326Y448667I0J-200D01*
G01X1566011Y448352D01*
X1565900Y448380D01*
G03X1566979Y447301I-375J-1454D01*
G01X1566951Y447412D01*
X1567573Y448034D01*
X1567714D01*
G02X1568083Y447482I0J-400D01*
G03X1570767I1342J-556D01*
G02X1571136Y448034I369J152D01*
G01X1572316D01*
X1572357Y448076D01*
X1573625D01*
X1574542Y448992D01*
Y449248D01*
X1581351D01*
X1581375Y449077D01*
G03X1581874Y448099I1685J243D01*
G02X1581747Y447443I-279J-286D01*
G03X1583712Y446438I553J-1343D01*
G01X1583686Y446546D01*
X1583944Y446805D01*
Y447866D01*
G03X1584745Y449077I-883J1455D01*
G01X1584769Y449248D01*
X1587262D01*
X1590249Y446261D01*
X1590154Y446124D01*
G03X1591864Y443942I1196J-824D01*
G02X1592405Y443568I141J-374D01*
G01Y443295D01*
X1592700Y443000D01*
X1592992D01*
Y442998D01*
X1598894D01*
Y443000D01*
X1600504D01*
X1601315Y442188D01*
Y435833D01*
X1600525Y435043D01*
X1587263D01*
G37*
G36*
G01X1553852Y472514D02*
G03Y475418I-27J1452D01*
G02X1553460Y475818I8J400D01*
G01Y477615D01*
X1553648Y477803D01*
G02X1554329Y477483I283J-282D01*
G03X1555638Y478792I1446J-137D01*
G02X1555318Y479473I-38J398D01*
G01X1555575Y479730D01*
X1556668D01*
G03X1558782I1057J996D01*
G01X1560501D01*
G03X1563119Y480571I1124J996D01*
G01X1563126Y480641D01*
X1563393Y480908D01*
G02X1564075Y480647I283J-283D01*
G03X1565604Y482176I1450J79D01*
G02X1565343Y482858I22J399D01*
G01X1565733Y483248D01*
G02X1566331Y483212I283J-283D01*
G03X1568369Y485250I1144J894D01*
G02X1568333Y485848I247J315D01*
G01X1568484Y485999D01*
G02X1569046Y486002I283J-283D01*
G03X1571296Y486274I1016J1037D01*
G01X1577700D01*
X1578974Y485000D01*
X1587298D01*
Y484998D01*
X1589398D01*
X1590726Y486326D01*
Y490209D01*
X1592892Y492375D01*
X1607520D01*
X1608496Y493351D01*
X1609448D01*
Y493348D01*
X1613298D01*
Y492985D01*
X1613328Y492956D01*
Y492245D01*
X1612998Y491916D01*
Y488798D01*
X1612547Y488347D01*
Y484529D01*
X1612160Y484142D01*
X1605076D01*
X1603785Y482850D01*
X1598250D01*
X1595900Y480500D01*
Y474500D01*
X1595061Y473661D01*
X1594933Y473723D01*
G03X1592927Y471717I-653J-1353D01*
G01X1592989Y471589D01*
X1590768Y469368D01*
X1585565D01*
X1585451Y469254D01*
X1581915D01*
X1575630Y462970D01*
X1572870D01*
X1572600Y462700D01*
Y459939D01*
X1571165Y458504D01*
X1571104Y458493D01*
G03X1570060Y457682I271J-1427D01*
G01X1568790D01*
G03X1566160I-1315J-616D01*
G01X1564890D01*
G03X1562260I-1315J-616D01*
G01X1560990D01*
G03X1558360I-1315J-616D01*
G01X1557090D01*
G03X1554460I-1315J-616D01*
G01X1553190D01*
G03X1550501Y457535I-1315J-616D01*
G01X1550455Y457400D01*
X1549395D01*
X1549349Y457535D01*
G03X1546601I-1374J-469D01*
G01X1546563Y457424D01*
X1546539Y457400D01*
X1545495D01*
X1545449Y457535D01*
G03X1542701I-1374J-469D01*
G01X1542655Y457400D01*
X1541595D01*
X1541549Y457535D01*
G03X1538801I-1374J-469D01*
G01X1538755Y457400D01*
X1533541D01*
X1532743Y456602D01*
X1532637Y456623D01*
G03X1530897Y455201I-288J-1423D01*
G01Y455002D01*
X1530348D01*
X1530189Y454842D01*
G02X1529526Y455000I-283J283D01*
G03X1527809Y455958I-1379J-454D01*
G02X1527316Y456347I-93J389D01*
G01Y458000D01*
X1526863Y458452D01*
Y459027D01*
X1526998Y459073D01*
G03Y461819I-473J1373D01*
G01X1526863Y461865D01*
Y462360D01*
G02X1527518Y462668I400J0D01*
G03X1529937Y463480I957J1158D01*
G01X1529973Y463634D01*
X1530927D01*
X1530964Y463481D01*
G03X1533786I1411J345D01*
G01X1533823Y463634D01*
X1534777D01*
X1534813Y463480D01*
G03X1537737I1462J346D01*
G01X1537773Y463634D01*
X1538727D01*
X1538764Y463481D01*
G03X1541586I1411J345D01*
G01X1541623Y463634D01*
X1542627D01*
X1542664Y463481D01*
G03X1545486I1411J345D01*
G01X1545523Y463634D01*
X1546527D01*
X1546564Y463481D01*
G03X1549378Y464201I1411J345D01*
G01X1549348Y464312D01*
X1551827Y466791D01*
G02X1552480Y466659I283J-283D01*
G03X1553852Y468658I1345J547D01*
G02X1553460Y469058I8J400D01*
G01Y472114D01*
G02X1553852Y472514I400J0D01*
G37*
G36*
G01X1625670Y473930D02*
Y469947D01*
X1624709Y468985D01*
X1624571Y469082D01*
G03X1624045Y466392I-866J-1227D01*
G02X1624536Y466002I91J-390D01*
G01Y465611D01*
X1624300D01*
X1624267Y465623D01*
G03X1622302Y463809I-518J-1410D01*
G02X1622076Y463335I-385J-107D01*
G03X1621136Y461900I625J-1435D01*
G01Y458862D01*
X1621560Y458437D01*
X1621575Y458389D01*
G03X1621610Y458284I1726J517D01*
G01X1621623Y458250D01*
Y458014D01*
X1598538D01*
X1598302Y458250D01*
Y462597D01*
X1597331Y463568D01*
X1589198D01*
X1588941Y463825D01*
Y465129D01*
X1588298Y465772D01*
X1586080D01*
X1585700Y466152D01*
Y468087D01*
X1585980Y468367D01*
X1601063D01*
X1601535Y467895D01*
X1604088D01*
X1605695Y466288D01*
X1610314D01*
X1611200Y467174D01*
Y472200D01*
X1609925Y473475D01*
Y478375D01*
X1610208Y478658D01*
X1612336D01*
X1613187Y477807D01*
G02X1613134Y477197I-283J-283D01*
G03X1615501Y475907I866J-1227D01*
G01X1615509Y476098D01*
X1616192D01*
X1616199Y475905D01*
G03X1619201I1501J52D01*
G01X1619208Y476098D01*
X1622885D01*
X1624861Y474122D01*
X1625478D01*
X1625670Y473930D01*
G37*
G36*
G01X1581071Y486200D02*
X1580783Y486488D01*
Y490403D01*
X1581161Y490782D01*
X1589118D01*
X1589600Y490300D01*
Y486900D01*
X1589202Y486502D01*
X1587298D01*
Y486200D01*
X1581071D01*
G37*
G36*
G01X1551313Y596880D02*
X1550942Y597251D01*
Y602799D01*
X1551225Y603082D01*
Y607936D01*
X1556708D01*
X1557103Y608330D01*
X1557151Y608345D01*
G03X1558355Y609549I-521J1725D01*
G01X1558370Y609597D01*
X1558604Y609831D01*
Y611560D01*
X1560000Y612957D01*
X1564237D01*
X1565869Y611325D01*
Y605673D01*
X1565832Y605636D01*
X1565869Y605600D01*
Y602953D01*
G03Y600447I1431J-1253D01*
G01Y599369D01*
X1564702Y598202D01*
X1555386D01*
X1554065Y596880D01*
X1551313D01*
G37*
G36*
G01X1546300Y593000D02*
X1543800Y595500D01*
Y598900D01*
X1544800Y599900D01*
X1546700D01*
X1547200Y600400D01*
Y602300D01*
X1547300Y602400D01*
X1549370D01*
Y600308D01*
X1549400D01*
Y598812D01*
X1549370D01*
Y596808D01*
X1549400D01*
Y595312D01*
X1549370D01*
Y593312D01*
X1549057Y593000D01*
X1546300D01*
G37*
G36*
G01X1615325Y100638D02*
X1618409D01*
X1620654Y98394D01*
Y89103D01*
X1620218Y88667D01*
X1612490D01*
X1612131Y89026D01*
Y92002D01*
X1612100Y92032D01*
Y92040D01*
X1612094D01*
X1610728Y93405D01*
Y94998D01*
X1610752D01*
Y97017D01*
X1611036Y97301D01*
X1614276D01*
X1614781Y97806D01*
Y100094D01*
X1615325Y100638D01*
G37*
G36*
G01X1647532Y140770D02*
X1644616Y143686D01*
Y148477D01*
X1645117Y148978D01*
Y151011D01*
X1645123Y151017D01*
Y151663D01*
X1645260Y151800D01*
X1649328D01*
X1649728Y151400D01*
Y149410D01*
X1649570Y149252D01*
X1647596D01*
Y149240D01*
X1647400D01*
X1646912Y148752D01*
X1646596D01*
Y148436D01*
X1646575Y148415D01*
Y144746D01*
X1646600Y144721D01*
Y143748D01*
X1646702D01*
X1647250Y143200D01*
X1649522D01*
X1649862Y142860D01*
Y140920D01*
X1649712Y140770D01*
X1647532D01*
G37*
G36*
G01X1622968Y142632D02*
X1622702Y142898D01*
Y144870D01*
X1624103D01*
X1624711Y145478D01*
X1625898D01*
Y145298D01*
X1627902D01*
Y145478D01*
X1630718D01*
X1631408Y146168D01*
X1633052D01*
Y146432D01*
X1633319Y146700D01*
X1633375D01*
X1634224Y147548D01*
X1636470D01*
Y145360D01*
X1637072Y144758D01*
X1637406D01*
X1637802Y144362D01*
X1639428D01*
X1639562Y144228D01*
Y143220D01*
X1639120Y142778D01*
X1627858D01*
X1627712Y142632D01*
X1622968D01*
G37*
G36*
G01X1623748Y95098D02*
X1623650Y95000D01*
X1621810D01*
X1621740Y95070D01*
Y99140D01*
X1619280Y101600D01*
Y106400D01*
X1621200Y108320D01*
Y108498D01*
X1621252D01*
Y110482D01*
X1621830Y111060D01*
Y115338D01*
X1621890D01*
Y117342D01*
X1621830D01*
Y118483D01*
X1623007Y119660D01*
X1623760D01*
X1624036Y119384D01*
Y118288D01*
X1623974Y118225D01*
Y107313D01*
X1624120Y107167D01*
Y104410D01*
X1623760Y104050D01*
Y104002D01*
X1623748D01*
Y101998D01*
X1623760D01*
Y100502D01*
X1623748D01*
Y98498D01*
X1623760D01*
Y97002D01*
X1623748D01*
Y95098D01*
G37*
G36*
G01X1641502Y123678D02*
Y124002D01*
X1640999D01*
X1640857Y124144D01*
Y125434D01*
X1639114Y127177D01*
X1637140D01*
X1637020Y127297D01*
X1633413D01*
X1633116Y127000D01*
Y126721D01*
X1632773Y126378D01*
X1631599D01*
X1631001Y125780D01*
X1627678D01*
X1627037Y126421D01*
X1625221D01*
X1624779Y125979D01*
Y125291D01*
X1623560Y124072D01*
X1622284D01*
X1621927Y124429D01*
Y140954D01*
X1622249Y141276D01*
Y141406D01*
X1622422Y141579D01*
X1628325D01*
X1628362Y141542D01*
X1639300D01*
X1640563Y142805D01*
Y144643D01*
X1639843Y145363D01*
X1638217D01*
X1637982Y145598D01*
Y147472D01*
X1637960D01*
Y148250D01*
X1637660Y148550D01*
X1633809D01*
X1632960Y147701D01*
X1629558D01*
X1628652Y146795D01*
X1627902D01*
Y146802D01*
X1626526D01*
X1626514Y146813D01*
X1624630D01*
X1623688Y145871D01*
X1622276D01*
X1621927Y146220D01*
Y148527D01*
X1625378Y151978D01*
X1625740D01*
X1625775Y151964D01*
G03X1626851I538J1348D01*
G01X1626886Y151978D01*
X1628983D01*
X1629016Y151966D01*
G03X1629233Y151908I469J1321D01*
G02Y151514I-37J-197D01*
G03X1629745I256J-1378D01*
G02Y151908I37J197D01*
G03X1629962Y151966I-252J1379D01*
G01X1629995Y151978D01*
X1632132D01*
X1632165Y151966D01*
G03X1633111I473J1320D01*
G01X1633144Y151978D01*
X1633678D01*
X1634478Y152778D01*
Y153878D01*
X1634796Y154196D01*
X1636759D01*
X1637378Y153578D01*
Y152278D01*
X1637878Y151778D01*
X1639391D01*
X1640513Y150656D01*
Y149041D01*
X1641478Y148076D01*
X1643209D01*
X1643587Y147698D01*
Y143110D01*
X1646147Y140550D01*
Y129952D01*
X1645252D01*
X1645041Y129740D01*
X1644991Y129726D01*
G03X1645665Y127006I386J-1348D01*
G02X1646147Y126614I82J-392D01*
G01Y124147D01*
X1646002Y124002D01*
X1642498D01*
Y123678D01*
X1641502D01*
G37*
G36*
G01X1637009Y155198D02*
X1634381D01*
X1633476Y154293D01*
Y153193D01*
X1633263Y152980D01*
X1631908D01*
X1631849Y153038D01*
Y154570D01*
G03X1632050Y155138I-700J567D01*
G01Y157738D01*
G03X1631699Y158452I-902J0D01*
G01X1631689Y158460D01*
X1630894Y159255D01*
Y167494D01*
X1629404Y168983D01*
Y175549D01*
X1631878Y178023D01*
Y178434D01*
X1631882D01*
Y180438D01*
X1631860D01*
X1629836Y182461D01*
Y184664D01*
X1627000Y187500D01*
Y193000D01*
X1627336Y193336D01*
X1630640D01*
X1630872Y193104D01*
Y188229D01*
X1631156Y187945D01*
X1632536D01*
X1633896Y186585D01*
Y185104D01*
X1633954Y185046D01*
X1633968Y185000D01*
G03X1634245Y184503I1382J445D01*
G02X1634191Y183932I-305J-259D01*
G03X1634573Y181447I909J-1132D01*
G01X1634700Y181398D01*
Y175225D01*
X1634697Y175228D01*
Y173002D01*
X1633506Y171810D01*
Y170467D01*
G03Y167333I664J-1567D01*
G01Y161742D01*
X1634349Y160898D01*
Y159038D01*
X1634849Y158538D01*
X1634853D01*
X1634908Y158494D01*
G03X1636720Y158538I880J1091D01*
G01X1636849D01*
X1637349Y158038D01*
Y157740D01*
X1637348D01*
Y155536D01*
X1637009Y155198D01*
G37*
G36*
G01X1649060Y154785D02*
X1649380Y154465D01*
Y152802D01*
X1644845D01*
X1644424Y152380D01*
X1644026D01*
X1643616Y151970D01*
Y151752D01*
X1643610D01*
Y151548D01*
X1643608Y151547D01*
Y149078D01*
X1641893D01*
X1641514Y149456D01*
Y151071D01*
X1641409Y151176D01*
Y152384D01*
X1641119Y152674D01*
Y153755D01*
X1641800Y154436D01*
X1643376D01*
X1643730Y154790D01*
X1643928D01*
Y154698D01*
X1645932D01*
Y154785D01*
X1649060D01*
G37*
G36*
G01X1608370Y190530D02*
X1607000Y191900D01*
Y197770D01*
X1607830Y198600D01*
X1616450D01*
X1617158Y197892D01*
Y194684D01*
X1617500Y194342D01*
Y190790D01*
X1617240Y190530D01*
X1608370D01*
G37*
G36*
G01X1656054Y299500D02*
X1656023Y299510D01*
G03X1655526Y299592I-500J-1483D01*
G01X1654408D01*
X1653700Y300300D01*
Y301950D01*
X1652450Y303200D01*
X1646050D01*
X1643650Y300800D01*
X1639200D01*
X1639050Y300950D01*
Y305353D01*
X1640948Y307251D01*
X1651201D01*
X1652200Y308250D01*
X1657350D01*
X1659500Y306100D01*
Y300350D01*
X1658650Y299500D01*
X1656054D01*
G37*
G36*
G01X1658498Y319734D02*
X1657765Y319000D01*
X1655000D01*
X1653750Y320250D01*
X1652150D01*
X1651974Y320425D01*
Y321002D01*
X1651474D01*
Y322002D01*
X1649250D01*
Y323314D01*
X1649645Y323709D01*
X1651157D01*
X1652346Y322520D01*
X1654160D01*
X1654925Y321755D01*
X1654998D01*
Y321748D01*
X1657002D01*
Y321755D01*
X1660745D01*
X1660850Y321650D01*
Y320110D01*
X1660500Y319760D01*
X1658525D01*
X1658516Y319752D01*
X1658498D01*
Y319734D01*
G37*
G36*
G01X1664700Y290750D02*
X1657821D01*
X1654094Y287024D01*
X1653970Y286900D01*
X1650818D01*
X1648802Y288916D01*
Y289552D01*
X1648800D01*
Y290250D01*
X1648300Y290750D01*
X1643350D01*
X1643000Y291100D01*
Y294400D01*
X1643790Y295190D01*
X1643798D01*
Y295198D01*
X1645850Y297250D01*
X1649750D01*
X1649850Y297150D01*
X1649886D01*
Y291547D01*
X1649900Y291532D01*
Y289650D01*
X1650400Y289150D01*
X1650698D01*
Y289148D01*
X1652502D01*
Y289150D01*
X1652650D01*
X1654200Y290700D01*
Y294000D01*
X1654416Y294216D01*
X1658028D01*
Y296550D01*
X1665450D01*
X1665600Y296400D01*
Y291706D01*
X1665036Y291141D01*
Y291085D01*
X1664700Y290750D01*
G37*
G36*
G01X1597656Y396123D02*
X1608614D01*
X1609596Y395141D01*
Y386690D01*
X1609281Y386375D01*
X1597517D01*
X1597175Y386717D01*
Y395642D01*
X1597656Y396123D01*
G37*
G36*
G01X1604944Y365622D02*
X1604765Y365801D01*
Y373432D01*
X1604915Y373582D01*
X1610709D01*
X1610849Y373442D01*
Y371956D01*
X1608038Y369145D01*
Y366325D01*
X1607335Y365622D01*
X1604944D01*
G37*
G36*
G01X1598222Y365572D02*
X1596908Y366886D01*
Y371705D01*
X1598751Y373548D01*
X1602638D01*
X1602748Y373438D01*
Y370446D01*
X1602769D01*
Y368750D01*
X1602748D01*
Y365767D01*
X1602553Y365572D01*
X1598222D01*
G37*
G36*
G01X1631002Y485000D02*
Y485002D01*
X1625998D01*
X1625698Y485302D01*
X1618411D01*
X1618199Y485090D01*
X1614672D01*
X1614562Y485200D01*
Y488272D01*
X1613999Y488835D01*
Y491500D01*
X1614275Y491775D01*
X1617875D01*
X1618500Y492400D01*
Y492998D01*
X1618502D01*
Y495002D01*
X1618500D01*
Y495350D01*
X1618750Y495600D01*
X1622400D01*
X1623208Y494792D01*
Y493205D01*
X1624113Y492300D01*
X1626850D01*
X1627775Y491375D01*
Y490825D01*
X1628208Y490392D01*
X1628213Y490386D01*
G03X1628386Y490213I1287J1114D01*
G01X1628392Y490208D01*
X1628850Y489750D01*
X1630750D01*
X1631600Y488900D01*
Y485250D01*
X1631350Y485000D01*
X1631002D01*
G37*
G36*
G01X1622300Y507500D02*
X1622000Y507800D01*
Y508198D01*
X1622002D01*
Y511002D01*
X1622000D01*
Y512698D01*
X1622002D01*
Y515702D01*
X1622100Y515800D01*
X1625147D01*
X1627504Y513443D01*
Y510269D01*
X1625898Y508663D01*
Y507500D01*
X1622300D01*
G37*
G36*
G01X1614800Y507200D02*
X1614000Y508000D01*
Y510227D01*
G03Y510373I-1500J73D01*
G01Y512500D01*
X1616500Y515000D01*
Y515384D01*
X1617316Y516200D01*
X1619400D01*
X1619998Y515601D01*
Y512698D01*
X1620000D01*
Y511002D01*
X1619998D01*
Y507999D01*
X1619200Y507200D01*
X1614800D01*
G37*
G36*
G01X1615310Y477100D02*
X1613204Y479206D01*
Y479221D01*
X1612274Y480151D01*
X1612178D01*
Y480170D01*
X1610172D01*
Y480151D01*
X1609931D01*
X1609152Y479372D01*
Y479052D01*
X1608652Y478552D01*
X1604948D01*
X1604850Y478650D01*
Y482150D01*
X1605712Y483012D01*
X1618269D01*
X1618985Y482296D01*
X1624684D01*
X1626180Y480800D01*
X1631100D01*
X1631600Y480300D01*
Y475800D01*
X1630924Y475124D01*
X1625276D01*
X1623300Y477100D01*
X1618595D01*
G03X1616805I-895J-1143D01*
G01X1615310D01*
G37*
G36*
G01X1614800Y492900D02*
X1614300Y493400D01*
Y494700D01*
X1613629Y495371D01*
X1608516D01*
X1607692Y496195D01*
X1607700Y496203D01*
Y511700D01*
X1616459Y520459D01*
X1618212D01*
X1618633Y520038D01*
Y518933D01*
X1611000Y511300D01*
Y508757D01*
X1613590Y506167D01*
X1617493D01*
X1619260Y504400D01*
Y498260D01*
X1617000Y496000D01*
Y495002D01*
X1616998D01*
Y492900D01*
X1614800D01*
G37*
G36*
G01X1605808Y468316D02*
X1605595Y468528D01*
X1604723Y469400D01*
X1603702D01*
Y469402D01*
X1601598D01*
X1599798Y471202D01*
Y473098D01*
X1597500Y475396D01*
Y480546D01*
X1598754Y481800D01*
X1603200D01*
X1603700Y481300D01*
Y477631D01*
X1604780Y476551D01*
X1604948D01*
Y476548D01*
X1608602D01*
X1608900Y476250D01*
Y473260D01*
X1608924Y473236D01*
Y473060D01*
X1610198Y471785D01*
Y468531D01*
X1609983Y468316D01*
X1605808D01*
G37*
G36*
G01X1590406Y555710D02*
X1590300Y555816D01*
Y579650D01*
X1590900Y580250D01*
Y583950D01*
X1591300Y584350D01*
X1596900D01*
X1597800Y583450D01*
Y573079D01*
X1597796Y573059D01*
G03Y572501I1374J-279D01*
G01X1597800Y572481D01*
Y571754D01*
X1597827Y571727D01*
Y569673D01*
X1600520Y566980D01*
Y556420D01*
X1599810Y555710D01*
X1590406D01*
G37*
G36*
G01X1663400Y155500D02*
X1663150Y155750D01*
Y157900D01*
X1662700Y158350D01*
Y162200D01*
X1662800Y162300D01*
X1671800D01*
X1672200Y162700D01*
X1675600D01*
X1677075Y164175D01*
Y164659D01*
X1677602Y165185D01*
Y166752D01*
X1678750Y167900D01*
Y168450D01*
X1680000Y169700D01*
Y170800D01*
X1680600Y171400D01*
X1683414D01*
Y168464D01*
X1682600Y167650D01*
Y164300D01*
X1682300Y164000D01*
X1679500D01*
X1676650Y161150D01*
Y160550D01*
X1674825Y158725D01*
X1666675D01*
X1665150Y157200D01*
Y156050D01*
X1664600Y155500D01*
X1663400D01*
G37*
G36*
G01X1662700Y163900D02*
X1662600Y164000D01*
Y167474D01*
X1664576Y169450D01*
X1670950D01*
X1673280Y171780D01*
X1673422Y171638D01*
G03X1675628Y171802I1033J1020D01*
G01X1676273D01*
G03X1678145Y171194I1326J898D01*
G02X1678681Y170817I136J-376D01*
G01Y170000D01*
X1676600Y167919D01*
Y165600D01*
X1675900Y164900D01*
X1675532D01*
X1672530D01*
X1672100D01*
X1671100Y163900D01*
X1662700D01*
G37*
G36*
G01X1651950Y330817D02*
Y331185D01*
X1653426Y332661D01*
X1659154D01*
X1659800Y332015D01*
Y328302D01*
X1659798D01*
Y326298D01*
X1659800D01*
Y324150D01*
X1658900Y323250D01*
X1657002D01*
Y323252D01*
X1654998D01*
X1654750Y323500D01*
Y329700D01*
X1653850Y330600D01*
X1653262D01*
X1653245Y330603D01*
G03X1652991Y330624I-256J-1544D01*
G01X1652143D01*
X1651950Y330817D01*
G37*
G36*
G01X1656134Y286810D02*
Y287534D01*
X1657250Y288650D01*
X1664500D01*
X1664650Y288500D01*
Y287342D01*
X1663857Y286550D01*
X1656394D01*
X1656134Y286810D01*
G37*
G36*
G01X1737600Y50460D02*
X1736320Y51740D01*
X1733750D01*
X1731390Y54100D01*
X1721900D01*
X1721600Y54400D01*
Y55843D01*
X1721757Y56000D01*
X1733600D01*
X1734050Y56450D01*
X1736450D01*
X1736950Y56950D01*
Y58950D01*
X1739200Y61200D01*
Y62800D01*
X1739600Y63200D01*
X1742100D01*
X1742600Y62700D01*
Y60500D01*
X1742100Y60000D01*
X1741500D01*
X1740500Y59000D01*
Y58802D01*
X1740498D01*
Y56798D01*
X1740500D01*
Y55702D01*
X1740498D01*
Y53698D01*
X1740500D01*
Y52602D01*
X1740498D01*
Y50599D01*
X1740360Y50460D01*
X1737600D01*
G37*
G36*
G01X1748355Y108096D02*
X1747253Y109198D01*
Y113940D01*
X1747408Y114094D01*
X1758689D01*
X1758784Y114000D01*
Y111200D01*
X1757848Y110265D01*
Y110256D01*
X1755688Y108096D01*
X1748355D01*
G37*
G36*
G01X1759200Y107400D02*
X1758850Y107750D01*
Y109850D01*
X1760050Y111050D01*
Y115200D01*
X1759650Y115600D01*
X1759026D01*
Y115602D01*
X1757024D01*
Y115600D01*
X1755826D01*
Y115602D01*
X1753824D01*
Y115600D01*
X1752626D01*
Y115602D01*
X1750624D01*
Y115600D01*
X1749426D01*
Y115602D01*
X1747448D01*
X1746800Y116250D01*
Y120400D01*
X1747200Y120800D01*
X1748900D01*
X1750100Y119600D01*
Y118350D01*
X1751000Y117450D01*
X1761850D01*
X1762000Y117300D01*
Y107850D01*
X1761550Y107400D01*
X1759200D01*
G37*
G36*
G01X1738500Y94600D02*
X1737900Y95200D01*
Y99100D01*
X1738800Y100000D01*
X1740750D01*
G02X1741075Y99367I0J-400D01*
G03X1743353I1139J-817D01*
G02X1743678Y100000I325J233D01*
G01X1747000D01*
X1747250Y100250D01*
X1748750D01*
X1755150Y106650D01*
X1760121D01*
G03X1760279I79J2250D01*
G01X1761550D01*
X1763550Y108650D01*
Y117350D01*
X1763700Y117500D01*
X1764940D01*
G03X1765090I75J1600D01*
G01X1765410D01*
X1765475Y117565D01*
X1765520Y117580D01*
G03X1766361Y119969I-505J1520D01*
G01Y147456D01*
X1765342Y148475D01*
Y163212D01*
X1756890Y171664D01*
X1717916D01*
X1717875Y171623D01*
X1717810Y171613D01*
G03X1716788Y170425I179J-1188D01*
G01Y169025D01*
G03X1716894Y168530I1209J0D01*
G01X1716912Y168491D01*
Y166903D01*
X1716894Y166864D01*
G03X1716788Y166369I1103J-495D01*
G01Y164969D01*
G03X1716790Y164891I1201J-8D01*
G01X1716796Y164801D01*
X1716359Y164364D01*
X1713382D01*
X1713312Y164434D01*
Y166402D01*
X1713227Y166609D01*
X1713358Y166740D01*
Y168970D01*
G03X1713312Y169376I-1852J-4D01*
G01X1713308Y169398D01*
Y170268D01*
X1713336D01*
Y173766D01*
X1713772Y174201D01*
X1713837Y174211D01*
G03X1715198Y175816I-241J1584D01*
G01X1715197Y175901D01*
X1716758Y177462D01*
X1723693D01*
X1725906Y175249D01*
Y175205D01*
X1725972Y175139D01*
X1726388D01*
X1726432Y175115D01*
G03X1727694Y175003I761J1410D01*
G01X1727725Y175014D01*
X1731661D01*
X1731692Y175003D01*
G03X1732996Y175139I500J1522D01*
G01X1738989D01*
G03X1740293Y175003I804J1386D01*
G01X1740324Y175014D01*
X1744260D01*
X1744291Y175003D01*
G03X1745595Y175139I500J1522D01*
G01X1746349D01*
X1748443Y177233D01*
X1750130D01*
X1750683Y176680D01*
Y175773D01*
X1751746Y174710D01*
X1778985D01*
X1781450Y172245D01*
Y157071D01*
G03Y154729I1499J-1171D01*
G01Y127631D01*
X1780048Y126229D01*
Y121112D01*
X1774112Y115176D01*
X1771029D01*
X1768642Y112789D01*
Y108182D01*
X1766741Y106281D01*
X1766694Y106266D01*
G03X1765484Y105056I556J-1766D01*
G01X1765469Y105009D01*
X1764173Y103713D01*
X1764144Y103699D01*
G03X1763301Y102856I856J-1699D01*
G01X1763287Y102827D01*
X1761910Y101450D01*
Y97410D01*
X1759450Y94950D01*
X1755050D01*
X1754700Y94600D01*
X1753062D01*
Y94612D01*
X1751058D01*
Y94600D01*
X1748225D01*
G02X1747851Y95140I0J400D01*
G03X1745131I-1360J510D01*
G02X1744757Y94600I-374J-140D01*
G01X1741302D01*
Y94602D01*
X1739298D01*
Y94600D01*
X1738500D01*
G37*
G36*
G01X1729434Y197850D02*
X1728800D01*
X1727150Y196200D01*
X1724913D01*
X1724000Y197113D01*
Y200200D01*
X1723100Y201100D01*
X1717550D01*
X1717250Y201400D01*
Y203350D01*
X1717650Y203750D01*
X1717998D01*
Y203748D01*
X1720002D01*
Y203750D01*
X1721498D01*
Y203748D01*
X1723502D01*
Y203750D01*
X1724998D01*
Y203748D01*
X1727002D01*
Y203750D01*
X1728498D01*
Y203748D01*
X1730702D01*
X1732300Y202150D01*
Y198450D01*
X1731700Y197850D01*
X1731266D01*
X1731215Y197902D01*
X1729485D01*
X1729434Y197850D01*
G37*
G36*
G01X1717748Y205252D02*
X1717400Y205600D01*
Y210380D01*
X1720120Y213100D01*
X1730500D01*
X1731005Y212595D01*
X1730966Y212477D01*
G03X1730872Y211145I2518J-847D01*
G01X1730892Y211042D01*
X1730761Y210911D01*
X1730724Y210895D01*
G03X1730114Y208793I536J-1295D01*
G01X1730150Y208741D01*
Y208400D01*
X1730950Y207600D01*
Y205450D01*
X1730750Y205250D01*
X1730302D01*
Y205252D01*
X1728498D01*
Y205250D01*
X1727002D01*
Y205252D01*
X1724998D01*
Y205250D01*
X1723502D01*
Y205252D01*
X1721498D01*
Y205250D01*
X1720002D01*
Y205252D01*
X1717748D01*
G37*
G36*
G01X1727752Y190684D02*
Y192502D01*
X1727750D01*
Y194750D01*
X1729900Y196900D01*
X1730902D01*
X1730907Y196705D01*
G03X1731500Y195102I2656J71D01*
G01Y191650D01*
X1730534Y190684D01*
X1727752D01*
G37*
G36*
G01X1763250Y248400D02*
X1762500Y249150D01*
Y251284D01*
X1762502Y251285D01*
Y256215D01*
X1762500Y256216D01*
Y256500D01*
X1761550Y257450D01*
X1743200D01*
X1743050Y257600D01*
Y259750D01*
X1744110Y260810D01*
X1771190D01*
X1773000Y259000D01*
Y249500D01*
X1771900Y248400D01*
X1763250D01*
G37*
G36*
G01X1732000Y259000D02*
Y250000D01*
X1730500Y248500D01*
X1724290D01*
X1723737Y249053D01*
Y249701D01*
X1723760Y249744D01*
G03X1723737Y251362I-1509J788D01*
G01Y258364D01*
X1725373Y260000D01*
X1731000D01*
X1732000Y259000D01*
G37*
G36*
G01X1734500Y245500D02*
X1733500Y246500D01*
Y257650D01*
X1734800Y258950D01*
X1741000D01*
X1741550Y258400D01*
Y256500D01*
X1742100Y255950D01*
X1743298D01*
Y255898D01*
X1745302D01*
Y255950D01*
X1746498D01*
Y255898D01*
X1748502D01*
Y255950D01*
X1749698D01*
Y255898D01*
X1751702D01*
Y255950D01*
X1752898D01*
Y255898D01*
X1754902D01*
Y255950D01*
X1756218D01*
Y255932D01*
X1758222D01*
Y255950D01*
X1759418D01*
Y255932D01*
X1761369D01*
X1761500Y255800D01*
Y251700D01*
X1761400Y251600D01*
X1758075D01*
G03X1757925I-75J-1600D01*
G01X1746100D01*
X1745000Y250500D01*
Y246100D01*
X1744400Y245500D01*
X1734500D01*
G37*
G36*
G01X1771700Y521100D02*
X1770100Y522700D01*
X1756600D01*
X1755700Y523600D01*
Y535664D01*
G03Y537918I-2235J1127D01*
G01Y540000D01*
X1756900Y541200D01*
X1770500D01*
X1771400Y540300D01*
X1776400D01*
X1779000Y537700D01*
Y533400D01*
X1784400Y528000D01*
Y522718D01*
X1782782Y521100D01*
X1771700D01*
G37*
G36*
G01X1836797Y19594D02*
X1831794D01*
X1831738Y19650D01*
Y30378D01*
X1840880D01*
X1842722Y28536D01*
Y28002D01*
X1842696D01*
Y25998D01*
X1842722D01*
Y25840D01*
X1843195Y25367D01*
Y25360D01*
X1843341D01*
X1843998Y24702D01*
X1845482D01*
Y22670D01*
X1843834D01*
Y22557D01*
X1842407D01*
G03X1840171I-1118J-926D01*
G01X1839760D01*
X1836797Y19594D01*
G37*
G36*
G01X1826502Y15900D02*
Y16752D01*
X1824453D01*
G02X1823816Y16653I-355J184D01*
G01X1823583Y16886D01*
Y19383D01*
X1824300Y20100D01*
X1826600D01*
X1827686Y21186D01*
Y26814D01*
X1827500Y27000D01*
X1827317D01*
X1827287Y27164D01*
G03X1826400Y27902I-887J-164D01*
G01X1825000D01*
G03X1824902Y27896I6J-902D01*
G01X1824891Y27895D01*
X1824680D01*
Y30261D01*
X1824882Y30463D01*
X1830619D01*
X1830736Y30346D01*
Y22418D01*
G03X1830706Y20693I1335J-886D01*
G01X1830736Y20645D01*
Y20036D01*
X1829734Y19034D01*
Y16430D01*
X1829204Y15900D01*
X1826502D01*
G37*
G36*
G01X1785400Y80450D02*
X1785100Y80750D01*
Y84550D01*
X1786850Y86300D01*
Y93750D01*
X1787250Y94150D01*
X1789600D01*
X1789916Y93834D01*
Y80966D01*
X1789400Y80450D01*
X1787702D01*
Y80452D01*
X1785698D01*
Y80450D01*
X1785400D01*
G37*
G36*
G01X1792659Y65425D02*
X1795325D01*
X1797960Y68060D01*
X1800994D01*
Y68058D01*
X1805996D01*
Y68060D01*
X1807494D01*
Y68058D01*
X1812496D01*
Y68060D01*
X1813050D01*
X1814346Y66764D01*
Y58244D01*
X1814565Y58025D01*
X1814568D01*
X1815527Y57066D01*
X1820188D01*
X1821000Y56254D01*
Y53030D01*
X1820928D01*
Y51028D01*
X1819735Y49835D01*
Y44647D01*
X1820100Y44282D01*
Y41198D01*
X1819978Y41076D01*
X1818156D01*
G03X1816216I-970J-1147D01*
G01X1813812D01*
X1809794Y45094D01*
X1802887Y52000D01*
X1796700D01*
X1791150Y57550D01*
Y59918D01*
X1791214Y59983D01*
Y63981D01*
X1792659Y65425D01*
G37*
G36*
G01X1799352Y93156D02*
Y101025D01*
X1805961D01*
X1806555Y100431D01*
Y96218D01*
X1805996Y95660D01*
Y93156D01*
X1799352D01*
G37*
G36*
G01X1843122Y59300D02*
X1841264Y61158D01*
X1837592D01*
X1837436Y61314D01*
Y67920D01*
X1836064Y69292D01*
Y71626D01*
X1834262Y73428D01*
Y77962D01*
X1835100Y78800D01*
X1844970D01*
X1847900Y75870D01*
Y71900D01*
X1854388Y65412D01*
X1861588D01*
X1862500Y64500D01*
Y61500D01*
X1861800Y60800D01*
X1861270D01*
Y60804D01*
X1856268D01*
Y60368D01*
X1855200Y59300D01*
X1854602D01*
Y59302D01*
X1852598D01*
Y59300D01*
X1843122D01*
G37*
G36*
G01X1831998Y50802D02*
Y45998D01*
X1827651Y41651D01*
X1827523Y41711D01*
G03X1825598Y41042I-623J-1311D01*
G01X1825543Y40931D01*
X1824907D01*
X1824860Y40958D01*
G03X1823355Y40931I-730J-1255D01*
G01X1821880D01*
X1821638Y41173D01*
Y43356D01*
X1822990Y44709D01*
Y45890D01*
X1823000Y45900D01*
Y54057D01*
X1822977Y54080D01*
Y55675D01*
X1822002Y56650D01*
Y56669D01*
X1820603Y58068D01*
X1820584D01*
X1820452Y58200D01*
X1816300D01*
X1815400Y59100D01*
Y68160D01*
X1812460Y71100D01*
X1797700D01*
X1797300Y71500D01*
Y74500D01*
X1805922Y83122D01*
X1806316D01*
Y83516D01*
X1806998Y84198D01*
Y95245D01*
X1807885Y96132D01*
X1815941D01*
X1816566Y95508D01*
Y95456D01*
X1818723Y93298D01*
X1818774D01*
X1820073Y92000D01*
X1820248D01*
Y91998D01*
X1822202D01*
X1822800Y91400D01*
Y83100D01*
X1824400Y81500D01*
Y78200D01*
X1827671Y74929D01*
X1831375D01*
X1833260Y73044D01*
Y73013D01*
X1835062Y71211D01*
Y68877D01*
X1835904Y68036D01*
Y55004D01*
X1832000Y51100D01*
Y50802D01*
X1831998D01*
G37*
G36*
G01X1826100Y97556D02*
Y101600D01*
X1827700Y103200D01*
X1832300D01*
X1835700Y99800D01*
Y96700D01*
X1837100Y95300D01*
X1841500D01*
X1843400Y93400D01*
Y83700D01*
X1842600Y82900D01*
X1832700D01*
X1831300Y84300D01*
Y92356D01*
X1826100Y97556D01*
G37*
G36*
G01X1830446Y141349D02*
X1830099Y141696D01*
Y145779D01*
X1831483Y147163D01*
X1833301D01*
X1833979Y146486D01*
X1837982D01*
X1839841Y144627D01*
Y141753D01*
X1839437Y141349D01*
X1830446D01*
G37*
G36*
G01X1838110Y153080D02*
X1837320Y152290D01*
X1832620D01*
X1830050Y154860D01*
X1826540D01*
X1826080Y155320D01*
Y158210D01*
X1826340Y158470D01*
X1826588D01*
Y158378D01*
X1829592D01*
Y158470D01*
X1837780D01*
X1838110Y158140D01*
Y153080D01*
G37*
G36*
G01X1791410Y167120D02*
X1791900Y167610D01*
X1798410D01*
X1799380Y166640D01*
Y161690D01*
X1798840Y161150D01*
X1792080D01*
X1791410Y161820D01*
Y167120D01*
G37*
G36*
G01X1826355Y160285D02*
X1825310Y161330D01*
Y167240D01*
X1826450Y168380D01*
X1838000D01*
X1840181Y166199D01*
X1853556D01*
G03X1855812Y165604I1444J901D01*
G01X1855943Y165676D01*
X1856220Y165399D01*
Y161505D01*
X1855563Y160848D01*
X1847952D01*
X1846800Y162000D01*
X1839000D01*
X1837260Y160260D01*
X1835152D01*
Y160582D01*
X1832148D01*
Y160260D01*
X1829592D01*
Y160382D01*
X1826588D01*
X1826355Y160285D01*
G37*
G36*
G01X1802680Y170750D02*
X1813050D01*
X1814538Y169262D01*
X1814550Y169200D01*
G03X1814800Y168592I1575J292D01*
G01Y163850D01*
X1814794Y163826D01*
G03Y163048I1554J-389D01*
G01X1814800Y163024D01*
Y158600D01*
X1814700Y158500D01*
X1803000D01*
X1801210Y160290D01*
Y161938D01*
X1801402D01*
Y164942D01*
X1801210D01*
Y169280D01*
X1802680Y170750D01*
G37*
G36*
G01X1843298Y490183D02*
Y490166D01*
X1843134Y490003D01*
Y489635D01*
X1843000Y489500D01*
X1835400D01*
X1834802Y490099D01*
Y494801D01*
X1835500Y495500D01*
X1843500D01*
X1844498Y494501D01*
Y494498D01*
X1844500D01*
Y491386D01*
X1843298Y490183D01*
G37*
G36*
G01X1835150Y482950D02*
X1834800Y483300D01*
Y483698D01*
X1834802D01*
Y488202D01*
X1835098Y488498D01*
X1841502D01*
X1842000Y488000D01*
Y483600D01*
X1841350Y482950D01*
X1836449D01*
G03X1836343I-53J-1601D01*
G01X1835150D01*
G37*
G36*
G01X1831300Y509300D02*
X1823850D01*
X1823250Y509900D01*
Y515750D01*
X1824700Y517200D01*
X1831400D01*
X1831900Y516700D01*
Y509900D01*
X1831300Y509300D01*
G37*
G36*
G01X1831700Y506600D02*
Y483100D01*
X1829921Y481321D01*
X1829868Y481307D01*
G03X1829035Y480700I351J-1357D01*
G01X1825100D01*
X1824200Y481600D01*
Y483982D01*
X1824658Y485619D01*
G03X1824691Y485747I-2555J727D01*
G01X1824703Y485803D01*
X1825666Y486766D01*
X1825679Y486776D01*
G03X1826000Y490812I-1554J2154D01*
G01Y496498D01*
X1826252D01*
Y496998D01*
X1827252D01*
Y499002D01*
X1826252D01*
Y499502D01*
X1826000D01*
Y500700D01*
X1826750Y501450D01*
X1827900D01*
X1829200Y502750D01*
Y505900D01*
X1829900Y506600D01*
X1831700D01*
G37*
G36*
G01X1783641Y531659D02*
X1782750Y532550D01*
Y538350D01*
X1780237Y540863D01*
Y547300D01*
X1780437Y547500D01*
X1786900D01*
X1787500Y548100D01*
Y549900D01*
X1785900Y551500D01*
Y553000D01*
X1786800Y553900D01*
Y555400D01*
X1788000Y556600D01*
X1789498D01*
Y556598D01*
X1791502D01*
Y556600D01*
X1791900D01*
X1792400Y556100D01*
Y550173D01*
G03Y550027I1500J-73D01*
G01Y549400D01*
X1793600Y548200D01*
Y532345D01*
X1792914Y531659D01*
X1783641D01*
G37*
G36*
G01X1806200Y539400D02*
X1806600Y539800D01*
X1817700D01*
X1818000Y539500D01*
Y538300D01*
X1817700Y538000D01*
X1814500D01*
X1813800Y537300D01*
Y532600D01*
X1813500Y532300D01*
X1806500D01*
X1806200Y532600D01*
Y539400D01*
G37*
G36*
G01X1849384Y16579D02*
X1849153Y16580D01*
X1847536D01*
X1847136Y16980D01*
Y18800D01*
X1847130Y18806D01*
Y20252D01*
X1846484Y20898D01*
Y25359D01*
X1846139Y25704D01*
X1844413D01*
X1844262Y25855D01*
Y30632D01*
X1844716Y31086D01*
X1849430D01*
X1849436Y31080D01*
Y18982D01*
X1849384D01*
Y16579D01*
G37*
G36*
G01X1852822Y30826D02*
X1855618Y28030D01*
X1866286D01*
X1866623Y27693D01*
Y21137D01*
X1865966Y20480D01*
X1857236D01*
X1853236Y16480D01*
X1851236D01*
X1851036Y16680D01*
Y30441D01*
X1851350Y30755D01*
X1851971D01*
X1852042Y30826D01*
X1852822D01*
G37*
G36*
G01X1870702Y26500D02*
G03X1870847Y26433I1646J3372D01*
G01X1870882Y26418D01*
X1871600Y25700D01*
Y24264D01*
X1870836Y23500D01*
Y23282D01*
X1870834D01*
Y21478D01*
X1870836D01*
Y19982D01*
X1870834D01*
Y18278D01*
X1870536Y17980D01*
X1868136D01*
X1867936Y18180D01*
Y26136D01*
X1868300Y26500D01*
X1870702D01*
G37*
G36*
G01X1869404Y75404D02*
X1867731Y77078D01*
Y81244D01*
X1867539Y81436D01*
X1864060D01*
X1863560Y80936D01*
Y80616D01*
X1863581Y80595D01*
Y79538D01*
X1863538D01*
Y77548D01*
X1863463Y77473D01*
X1861476D01*
X1860824Y78124D01*
Y81476D01*
X1855000Y87300D01*
Y100009D01*
X1855630Y100639D01*
X1865919D01*
X1869254Y97304D01*
X1891699D01*
X1892422Y96582D01*
Y76342D01*
X1891484Y75404D01*
X1884927D01*
G02X1884564Y75971I0J400D01*
G03X1881836I-1364J629D01*
G02X1881473Y75404I-363J-167D01*
G01X1869404D01*
G37*
G36*
G01X1852152Y53500D02*
X1852151Y53502D01*
X1847098D01*
X1846500Y54100D01*
Y57200D01*
X1847100Y57800D01*
X1852598D01*
Y57798D01*
X1854602D01*
Y57800D01*
X1862200D01*
X1862500Y57500D01*
Y54500D01*
X1861500Y53500D01*
X1852152D01*
G37*
G36*
G01X1871482Y52798D02*
X1871956Y53272D01*
X1878052D01*
X1878389Y52935D01*
Y49733D01*
X1877877Y49221D01*
X1871955D01*
X1871482Y49694D01*
Y52798D01*
G37*
G36*
G01X1893970Y82000D02*
X1893574Y82396D01*
Y96677D01*
X1898968Y102070D01*
X1908490D01*
X1909610Y100950D01*
Y90810D01*
X1908463Y89663D01*
X1907012D01*
X1905776Y88427D01*
Y82172D01*
X1905605Y82000D01*
X1893970D01*
G37*
G36*
G01X1873732Y111568D02*
X1872770Y112530D01*
Y114444D01*
X1870292Y116922D01*
Y118982D01*
X1870289D01*
Y120478D01*
X1870292D01*
Y122482D01*
X1870289D01*
Y124611D01*
X1868800Y126100D01*
Y129700D01*
X1869098Y129998D01*
X1874002D01*
Y130002D01*
X1875800Y131800D01*
X1876498D01*
Y131748D01*
X1878502D01*
Y131800D01*
X1879998D01*
Y131748D01*
X1882002D01*
Y131800D01*
X1886101D01*
X1886748Y131152D01*
Y129498D01*
X1886800D01*
Y129200D01*
X1888288Y127712D01*
Y125212D01*
X1892255Y121245D01*
Y120002D01*
X1892248D01*
Y117998D01*
X1892255D01*
Y112655D01*
X1891100Y111500D01*
X1890792D01*
Y111582D01*
X1888788D01*
Y111500D01*
X1887292D01*
Y111582D01*
X1885288D01*
Y111500D01*
X1882292D01*
Y111582D01*
X1880288D01*
Y111500D01*
X1875940D01*
Y111568D01*
X1873732D01*
G37*
G36*
G01X1843052Y153048D02*
X1841900Y154200D01*
Y159750D01*
X1842098Y159948D01*
X1845102D01*
Y159950D01*
X1846750D01*
X1847300Y159400D01*
X1855550D01*
X1856600Y158350D01*
Y156843D01*
X1856578Y156801D01*
G03Y155445I1341J-678D01*
G01X1856600Y155403D01*
Y153550D01*
X1856098Y153048D01*
X1843052D01*
G37*
G36*
G01X1891380Y150510D02*
X1891060Y150830D01*
Y153080D01*
X1892160Y154180D01*
Y157489D01*
X1891779Y157870D01*
Y160539D01*
X1893199Y161959D01*
Y165007D01*
X1892212Y165994D01*
Y173498D01*
X1892252D01*
Y174952D01*
X1894398Y177098D01*
X1894402D01*
Y180102D01*
X1894400D01*
Y180400D01*
X1895100Y181100D01*
X1896600D01*
X1896798Y181298D01*
X1898502D01*
Y183002D01*
X1900900Y185400D01*
Y186498D01*
X1901252D01*
Y188252D01*
X1901550Y188550D01*
X1904798D01*
Y188548D01*
X1906802D01*
Y188550D01*
X1908998D01*
Y187498D01*
X1912002D01*
Y188550D01*
X1912950D01*
X1915000Y190600D01*
X1917500D01*
X1918204Y189896D01*
Y177499D01*
X1919454Y176249D01*
Y170479D01*
X1918818Y169843D01*
Y165321D01*
X1920123Y164016D01*
Y159733D01*
X1919201Y158811D01*
X1914158D01*
X1913835Y159134D01*
Y160055D01*
X1913559Y160331D01*
X1910734D01*
X1910473Y160070D01*
Y159333D01*
X1909583Y158443D01*
X1903750D01*
X1903500Y158693D01*
Y161700D01*
X1902250Y162950D01*
X1900450D01*
X1899200Y161700D01*
Y158400D01*
X1896900Y156100D01*
Y154050D01*
X1896450Y153600D01*
X1895350D01*
X1893400Y151650D01*
Y150975D01*
X1892935Y150510D01*
X1891380D01*
G37*
G36*
G01X1887570Y150980D02*
X1887510Y151040D01*
Y153040D01*
X1888010Y153540D01*
Y157240D01*
X1886750Y158500D01*
X1885240D01*
X1884570Y157830D01*
Y157625D01*
X1884541Y157577D01*
G03Y155823I1459J-877D01*
G01X1884570Y155775D01*
Y155270D01*
X1884700Y155140D01*
Y152700D01*
X1883800Y151800D01*
X1882850D01*
G02X1882520Y152427I-1J400D01*
G03X1879972Y153779I-1196J823D01*
G02X1879275Y153691I-372J146D01*
G03X1877550Y154189I-1179J-848D01*
G02X1877000Y154559I-150J371D01*
G01Y155914D01*
X1877006Y155939D01*
G03Y156661I-1406J361D01*
G01X1877000Y156686D01*
Y171000D01*
X1878500Y172500D01*
X1882477D01*
X1882778Y172198D01*
X1882802D01*
X1883600Y171400D01*
Y165700D01*
X1884800Y164500D01*
X1886570D01*
X1887196Y165126D01*
X1890904D01*
X1891148Y164882D01*
Y161998D01*
X1891150D01*
Y161667D01*
X1890250Y160767D01*
Y160102D01*
X1890248D01*
Y158062D01*
X1890640Y157670D01*
Y154270D01*
X1889550Y153180D01*
Y152902D01*
X1889548D01*
Y151119D01*
X1889410Y150980D01*
X1887570D01*
G37*
G36*
G01X1896000Y125242D02*
X1895979Y125201D01*
G03X1897473Y122748I1528J-751D01*
G01X1897553Y122747D01*
X1901300Y119000D01*
X1903377D01*
X1903378Y118998D01*
X1904302D01*
X1904892Y118408D01*
Y115008D01*
X1905108Y114792D01*
X1905123Y114755D01*
G03X1907066Y113982I1344J550D01*
G01X1907105Y114000D01*
X1907998D01*
Y113998D01*
X1912802D01*
X1913000Y113800D01*
Y109600D01*
X1912403Y109003D01*
X1904842D01*
Y110392D01*
X1899838D01*
Y109003D01*
X1896638D01*
Y109004D01*
X1893604D01*
X1893229Y109379D01*
Y112213D01*
X1893256Y112240D01*
Y112830D01*
X1893802Y113375D01*
Y121198D01*
X1889300Y125700D01*
Y128200D01*
X1888400Y129100D01*
Y134925D01*
X1888444Y134944D01*
Y139256D01*
X1887500Y140200D01*
X1886716D01*
X1886615Y140302D01*
X1884998D01*
X1884600Y140700D01*
Y141800D01*
X1885017Y142217D01*
X1892331D01*
X1893776Y140772D01*
G02X1893791Y140222I-283J-283D01*
G03X1894000Y138159I1043J-936D01*
G01Y137091D01*
G03Y135107I1060J-992D01*
G01Y128000D01*
X1896000Y126000D01*
Y125242D01*
G37*
G36*
G01X1875940Y110100D02*
X1877288D01*
X1878704Y108684D01*
Y104740D01*
X1877717Y103753D01*
Y102462D01*
X1877243Y101988D01*
X1867918D01*
X1866774Y103132D01*
Y108021D01*
X1867559Y108806D01*
X1867566Y108812D01*
G03X1867761Y109007I-960J1155D01*
G01X1867767Y109014D01*
X1867981Y109228D01*
X1870992D01*
Y109230D01*
X1871181D01*
X1872051Y110100D01*
X1873938D01*
Y110066D01*
X1875940D01*
Y110100D01*
G37*
G36*
G01X1889231Y102163D02*
G03X1886655Y102992I-1401J64D01*
G02X1886037Y102927I-335J218D01*
G01X1885107Y103857D01*
Y109907D01*
X1885278Y110078D01*
X1887292D01*
Y110100D01*
X1888788D01*
Y110078D01*
X1890922D01*
X1891177Y109823D01*
Y109337D01*
X1893518Y106996D01*
X1896289D01*
X1897331Y105954D01*
Y102074D01*
X1897028Y101771D01*
X1891671D01*
X1891645Y101745D01*
X1889630D01*
G02X1889231Y102163I0J400D01*
G37*
G36*
G01X1867990Y111238D02*
X1866006Y113222D01*
G02X1865990Y113771I283J283D01*
G03X1864765Y116180I-1086J964D01*
G02X1864327Y116578I-38J398D01*
G01Y124646D01*
X1865181Y125500D01*
X1867984D01*
X1868770Y124714D01*
Y116989D01*
X1871612Y114147D01*
Y111785D01*
X1871065Y111238D01*
X1867990D01*
G37*
G36*
G01X1865700Y131600D02*
X1865000Y132300D01*
Y138900D01*
X1866800Y140700D01*
X1868508D01*
G03X1870258I875J1800D01*
G01X1877400D01*
X1877498Y140798D01*
X1877902D01*
Y141202D01*
X1877998Y141298D01*
X1878802D01*
X1878898Y141202D01*
Y140798D01*
X1882902D01*
X1884400Y139300D01*
X1886200D01*
X1886438Y139063D01*
Y136216D01*
X1886500D01*
Y133500D01*
X1886200Y133200D01*
X1882002D01*
Y133252D01*
X1879998D01*
Y133200D01*
X1878502D01*
Y133252D01*
X1876498D01*
Y133200D01*
X1874200D01*
X1874002Y133002D01*
X1868998D01*
Y132800D01*
X1868800D01*
X1867600Y131600D01*
X1865700D01*
G37*
G36*
G01X1853330Y137390D02*
X1853300Y137420D01*
X1842660D01*
X1842066Y138014D01*
Y141946D01*
X1842114D01*
Y144900D01*
X1843076Y145861D01*
X1858169D01*
X1858630Y145400D01*
Y137950D01*
X1858070Y137390D01*
X1853330D01*
G37*
G36*
G01X1862500Y170500D02*
X1866000D01*
X1868800Y173300D01*
X1874800D01*
X1875400Y172700D01*
Y158300D01*
X1874800Y157700D01*
X1864800D01*
X1861700Y160800D01*
Y169700D01*
X1862500Y170500D01*
G37*
G36*
G01X1881850Y214250D02*
Y212250D01*
X1880400Y210800D01*
X1879417D01*
X1879415Y210802D01*
X1875832D01*
X1875830Y210800D01*
X1866300D01*
X1865784Y211316D01*
X1865814Y211428D01*
G03X1862685Y212700I-1644J441D01*
G01X1862288D01*
X1862240Y212728D01*
G03X1861461Y212933I-745J-1247D01*
G02X1861053Y213305I-9J400D01*
G03X1858154Y213123I-1449J-99D01*
G02X1857755Y212700I-399J-23D01*
G01X1856152D01*
X1856110Y212844D01*
G03X1853018Y213242I-1633J-479D01*
G02X1852393Y213165I-343J206D01*
G01X1852294Y213264D01*
X1852280Y213316D01*
G03X1850656Y214381I-1404J-370D01*
G01X1850641Y214379D01*
X1850286D01*
X1849500Y215165D01*
Y215498D01*
X1849502D01*
Y217502D01*
X1849500D01*
Y217953D01*
G02X1849824Y218110I200J0D01*
G03Y220390I899J1140D01*
G02X1849500Y220547I-124J157D01*
G01Y220998D01*
X1849502D01*
Y223002D01*
X1849500D01*
Y223998D01*
X1849502D01*
Y226002D01*
X1849500D01*
Y226998D01*
X1849502D01*
Y229002D01*
X1849500D01*
Y229998D01*
X1849502D01*
Y232002D01*
X1849500D01*
Y232998D01*
X1849502D01*
Y235002D01*
X1849500D01*
Y235998D01*
X1849502D01*
Y238002D01*
X1849500D01*
Y238998D01*
X1849502D01*
Y241002D01*
X1849500D01*
Y241998D01*
X1849502D01*
Y244002D01*
X1849500D01*
Y244998D01*
X1849502D01*
Y247002D01*
X1849500D01*
Y247800D01*
X1849750Y248050D01*
X1852400D01*
X1852700Y247750D01*
Y226403D01*
X1861053Y218050D01*
X1873150D01*
X1877900Y222800D01*
X1881252D01*
X1881292Y222782D01*
G03X1882508I608J1318D01*
G01X1882548Y222800D01*
X1883752D01*
X1883792Y222782D01*
G03X1885762Y224602I608J1318D01*
G01X1885750Y224636D01*
Y226199D01*
G03X1886299Y226745I-749J1302D01*
G01X1886312Y226768D01*
X1886521Y226977D01*
X1887962D01*
Y226886D01*
X1890299D01*
X1890550Y226634D01*
Y226429D01*
X1890504Y226373D01*
G03X1890298Y225800I696J-574D01*
G01Y224342D01*
X1889925Y223969D01*
X1888748D01*
X1888127Y223348D01*
Y220038D01*
X1888412Y219754D01*
Y218936D01*
X1888912D01*
Y217936D01*
X1890914D01*
Y218936D01*
X1891414D01*
Y219418D01*
X1892623D01*
X1894079Y217962D01*
X1897655D01*
X1897677Y217984D01*
X1897864D01*
X1898550Y217298D01*
Y212175D01*
X1897720Y211345D01*
X1896573D01*
X1896571Y211346D01*
X1894122D01*
X1892516Y212952D01*
X1888876D01*
X1888427Y213401D01*
Y215000D01*
X1887927Y215500D01*
X1883100D01*
X1881850Y214250D01*
G37*
G36*
G01X1898600Y434900D02*
X1897600Y435900D01*
Y444298D01*
X1897702D01*
Y446302D01*
X1897600D01*
Y449300D01*
X1897000Y449900D01*
Y450198D01*
X1897002D01*
Y452099D01*
X1896500Y452600D01*
X1896116D01*
X1894602Y454115D01*
Y455215D01*
X1894500Y455316D01*
Y456000D01*
X1893900Y456600D01*
X1890700D01*
X1889600Y457700D01*
Y467500D01*
X1890950Y468850D01*
X1893821D01*
X1893846Y468844D01*
G03X1894554I354J1356D01*
G01X1894579Y468850D01*
X1896421D01*
X1896446Y468844D01*
G03X1897154I354J1356D01*
G01X1897179Y468850D01*
X1898821D01*
X1898846Y468844D01*
G03X1899554I354J1356D01*
G01X1899579Y468850D01*
X1901421D01*
X1901446Y468844D01*
G03X1902154I354J1356D01*
G01X1902179Y468850D01*
X1907850D01*
X1908850Y467850D01*
Y462750D01*
X1910900Y460700D01*
Y452200D01*
X1909700Y451000D01*
X1907000D01*
X1906000Y450000D01*
X1905816D01*
X1905615Y450202D01*
X1904002D01*
Y452002D01*
X1903900D01*
Y452300D01*
X1903500Y452700D01*
Y455500D01*
X1902800Y456200D01*
X1900600D01*
X1899800Y455400D01*
Y449500D01*
X1900100Y449200D01*
X1902200D01*
X1902600Y448800D01*
Y447516D01*
X1901998Y446915D01*
Y443885D01*
X1902000Y443884D01*
Y443300D01*
X1902500Y442800D01*
X1902998D01*
Y442628D01*
X1904972D01*
X1905000Y442600D01*
Y435300D01*
X1904600Y434900D01*
X1898600D01*
G37*
G36*
G01X1885000Y437630D02*
X1884500Y438130D01*
Y448630D01*
X1881500Y451630D01*
Y454900D01*
X1882100Y455500D01*
X1892900D01*
X1893600Y454800D01*
Y453700D01*
X1895415Y451885D01*
Y449785D01*
X1896200Y449000D01*
Y446302D01*
X1896198D01*
Y444298D01*
X1896200D01*
Y439030D01*
X1894800Y437630D01*
X1885000D01*
G37*
G36*
G01X1837690Y498510D02*
X1836500Y499700D01*
Y506600D01*
X1842000Y512100D01*
X1848700D01*
X1850400Y510400D01*
Y498878D01*
X1850032Y498510D01*
X1843899D01*
G02X1843500Y498888I0J400D01*
G03X1840300I-1600J-88D01*
G02X1839901Y498510I-399J22D01*
G01X1837690D01*
G37*
G36*
G01X1940985Y602914D02*
X1937729Y606171D01*
X1937846Y606311D01*
G03X1936303Y608532I-1076J899D01*
G02X1935777Y608983I-133J377D01*
G03X1933554Y610464I-1427J267D01*
G01X1933436D01*
X1932752Y611148D01*
Y613052D01*
X1932464D01*
Y613102D01*
X1929852Y615714D01*
X1928185D01*
X1927400Y616500D01*
X1921100D01*
X1916700Y612100D01*
X1911900D01*
X1910550Y613450D01*
X1901924D01*
Y613664D01*
X1898020D01*
Y613450D01*
X1897650D01*
X1896850Y614250D01*
Y623050D01*
X1898300Y624500D01*
X1934600D01*
X1948400Y610700D01*
Y607609D01*
G02X1947659Y607401I-400J1D01*
G03X1942426Y603577I-2777J-1693D01*
G02X1942124Y602914I-302J-263D01*
G01X1940985D01*
G37*
G36*
G01X1899614Y107400D02*
X1899838D01*
Y107388D01*
X1904842D01*
Y107400D01*
X1908700D01*
X1909800Y106300D01*
Y104000D01*
X1908872Y103072D01*
X1899437D01*
X1899300Y103209D01*
Y106419D01*
G03X1899600Y107215I-1198J906D01*
G01X1899614Y107400D01*
G37*
G36*
G01X1903416Y122500D02*
X1903400Y122516D01*
Y135250D01*
X1913800D01*
Y122500D01*
X1903416D01*
G37*
G36*
G01X1940050Y102050D02*
X1939400Y101400D01*
X1932000D01*
X1931500Y101900D01*
Y109000D01*
X1932000Y109500D01*
X1934100D01*
X1936600Y107000D01*
X1938500D01*
X1938600Y106900D01*
X1938850D01*
X1939150Y106800D01*
X1939400Y106700D01*
X1940050Y106050D01*
Y102050D01*
G37*
G36*
G01X1947514Y136914D02*
X1942886D01*
X1941900Y137900D01*
X1939400D01*
X1938700Y137200D01*
X1936200D01*
X1935600Y137800D01*
Y139300D01*
X1936600Y140300D01*
X1947734D01*
Y139208D01*
X1948200Y138742D01*
Y137600D01*
X1947514Y136914D01*
G37*
G36*
G01X1924861Y218575D02*
X1928940Y214496D01*
X1929400Y213115D01*
Y211400D01*
X1929200Y211200D01*
X1925787D01*
X1924287Y212700D01*
X1919988D01*
X1919952Y212855D01*
G03X1917026I-1463J-342D01*
G01X1916990Y212700D01*
X1913446D01*
X1911520Y214626D01*
Y217230D01*
X1911521Y217238D01*
G03Y217460I-1398J111D01*
G01X1911520Y217468D01*
Y218234D01*
X1911861Y218575D01*
X1917346D01*
G03X1918940I797J1273D01*
G01X1924861D01*
G37*
G36*
G01X1906117Y199324D02*
X1905139Y200302D01*
Y200686D01*
X1905167Y200733D01*
G03X1905139Y202256I-1250J739D01*
G01Y203944D01*
G03Y205846I-1097J951D01*
G01Y215408D01*
X1905419Y215688D01*
X1908756D01*
X1912758Y211686D01*
X1917058D01*
X1917435Y211310D01*
Y206262D01*
X1912798Y201626D01*
X1911856D01*
X1909554Y199324D01*
X1906117D01*
G37*
G36*
G01X1965600Y219500D02*
X1965300Y219800D01*
Y224000D01*
X1963382Y225918D01*
X1957661D01*
X1951379Y232200D01*
X1950610D01*
X1950590Y232204D01*
G03X1949410I-590J-2943D01*
G01X1949390Y232200D01*
X1944600D01*
X1942250Y229850D01*
Y227450D01*
X1941500Y226700D01*
X1937600D01*
X1937000Y227300D01*
Y231486D01*
X1937022D01*
Y232122D01*
X1941336Y236436D01*
X1947956D01*
G03X1952044I2044J2719D01*
G01X1953628D01*
X1956513Y233551D01*
X1968081D01*
X1971606Y230026D01*
Y223994D01*
X1971600Y223988D01*
Y219700D01*
X1971400Y219500D01*
X1965600D01*
G37*
G36*
G01X1912999Y221418D02*
X1912236Y222181D01*
X1910527D01*
X1910515Y222182D01*
G03X1910165I-175J-1441D01*
G01X1910153Y222181D01*
X1909509D01*
X1908936Y222754D01*
Y226952D01*
X1915056D01*
X1916454D01*
X1923056D01*
X1923983D01*
X1925079Y225856D01*
Y221756D01*
X1924741Y221418D01*
X1912999D01*
G37*
G36*
G01X1906700Y434700D02*
X1906100Y435300D01*
Y443000D01*
X1906800Y443700D01*
Y448700D01*
X1907500Y449400D01*
X1911400D01*
X1912100Y448700D01*
Y446802D01*
X1911498D01*
Y444798D01*
X1912100D01*
Y443232D01*
X1909998D01*
Y438228D01*
X1912100D01*
Y435200D01*
X1911600Y434700D01*
X1906700D01*
G37*
G36*
G01X1926500Y434600D02*
X1926000Y435100D01*
Y438228D01*
X1926002D01*
Y443232D01*
X1926000D01*
Y443700D01*
X1925501Y444199D01*
Y444798D01*
X1925502D01*
Y446802D01*
X1925501D01*
Y449401D01*
X1925700Y449600D01*
X1927082D01*
G03X1929075Y447798I3238J1578D01*
G01X1929117Y447783D01*
X1929400Y447500D01*
X1932900D01*
X1934500Y445900D01*
Y435100D01*
X1934000Y434600D01*
X1926500D01*
G37*
G36*
G01X1914000D02*
X1913102Y435499D01*
Y449115D01*
X1913035Y449181D01*
Y456435D01*
X1919100Y462500D01*
Y468500D01*
X1920076Y469476D01*
X1932125D01*
X1933500Y468100D01*
Y459603D01*
X1924000Y450103D01*
Y446802D01*
X1923998D01*
Y444798D01*
X1924000D01*
Y444391D01*
X1923000Y443391D01*
Y443232D01*
X1922998D01*
Y438228D01*
X1923000D01*
Y435200D01*
X1922400Y434600D01*
X1914000D01*
G37*
G36*
G01X1905032Y444132D02*
X1903168D01*
X1903000Y444300D01*
Y446500D01*
X1903700Y447200D01*
Y448800D01*
X1904100Y449200D01*
X1905200D01*
X1905798Y448601D01*
Y444899D01*
X1905032Y444132D01*
G37*
G36*
G01X1915576Y473364D02*
Y472757D01*
X1918170Y470162D01*
Y468986D01*
X1918098Y468915D01*
Y465635D01*
X1917803Y465340D01*
X1910294D01*
X1909852Y465782D01*
Y468265D01*
X1908265Y469852D01*
X1908254D01*
X1907130Y470975D01*
Y478340D01*
X1907611Y478821D01*
X1907858Y478718D01*
Y478660D01*
X1909860D01*
Y478930D01*
X1913830D01*
X1914330Y478430D01*
Y474610D01*
X1915576Y473364D01*
G37*
G36*
G01X1965241Y183172D02*
X1964676Y183736D01*
X1960252D01*
G03X1959961Y183709I-2J-1564D01*
G02X1959487Y184102I-74J393D01*
G01Y184192D01*
G02X1959962Y184585I400J0D01*
G03X1960252Y184558I288J1524D01*
G01X1965152D01*
X1965866Y185272D01*
X1966508D01*
X1966747Y185033D01*
Y183446D01*
X1966473Y183172D01*
X1965241D01*
G37*
%LPC*%
G75*
G36*
G01X746700Y-37400D02*
X783207D01*
Y-57100D01*
X746700D01*
Y-57200D01*
X562100D01*
Y-37300D01*
X746700D01*
Y-37400D01*
G37*
G36*
G01X397000Y-39100D02*
X450380D01*
Y-57500D01*
X394400D01*
Y-57530D01*
X136000D01*
Y-37300D01*
X145500D01*
Y-39050D01*
X397000D01*
Y-39100D01*
G37*
G36*
G01X893900Y-37100D02*
X1115285D01*
Y-57100D01*
X893900D01*
Y-37100D01*
G37*
G36*
G01X1670408Y-57200D02*
X1448243D01*
Y-37300D01*
X1670408D01*
Y-57200D01*
G37*
G36*
G01X213300Y659600D02*
Y639900D01*
X51200D01*
Y659600D01*
X213300D01*
G37*
G36*
G01X903000D02*
Y639900D01*
X615600D01*
Y659600D01*
X903000D01*
G37*
G36*
G01X58748Y517276D02*
G02X57124I-812J-1264D01*
G03Y517948I-216J336D01*
G02X56933Y518094I814J1263D01*
G03X56420Y518113I-268J-297D01*
G02X54397Y518281I-920J1187D01*
G03X54103I-147J-136D01*
G02X54037Y518214I-1102J1020D01*
G03X54036Y517925I138J-145D01*
G02X51848Y517819I-1044J-1079D01*
G03X51849Y518335I-305J259D01*
G02X51868Y520287I1151J965D01*
G03Y520813I-302J263D01*
G02Y522787I1132J987D01*
G03Y523313I-302J263D01*
G02X51736Y523488I1130J990D01*
G03X51064I-336J-216D01*
G02Y525112I-1264J812D01*
G03X51736I336J216D01*
G02X53987Y525432I1264J-812D01*
G03X54513I263J302D01*
G02X56487I987J-1132D01*
G03X57013I263J302D01*
G02X58096Y525799I987J-1132D01*
G03X58517Y526262I26J399D01*
G02X59904Y525001I1483J238D01*
G03X59483Y524538I-26J-399D01*
G02X59132Y523313I-1483J-238D01*
G03Y522787I302J-263D01*
G02X59158Y522757I-1122J-999D01*
G03X59475Y522769I154J128D01*
G02X59673Y520804I1225J-869D01*
G03X59105Y520783I-274J-292D01*
G02X59075Y520751I-1111J1011D01*
G03X59061Y520207I286J-280D01*
G02X58748Y517948I-1125J-995D01*
G03Y517276I216J-336D01*
G37*
G36*
G01X63208Y-523D02*
G03X63322Y-1099I323J-235D01*
G02X61322Y-1494I-786J-1280D01*
G03X61208Y-918I-323J235D01*
G02X63208Y-523I786J1280D01*
G37*
G36*
G01X64990Y-12127D02*
G03X65490Y-12300I348J197D01*
G02X64754Y-14428I571J-1389D01*
G03X64254Y-14255I-348J-197D01*
G02X64990Y-12127I-571J1389D01*
G37*
G36*
G01X115086Y5054D02*
G03X115064Y4488I271J-294D01*
G02X113014Y4566I-1064J-988D01*
G03X113036Y5132I-271J294D01*
G02X115086Y5054I1064J988D01*
G37*
G36*
G01X110358Y92023D02*
G02X110135Y93819I-1301J750D01*
G03X110765Y93891I287J279D01*
G02X110985Y92107I1242J-752D01*
G03X110358Y92023I-281J-284D01*
G37*
G36*
G01X91217Y294524D02*
X91372Y294369D01*
Y291893D01*
X90997Y291518D01*
X85283D01*
X83191Y293610D01*
Y294947D01*
X84091Y295847D01*
X85563D01*
X86886Y294524D01*
X91217D01*
G37*
G36*
G01X71150Y308979D02*
Y305200D01*
X70100Y304150D01*
X68600D01*
X67400Y305350D01*
Y311300D01*
X68450Y312350D01*
X70250D01*
X70718Y311882D01*
G03X71305Y311905I283J283D01*
G02X74062Y311672I1295J-1105D01*
G03X74662Y311570I343J205D01*
G02X75453Y311910I964J-1152D01*
G03X75805Y312344I-46J397D01*
G02X77523Y310798I1695J156D01*
G03X77128Y310402I5J-400D01*
G02X74406Y309542I-1502J16D01*
G03X73799Y309592I-325J-233D01*
G02X71750Y309326I-1199J1208D01*
G03X71150Y308979I-200J-347D01*
G37*
G36*
G01X108874Y392919D02*
G03X108274I-300J-265D01*
G02Y394777I-1050J929D01*
G03X108874I300J265D01*
G02Y392919I1050J-929D01*
G37*
G36*
G01X113766Y367078D02*
G02X112134Y367622I-1166J-778D01*
G03X112334Y368222I-133J378D01*
G02X113966Y367678I1166J778D01*
G03X113766Y367078I133J-378D01*
G37*
G36*
G01X199402Y331215D02*
X198015Y329828D01*
X191085D01*
X189698Y331215D01*
Y337045D01*
X191085Y338432D01*
X193098D01*
Y339482D01*
X196102D01*
Y338432D01*
X198115D01*
X199402Y337145D01*
Y331215D01*
G37*
G36*
G01Y298485D02*
X198015Y297098D01*
X191085D01*
X189698Y298485D01*
Y304315D01*
X191085Y305702D01*
X193098D01*
Y306752D01*
X196102D01*
Y305702D01*
X198115D01*
X199402Y304415D01*
Y298485D01*
G37*
G36*
G01Y269485D02*
X198015Y268098D01*
X191085D01*
X189698Y269485D01*
Y275315D01*
X191085Y276702D01*
X193098D01*
Y277752D01*
X196102D01*
Y276702D01*
X198115D01*
X199402Y275415D01*
Y269485D01*
G37*
G36*
G01X196102Y235598D02*
Y234596D01*
X193098D01*
Y235598D01*
X190917D01*
X189430Y237085D01*
Y244115D01*
X190917Y245602D01*
X193098D01*
Y246600D01*
X196102D01*
Y245602D01*
X198115D01*
X199702Y244015D01*
Y236985D01*
X198315Y235598D01*
X196102D01*
G37*
G36*
G01X199802Y377585D02*
X198415Y376198D01*
X191485D01*
X190098Y377585D01*
Y383415D01*
X191485Y384802D01*
X194198D01*
Y385302D01*
X196202D01*
Y384802D01*
X198515D01*
X199802Y383515D01*
Y377585D01*
G37*
G36*
G01X339894Y11698D02*
Y11198D01*
X335390D01*
Y11798D01*
X334327D01*
G02Y14602I-35J1402D01*
G01X335390D01*
Y15202D01*
X339894D01*
Y14702D01*
X341394D01*
Y11698D01*
X339894D01*
G37*
G36*
G01X326894D02*
Y11198D01*
X322390D01*
Y11898D01*
X321714D01*
X321681Y11886D01*
G02Y14514I-489J1314D01*
G01X321714Y14502D01*
X322390D01*
Y15202D01*
X326894D01*
Y14702D01*
X328394D01*
Y11698D01*
X326894D01*
G37*
G36*
G01X339894Y49498D02*
Y48998D01*
X335390D01*
Y49698D01*
X334814D01*
X334781Y49686D01*
G02Y52314I-489J1314D01*
G01X334814Y52302D01*
X335390D01*
Y53002D01*
X339894D01*
Y52502D01*
X341394D01*
Y49498D01*
X339894D01*
G37*
G36*
G01X326894D02*
Y48998D01*
X322390D01*
Y49698D01*
X321714D01*
X321681Y49686D01*
G02Y52314I-489J1314D01*
G01X321714Y52302D01*
X322390D01*
Y53002D01*
X326894D01*
Y52502D01*
X328394D01*
Y49498D01*
X326894D01*
G37*
G36*
G01X339894Y550498D02*
Y549998D01*
X335390D01*
Y550698D01*
X334814D01*
X334781Y550686D01*
G02Y553314I-489J1314D01*
G01X334814Y553302D01*
X335390D01*
Y554002D01*
X339894D01*
Y553502D01*
X341394D01*
Y550498D01*
X339894D01*
G37*
G36*
G01X326894D02*
Y549998D01*
X322390D01*
Y550698D01*
X321645D01*
X321612Y550686D01*
G02Y553314I-489J1314D01*
G01X321645Y553302D01*
X322390D01*
Y554002D01*
X326894D01*
Y553502D01*
X328394D01*
Y550498D01*
X326894D01*
G37*
G36*
G01X339894Y588298D02*
Y587798D01*
X335390D01*
Y588498D01*
X334814D01*
X334781Y588486D01*
G02Y591114I-489J1314D01*
G01X334814Y591102D01*
X335390D01*
Y591802D01*
X339894D01*
Y591302D01*
X341394D01*
Y588298D01*
X339894D01*
G37*
G36*
G01X326894D02*
Y587798D01*
X322390D01*
Y588498D01*
X321714D01*
X321681Y588486D01*
G02Y591114I-489J1314D01*
G01X321714Y591102D01*
X322390D01*
Y591802D01*
X326894D01*
Y591302D01*
X328394D01*
Y588298D01*
X326894D01*
G37*
G36*
G01X432402Y11698D02*
Y11198D01*
X427898D01*
Y11698D01*
X426398D01*
Y14702D01*
X427898D01*
Y15202D01*
X432402D01*
Y14702D01*
X433508D01*
G02Y11698I0J-1502D01*
G01X432402D01*
G37*
G36*
G01X419402D02*
Y11198D01*
X414898D01*
Y11698D01*
X413398D01*
Y14702D01*
X414898D01*
Y15202D01*
X419402D01*
Y14702D01*
X421368D01*
G02Y11698I0J-1502D01*
G01X419402D01*
G37*
G36*
G01X406952D02*
Y11198D01*
X402448D01*
Y11698D01*
X400948D01*
Y14702D01*
X402448D01*
Y15202D01*
X406952D01*
Y14702D01*
X408184D01*
G02Y11698I0J-1502D01*
G01X406952D01*
G37*
G36*
G01X432402Y550698D02*
Y549998D01*
X427898D01*
Y550498D01*
X426398D01*
Y553502D01*
X427898D01*
Y554002D01*
X432402D01*
Y553302D01*
X432986D01*
X433019Y553314D01*
G02Y550686I489J-1314D01*
G01X432986Y550698D01*
X432402D01*
G37*
G36*
G01Y588498D02*
Y587798D01*
X427898D01*
Y588298D01*
X426398D01*
Y591302D01*
X427898D01*
Y591802D01*
X432402D01*
Y591102D01*
X432978D01*
X433011Y591114D01*
G02Y588486I489J-1314D01*
G01X432978Y588498D01*
X432402D01*
G37*
G36*
G01Y49698D02*
Y48998D01*
X427898D01*
Y49498D01*
X426398D01*
Y52502D01*
X427898D01*
Y53002D01*
X432402D01*
Y52302D01*
X432986D01*
X433019Y52314D01*
G02Y49686I489J-1314D01*
G01X432986Y49698D01*
X432402D01*
G37*
G36*
G01X618752Y68476D02*
Y67998D01*
X614248D01*
Y68498D01*
X612748D01*
Y71502D01*
X614248D01*
Y72002D01*
X618752D01*
Y71080D01*
X619670D01*
X619703Y71092D01*
G02Y68464I489J-1314D01*
G01X619670Y68476D01*
X618752D01*
G37*
G36*
G01Y30676D02*
Y29998D01*
X614248D01*
Y30498D01*
X612748D01*
Y33502D01*
X614248D01*
Y34002D01*
X618752D01*
Y33280D01*
X619670D01*
X619703Y33292D01*
G02Y30664I489J-1314D01*
G01X619670Y30676D01*
X618752D01*
G37*
G36*
G01X617219Y-8702D02*
G03X616859Y-9274I1J-400D01*
G02X614230Y-9294I-1310J-627D01*
G01X614248Y-9254D01*
Y-8202D01*
X612748D01*
Y-5198D01*
X614248D01*
Y-4698D01*
X616661D01*
X616839Y-4520D01*
X619670D01*
X619703Y-4508D01*
G02Y-7136I489J-1314D01*
G01X619670Y-7124D01*
X618752D01*
Y-8702D01*
X617219D01*
G37*
G36*
G01X606533Y74888D02*
G02X604487I-1023J-1031D01*
G03X604205Y75572I-282J284D01*
G01X604008D01*
Y83674D01*
X604296D01*
Y83959D01*
X604267Y84007D01*
G02X606753I1243J750D01*
G01X606724Y83959D01*
Y83674D01*
X607012D01*
Y75572D01*
X606815D01*
G03X606533Y74888I0J-400D01*
G37*
G36*
G01X616764Y55597D02*
X616792Y55549D01*
G02X614306I-1243J-750D01*
G01X614334Y55597D01*
Y55882D01*
X614048D01*
Y63984D01*
X614244D01*
G03X614526Y64668I0J400D01*
G02X616572I1023J1031D01*
G03X616854Y63984I282J-284D01*
G01X617050D01*
Y55882D01*
X616764D01*
Y55597D01*
G37*
G36*
G01X606724D02*
X606753Y55549D01*
G02X604267I-1243J-750D01*
G01X604296Y55597D01*
Y55882D01*
X604008D01*
Y63984D01*
X604205D01*
G03X604487Y64668I0J400D01*
G02X606533I1023J1031D01*
G03X606815Y63984I282J-284D01*
G01X607012D01*
Y55882D01*
X606724D01*
Y55597D01*
G37*
G36*
G01X606533Y37088D02*
G02X604487I-1023J-1031D01*
G03X604205Y37772I-282J284D01*
G01X604008D01*
Y45874D01*
X604296D01*
Y46159D01*
X604267Y46207D01*
G02X606753I1243J750D01*
G01X606724Y46159D01*
Y45874D01*
X607012D01*
Y37772D01*
X606815D01*
G03X606533Y37088I0J-400D01*
G37*
G36*
G01X616764Y17797D02*
X616792Y17749D01*
G02X614306I-1243J-750D01*
G01X614334Y17797D01*
Y18082D01*
X614048D01*
Y26184D01*
X614244D01*
G03X614526Y26868I0J400D01*
G02X616572I1023J1031D01*
G03X616854Y26184I282J-284D01*
G01X617050D01*
Y18082D01*
X616764D01*
Y17797D01*
G37*
G36*
G01X606724D02*
X606753Y17749D01*
G02X604267I-1243J-750D01*
G01X604296Y17797D01*
Y18081D01*
X603464D01*
Y17521D01*
X603477Y17488D01*
G02X600849I-1314J-489D01*
G01X600862Y17521D01*
Y18081D01*
X600661D01*
Y26185D01*
X604205D01*
G03X604487Y26869I0J400D01*
G02X606533I1023J1030D01*
G03X606815Y26185I282J-284D01*
G01X607012D01*
Y18081D01*
X606724D01*
Y17797D01*
G37*
G36*
G01X606533Y-712D02*
G02X604487I-1023J-1031D01*
G03X604205Y-28I-282J284D01*
G01X604008D01*
Y8074D01*
X604296D01*
Y8359D01*
X604267Y8407D01*
G02X606753I1243J750D01*
G01X606724Y8359D01*
Y8074D01*
X607012D01*
Y-28D01*
X606815D01*
G03X606533Y-712I0J-400D01*
G37*
G36*
G01X624396Y-2602D02*
G02X622991Y-1548I-1396J-398D01*
G03X623374Y-1038I-2J400D01*
G02X624779Y-2092I1396J398D01*
G03X624396Y-2602I2J-400D01*
G37*
G36*
G01X618244Y608076D02*
Y607376D01*
X613740D01*
Y607876D01*
X612240D01*
Y610880D01*
X613740D01*
Y611380D01*
X618244D01*
Y610680D01*
X620072D01*
X620584Y610168D01*
X620617Y610153D01*
G02X618883Y608076I-584J-1275D01*
G01X618244D01*
G37*
G36*
G01X619144Y571189D02*
Y568776D01*
X614640D01*
Y569276D01*
X613140D01*
Y572280D01*
X614640D01*
Y572780D01*
X616990D01*
Y573778D01*
X616978Y573811D01*
G02X619606I1314J489D01*
G01X619594Y573778D01*
Y571639D01*
X619144Y571189D01*
G37*
G36*
G01Y531676D02*
Y530976D01*
X614640D01*
Y531476D01*
X613140D01*
Y534480D01*
X614640D01*
Y534980D01*
X619144D01*
Y534280D01*
X619670D01*
X619703Y534292D01*
G02Y531664I489J-1314D01*
G01X619670Y531676D01*
X619144D01*
G37*
G36*
G01X607012Y509076D02*
Y500972D01*
X604008D01*
Y509076D01*
X604296D01*
Y509359D01*
X604267Y509407D01*
G02X606753I1243J750D01*
G01X606724Y509359D01*
Y509076D01*
X607012D01*
G37*
G36*
G01X629045Y611414D02*
G02X628146Y613356I-1340J559D01*
G03X628637Y613583I122J381D01*
G02X630086Y614472I1340J-559D01*
G03X630467Y615063I30J399D01*
G02X631632Y614311I1274J696D01*
G03X631251Y613720I-30J-399D01*
G02X629536Y611641I-1274J-696D01*
G03X629045Y611414I-122J-381D01*
G37*
G36*
G01X616613Y592611D02*
G02X614306Y594349I-1064J988D01*
G01X614334Y594397D01*
Y594682D01*
X614048D01*
Y602786D01*
X614243D01*
G03X614525Y603469I0J400D01*
G02X616573I1024J1030D01*
G03X616855Y602786I282J-283D01*
G01X617050D01*
Y595242D01*
G03X617615Y594878I400J0D01*
G02X617191Y592618I577J-1278D01*
G03X616613Y592611I-286J-280D01*
G37*
G36*
G01X606724Y594397D02*
X606753Y594349D01*
G02X604267I-1243J-750D01*
G01X604296Y594397D01*
Y594682D01*
X603464D01*
Y594121D01*
X603477Y594088D01*
G02X600849I-1314J-489D01*
G01X600862Y594121D01*
Y594682D01*
X600661D01*
Y602786D01*
X600929D01*
G03X601203Y603477I0J400D01*
G02X603123I960J1022D01*
G03X603397Y602786I274J-291D01*
G01X604204D01*
G03X604486Y603470I0J400D01*
G02X606534I1024J1029D01*
G03X606816Y602786I282J-284D01*
G01X607012D01*
Y594682D01*
X606724D01*
Y594397D01*
G37*
G36*
G01X606532Y575888D02*
G02X604488I-1022J-1031D01*
G03X604206Y576572I-281J284D01*
G01X604008D01*
Y584676D01*
X604296D01*
Y584959D01*
X604267Y585007D01*
G02X606753I1243J750D01*
G01X606724Y584959D01*
Y584676D01*
X607012D01*
Y576572D01*
X606814D01*
G03X606532Y575888I-1J-400D01*
G37*
G36*
G01X616764Y556597D02*
X616792Y556549D01*
G02X614306I-1243J-750D01*
G01X614334Y556597D01*
Y556882D01*
X614048D01*
Y564986D01*
X614243D01*
G03X614525Y565669I0J400D01*
G02X616573I1024J1030D01*
G03X616855Y564986I282J-283D01*
G01X617050D01*
Y556882D01*
X616764D01*
Y556597D01*
G37*
G36*
G01X606724D02*
X606753Y556549D01*
G02X604267I-1243J-750D01*
G01X604296Y556597D01*
Y556882D01*
X604008D01*
Y564986D01*
X604204D01*
G03X604486Y565669I0J400D01*
G02X606534I1024J1030D01*
G03X606816Y564986I282J-283D01*
G01X607012D01*
Y556882D01*
X606724D01*
Y556597D01*
G37*
G36*
G01X606532Y538088D02*
G02X604488I-1022J-1031D01*
G03X604206Y538772I-281J284D01*
G01X604008D01*
Y546876D01*
X604296D01*
Y547159D01*
X604267Y547207D01*
G02X606753I1243J750D01*
G01X606724Y547159D01*
Y546876D01*
X607012D01*
Y538772D01*
X606814D01*
G03X606532Y538088I-1J-400D01*
G37*
G36*
G01X616764Y518797D02*
X616792Y518749D01*
G02X614306I-1243J-750D01*
G01X614334Y518797D01*
Y519082D01*
X614048D01*
Y527186D01*
X614243D01*
G03X614525Y527869I0J400D01*
G02X616573I1024J1030D01*
G03X616855Y527186I282J-283D01*
G01X617050D01*
Y519082D01*
X616764D01*
Y518797D01*
G37*
G36*
G01X606724D02*
X606753Y518749D01*
G02X604267I-1243J-750D01*
G01X604296Y518797D01*
Y519082D01*
X603464D01*
Y518521D01*
X603477Y518488D01*
G02X600849I-1314J-489D01*
G01X600862Y518521D01*
Y519082D01*
X600661D01*
Y527186D01*
X600929D01*
G03X601203Y527877I0J400D01*
G02X603123I960J1022D01*
G03X603397Y527186I274J-291D01*
G01X604204D01*
G03X604486Y527870I0J400D01*
G02X606534I1024J1029D01*
G03X606816Y527186I282J-284D01*
G01X607012D01*
Y519082D01*
X606724D01*
Y518797D01*
G37*
G36*
G01X688623Y289618D02*
X688757Y289646D01*
X688782Y289671D01*
Y290410D01*
X687782D01*
Y292414D01*
X688782D01*
Y292914D01*
X691786D01*
Y289910D01*
X691498D01*
Y288954D01*
X690398Y287854D01*
X690385Y287799D01*
G02X688623Y289618I-1461J348D01*
G37*
G36*
G01X683500Y306500D02*
X682200Y305200D01*
X680416D01*
X680415Y305198D01*
X653485D01*
X653484Y305200D01*
X653000D01*
X650500Y307700D01*
Y315498D01*
X650498D01*
Y317502D01*
X650500D01*
Y319498D01*
X650498D01*
Y321502D01*
X650500D01*
Y332498D01*
X650498D01*
Y334502D01*
X650502D01*
X651800Y335800D01*
X651884D01*
X651885Y335802D01*
X662215D01*
X662216Y335800D01*
X662700D01*
X663400Y335100D01*
X677100D01*
X678000Y336000D01*
X681500D01*
X683498Y334002D01*
X683502D01*
Y331998D01*
X683500D01*
Y322502D01*
X683502D01*
Y320498D01*
X683500D01*
Y318502D01*
X683502D01*
Y316498D01*
X683500D01*
Y306500D01*
G37*
G36*
G01X653147Y283694D02*
G02X653091Y285381I-1147J806D01*
G03X653738Y285415I311J251D01*
G02X653795Y283703I1262J-815D01*
G03X653147Y283694I-321J-239D01*
G37*
G36*
G01X939777Y-8339D02*
G03X939764Y-8901I278J-288D01*
G02X937716Y-8911I-1019J-963D01*
G03X937698Y-8350I-293J271D01*
G02X937639Y-6230I1034J1090D01*
G03Y-5681I-291J274D01*
G02X937702Y-3557I1093J1031D01*
G03X937723Y-2996I-274J291D01*
G02X939773Y-3017I1035J946D01*
G03X939783Y-3578I290J-275D01*
G02X939825Y-5681I-1051J-1073D01*
G03Y-6230I291J-274D01*
G02X939777Y-8339I-1093J-1030D01*
G37*
G36*
G01X902966D02*
G03X902953Y-8901I278J-288D01*
G02X900905Y-8911I-1019J-963D01*
G03X900887Y-8350I-293J271D01*
G02X900828Y-6230I1034J1090D01*
G03Y-5681I-291J274D01*
G02X900891Y-3557I1093J1031D01*
G03X900912Y-2996I-274J291D01*
G02X902962Y-3017I1035J946D01*
G03X902972Y-3578I290J-275D01*
G02X903014Y-5681I-1051J-1073D01*
G03Y-6230I291J-274D01*
G02X902966Y-8339I-1093J-1030D01*
G37*
G36*
G01X866155D02*
G03X866142Y-8901I278J-288D01*
G02X864094Y-8911I-1019J-963D01*
G03X864076Y-8350I-293J271D01*
G02X864017Y-6230I1034J1090D01*
G03Y-5681I-291J274D01*
G02X864080Y-3557I1093J1031D01*
G03X864101Y-2996I-274J291D01*
G02X866151Y-3017I1035J946D01*
G03X866161Y-3578I290J-275D01*
G02X866203Y-5681I-1051J-1073D01*
G03Y-6230I291J-274D01*
G02X866155Y-8339I-1093J-1030D01*
G37*
G36*
G01X829344D02*
G03X829331Y-8901I278J-288D01*
G02X827283Y-8911I-1019J-963D01*
G03X827265Y-8350I-293J271D01*
G02X827206Y-6230I1034J1090D01*
G03Y-5681I-291J274D01*
G02X827269Y-3557I1093J1031D01*
G03X827290Y-2996I-274J291D01*
G02X829340Y-3017I1035J946D01*
G03X829350Y-3578I290J-275D01*
G02X829392Y-5681I-1051J-1073D01*
G03Y-6230I291J-274D01*
G02X829344Y-8339I-1093J-1030D01*
G37*
G36*
G01X792533D02*
G03X792520Y-8901I278J-288D01*
G02X790472Y-8911I-1019J-963D01*
G03X790454Y-8350I-293J271D01*
G02X790395Y-6230I1034J1090D01*
G03Y-5681I-291J274D01*
G02X790458Y-3557I1093J1031D01*
G03X790479Y-2996I-274J291D01*
G02X792529Y-3017I1035J946D01*
G03X792539Y-3578I290J-275D01*
G02X792581Y-5681I-1051J-1073D01*
G03Y-6230I291J-274D01*
G02X792533Y-8339I-1093J-1030D01*
G37*
G36*
G01X1012148Y-10500D02*
G02X1009483Y-10458I-1322J714D01*
G03X1008770Y-10453I-358J-179D01*
G02Y-9119I-1290J667D01*
G03X1009483Y-9114I355J184D01*
G02X1012148Y-9072I1343J-672D01*
G03X1012851I352J190D01*
G02X1015516Y-9114I1322J-714D01*
G03X1016229Y-9119I358J179D01*
G02Y-10453I1290J-667D01*
G03X1015516Y-10458I-355J-184D01*
G02X1012851Y-10500I-1343J672D01*
G03X1012148I-352J-190D01*
G37*
G36*
G01X1025002Y610661D02*
X1024490Y610149D01*
X1024475Y610116D01*
G02X1022398Y611850I-1275J584D01*
G01Y615198D01*
X1021198D01*
Y615200D01*
X1020736D01*
Y615176D01*
X1015732D01*
Y615200D01*
X1013800D01*
X1013324Y615676D01*
X1013232D01*
Y615768D01*
X1013200Y615800D01*
Y620600D01*
X1013232Y620632D01*
Y620678D01*
X1013278D01*
X1013800Y621200D01*
X1021198D01*
Y621202D01*
X1026202D01*
Y621200D01*
X1028200D01*
X1028698Y620702D01*
X1028702D01*
Y615698D01*
X1028398D01*
X1027900Y615200D01*
X1026202D01*
Y615198D01*
X1025002D01*
Y610661D01*
G37*
G36*
G01X1015974Y612968D02*
G02X1015594Y610918I804J-1209D01*
G03X1015038Y611014I-326J-231D01*
G02X1012851Y611528I-865J1228D01*
G03X1012148I-352J-190D01*
G02X1009483Y611570I-1322J714D01*
G03X1008770Y611575I-358J-179D01*
G02X1006167Y611622I-1290J667D01*
G03X1005454Y611642I-362J-171D01*
G02X1005500Y612981I-1321J716D01*
G03X1006213Y612951I364J165D01*
G02X1008770Y612909I1267J-709D01*
G03X1009483Y612914I355J184D01*
G02X1012148Y612956I1343J-672D01*
G03X1012851I352J190D01*
G02X1015421Y613079I1322J-714D01*
G03X1015974Y612968I332J222D01*
G37*
G36*
G01X722273Y608773D02*
G02Y610327I-1167J777D01*
G03X722939I333J222D01*
G02X724817Y610758I1167J-777D01*
G03X725416Y611053I202J345D01*
G02X727941Y611837I1441J-182D01*
G03X728537Y611835I299J266D01*
G02X730676Y611855I1079J-972D01*
G03X731291Y611891I293J273D01*
G02X731381Y609999I1209J-891D01*
G03X730766Y609976I-298J-267D01*
G02X728532Y609897I-1150J887D01*
G03X727936Y609899I-299J-266D01*
G02X726098Y609633I-1079J972D01*
G03X725494Y609349I-208J-341D01*
G02X722939Y608773I-1388J201D01*
G03X722273I-333J-222D01*
G37*
G36*
G01X761755Y361723D02*
G03X761798Y361454I166J-111D01*
G02X758850Y361102I-1298J-1654D01*
G03X758827Y361374I-157J124D01*
G02X761755Y361723I1313J1445D01*
G37*
G36*
G01X754964Y592607D02*
G03X754403Y592580I-267J-298D01*
G02X754363Y594661I-1103J1020D01*
G03X754924Y594657I283J283D01*
G02X754964Y592607I976J-1006D01*
G37*
G36*
G01X751693Y517123D02*
G03X751774Y517704I-229J328D01*
G02X751829Y519601I1126J917D01*
G03Y520141I-295J270D01*
G02X751552Y520581I1070J981D01*
G03X751034Y520804I-371J-149D01*
G02X751805Y522665I-516J1304D01*
G03X752329Y522456I367J159D01*
G02X753971Y520141I571J-1335D01*
G03Y519601I295J-270D01*
G02X753701Y517410I-1071J-980D01*
G03X753605Y516832I221J-334D01*
G02X751693Y517123I-1109J-858D01*
G37*
G36*
G01X849602Y330485D02*
X848115Y328998D01*
X842085D01*
X840598Y330485D01*
Y335915D01*
X841985Y337302D01*
X842998D01*
Y338502D01*
X846002D01*
Y337302D01*
X847615D01*
X849602Y335315D01*
Y330485D01*
G37*
G36*
G01Y298885D02*
X848115Y297398D01*
X842085D01*
X840598Y298885D01*
Y304315D01*
X841985Y305702D01*
X842998D01*
Y306952D01*
X846002D01*
Y305702D01*
X847615D01*
X849602Y303715D01*
Y298885D01*
G37*
G36*
G01Y267185D02*
X848115Y265698D01*
X842085D01*
X840598Y267185D01*
Y272615D01*
X841985Y274002D01*
X842998D01*
Y275252D01*
X846002D01*
Y274002D01*
X847615D01*
X849602Y272015D01*
Y267185D01*
G37*
G36*
G01X841824Y244641D02*
X841985Y244802D01*
X842498D01*
Y245232D01*
X842998D01*
Y246732D01*
X846002D01*
Y245232D01*
X846502D01*
Y244802D01*
X847565D01*
G02X848999Y243488I35J-1402D01*
G01X849004Y243412D01*
X849602Y242815D01*
Y237985D01*
X848115Y236498D01*
X846502D01*
Y236228D01*
X846002D01*
Y234728D01*
X842998D01*
Y236228D01*
X842498D01*
Y236498D01*
X842085D01*
X841664Y236920D01*
X841567Y236908D01*
G02X840390Y239273I-167J1392D01*
G03Y239827I-288J277D01*
G02Y241773I1010J973D01*
G03Y242327I-288J277D01*
G02X841716Y244666I1010J973D01*
G01X841824Y244641D01*
G37*
G36*
G01X846310Y383802D02*
X847034D01*
X847589Y383246D01*
X847665Y383241D01*
G02X846335Y381191I-88J-1399D01*
G01X846279Y381298D01*
X843306D01*
Y384302D01*
X843806D01*
Y385302D01*
X845810D01*
Y384302D01*
X846310D01*
Y383802D01*
G37*
G36*
G01X1131460Y229921D02*
G02X1130626Y231368I-1800J-74D01*
G03X1131240Y231723I214J338D01*
G02X1132074Y230276I1800J74D01*
G03X1131460Y229921I-214J-338D01*
G37*
G36*
G01X999422Y226305D02*
G02X997750I-836J-1596D01*
G03Y227014I-186J354D01*
G02X999551Y230132I836J1597D01*
G03X1000164Y230486I214J338D01*
G02X1001000Y229037I1801J73D01*
G03X1000387Y228683I-214J-338D01*
G02X999422Y227014I-1801J-72D01*
G03Y226305I186J-355D01*
G37*
G36*
G01X928444Y224356D02*
G02X926770I-837J-1596D01*
G03Y225064I-186J354D01*
G02X928573Y228181I837J1596D01*
G03X929187Y228536I214J338D01*
G02X930021Y227089I1800J74D01*
G03X929407Y226734I-214J-338D01*
G02X928444Y225064I-1800J-74D01*
G03Y224356I186J-354D01*
G37*
G36*
G01X986866Y220884D02*
G02X983266I-1800J-75D01*
G03X982652Y221239I-400J17D01*
G02X979885Y222833I-966J1521D01*
G03X979272Y223188I-400J17D01*
G02X977470Y226305I-966J1521D01*
G03Y227014I-186J354D01*
G02X979272Y230131I836J1596D01*
G03X979885Y230486I213J338D01*
G02X982652Y232080I1801J73D01*
G03X983266Y232435I214J338D01*
G02X985904Y230914I1800J74D01*
G03Y230205I186J-354D01*
G02X984100Y227089I-838J-1595D01*
G03X983486Y226734I-214J-338D01*
G02X982523Y225064I-1800J-74D01*
G03Y224356I186J-354D01*
G02X983486Y222685I-837J-1596D01*
G03X984100Y222330I400J-17D01*
G02X986032I966J-1521D01*
G03X986646Y222685I214J338D01*
G02X989412Y224281I1800J75D01*
G03X990025Y224636I213J338D01*
G02X990990Y226305I1801J72D01*
G03Y227014I-186J354D01*
G02X992662I836J1596D01*
G03Y226305I186J-355D01*
G02X990860Y223188I-836J-1596D01*
G03X990247Y222833I-213J-338D01*
G02X987480Y221239I-1801J-73D01*
G03X986866Y220884I-214J-338D01*
G37*
G36*
G01X1090902Y218220D02*
G02X1087300I-1801J-73D01*
G03X1086687Y218575I-400J17D01*
G02X1087522Y220023I-966J1522D01*
G03X1088135Y219668I400J-17D01*
G02X1090067I966J-1521D01*
G03X1090680Y220023I213J338D01*
G02X1091515Y218575I1801J74D01*
G03X1090902Y218220I-213J-338D01*
G37*
G36*
G01X1026462Y214605D02*
G02X1024788I-837J-1596D01*
G03Y215313I-186J354D01*
G02X1023825Y216984I837J1596D01*
G03X1023211Y217339I-400J17D01*
G02X1021408Y220456I-966J1521D01*
G03Y221164I-186J354D01*
G02X1020444Y222833I837J1596D01*
G03X1019831Y223188I-400J17D01*
G02X1018029Y226305I-966J1521D01*
G03Y227014I-186J354D01*
G02X1017064Y228683I836J1597D01*
G03X1016451Y229038I-400J17D01*
G02X1017286Y230486I-966J1522D01*
G03X1017899Y230131I400J-17D01*
G02X1019831I966J-1521D01*
G03X1020444Y230486I213J338D01*
G02X1021279Y229038I1801J74D01*
G03X1020666Y228683I-213J-338D01*
G02X1019701Y227014I-1801J-72D01*
G03Y226305I186J-355D01*
G02X1020666Y224636I-836J-1597D01*
G03X1021279Y224281I400J-17D01*
G02X1023211I966J-1521D01*
G03X1023824Y224636I213J338D01*
G02X1027426I1801J73D01*
G03X1028039Y224281I400J-17D01*
G02X1029971I966J-1521D01*
G03X1030584Y224636I213J338D01*
G02X1034186I1801J73D01*
G03X1034799Y224281I400J-17D01*
G02X1036731I966J-1521D01*
G03X1037344Y224636I213J338D01*
G02X1040946I1801J73D01*
G03X1041559Y224282I399J-16D01*
G02X1043490Y224281I965J-1522D01*
G03X1044103Y224636I213J338D01*
G02X1044938Y223188I1801J74D01*
G03X1044325Y222833I-213J-338D01*
G02X1043361Y221164I-1801J-73D01*
G03Y220456I186J-354D01*
G02X1044324Y218785I-837J-1596D01*
G03X1044938Y218430I400J-17D01*
G02X1046870I966J-1521D01*
G03X1047484Y218785I214J338D01*
G02X1048318Y217339I1800J75D01*
G03X1047704Y216984I-214J-338D01*
G02X1044104I-1800J-75D01*
G03X1043490Y217339I-400J17D01*
G02X1041687Y220456I-966J1521D01*
G03Y221164I-186J354D01*
G02X1040723Y222833I837J1596D01*
G03X1040110Y223187I-399J16D01*
G02X1038179Y223188I-965J1522D01*
G03X1037566Y222833I-213J-338D01*
G02X1036602Y221164I-1801J-73D01*
G03Y220456I186J-354D01*
G02X1034928I-837J-1596D01*
G03Y221164I-186J354D01*
G02X1033964Y222833I837J1596D01*
G03X1033351Y223188I-400J17D01*
G02X1031419I-966J1521D01*
G03X1030806Y222833I-213J-338D01*
G02X1029842Y221164I-1801J-73D01*
G03Y220456I186J-354D01*
G02X1028039Y217339I-837J-1596D01*
G03X1027425Y216984I-214J-338D01*
G02X1026462Y215313I-1800J-75D01*
G03Y214605I186J-354D01*
G37*
G36*
G01X1006182D02*
G02X1004508I-837J-1596D01*
G03Y215313I-186J354D01*
G02X1003545Y216984I837J1596D01*
G03X1002931Y217339I-400J17D01*
G02X1003765Y218785I-966J1521D01*
G03X1004379Y218430I400J-17D01*
G02X1006311I966J-1521D01*
G03X1006925Y218785I214J338D01*
G02X1007759Y217339I1800J75D01*
G03X1007145Y216984I-214J-338D01*
G02X1006182Y215313I-1800J-75D01*
G03Y214605I186J-354D01*
G37*
G36*
G01X997620Y374430D02*
G02X996786Y372984I966J-1521D01*
G03X996172Y373339I-400J17D01*
G02X994369Y376456I-966J1521D01*
G03Y377164I-186J354D01*
G02X996043I837J1596D01*
G03Y376456I186J-354D01*
G02X997006Y374785I-837J-1596D01*
G03X997620Y374430I400J-17D01*
G37*
G36*
G01X989502Y11698D02*
Y11198D01*
X984998D01*
Y11798D01*
X983935D01*
G02Y14602I-35J1402D01*
G01X984998D01*
Y15202D01*
X989502D01*
Y14702D01*
X991002D01*
Y11698D01*
X989502D01*
G37*
G36*
G01X976502D02*
Y11198D01*
X971998D01*
Y11798D01*
X970835D01*
G02Y14602I-35J1402D01*
G01X971998D01*
Y15202D01*
X976502D01*
Y14702D01*
X978002D01*
Y11698D01*
X976502D01*
G37*
G36*
G01X989502Y49498D02*
Y48998D01*
X984998D01*
Y49698D01*
X984422D01*
X984389Y49686D01*
G02Y52314I-489J1314D01*
G01X984422Y52302D01*
X984998D01*
Y53002D01*
X989502D01*
Y52502D01*
X991002D01*
Y49498D01*
X989502D01*
G37*
G36*
G01X976502D02*
Y48998D01*
X971998D01*
Y49698D01*
X971587D01*
X971539Y49668D01*
G02X970216Y52135I-739J1192D01*
G01X970249Y52150D01*
X970401Y52302D01*
X971998D01*
Y53002D01*
X976502D01*
Y52502D01*
X978002D01*
Y49498D01*
X976502D01*
G37*
G36*
G01X1013862Y74314D02*
G02X1015361Y72029I488J-1314D01*
G03X1015649Y71352I288J-277D01*
G01X1015752D01*
Y67448D01*
X1014252D01*
Y66948D01*
X1009748D01*
Y71852D01*
X1011111D01*
X1013561Y74302D01*
X1013829D01*
X1013862Y74314D01*
G37*
G36*
G01X989502Y550498D02*
Y549998D01*
X984998D01*
Y550598D01*
X983935D01*
G02Y553402I-35J1402D01*
G01X984998D01*
Y554002D01*
X989502D01*
Y553502D01*
X991002D01*
Y550498D01*
X989502D01*
G37*
G36*
G01X976502D02*
Y549998D01*
X971998D01*
Y550598D01*
X970766D01*
G02Y553402I-35J1402D01*
G01X971998D01*
Y554002D01*
X976502D01*
Y553502D01*
X978002D01*
Y550498D01*
X976502D01*
G37*
G36*
G01X989502Y588298D02*
Y587798D01*
X984998D01*
Y588498D01*
X984422D01*
X984389Y588486D01*
G02Y591114I-489J1314D01*
G01X984422Y591102D01*
X984998D01*
Y591802D01*
X989502D01*
Y591302D01*
X991002D01*
Y588298D01*
X989502D01*
G37*
G36*
G01X976502D02*
Y587798D01*
X971998D01*
Y588498D01*
X971253D01*
X971220Y588486D01*
G02Y591114I-489J1314D01*
G01X971253Y591102D01*
X971998D01*
Y591802D01*
X976502D01*
Y591302D01*
X978002D01*
Y588298D01*
X976502D01*
G37*
G36*
G01X1115428Y-5436D02*
G03X1115434Y-5993I290J-275D01*
G02X1113278Y-6015I-1067J-1057D01*
G03X1113272Y-5458I-290J275D01*
G02X1115428Y-5436I1067J1057D01*
G37*
G36*
G01X1120533Y-5681D02*
G03Y-6230I291J-274D01*
G02X1118347I-1093J-1030D01*
G03Y-5681I-291J274D01*
G02X1120533I1093J1030D01*
G37*
G36*
G01X1082010Y11948D02*
Y11198D01*
X1077506D01*
Y11698D01*
X1076006D01*
Y14702D01*
X1077506D01*
Y15202D01*
X1082010D01*
Y14452D01*
X1082482D01*
X1082523Y14470D01*
G02Y11930I593J-1270D01*
G01X1082482Y11948D01*
X1082010D01*
G37*
G36*
G01X1069010D02*
Y11198D01*
X1064506D01*
Y11698D01*
X1063006D01*
Y14702D01*
X1064506D01*
Y15202D01*
X1069010D01*
Y14452D01*
X1070342D01*
X1070383Y14470D01*
G02Y11930I593J-1270D01*
G01X1070342Y11948D01*
X1069010D01*
G37*
G36*
G01X1056560D02*
Y11198D01*
X1052056D01*
Y11698D01*
X1050556D01*
Y14702D01*
X1052056D01*
Y15202D01*
X1056560D01*
Y14452D01*
X1057158D01*
X1057199Y14470D01*
G02Y11930I593J-1270D01*
G01X1057158Y11948D01*
X1056560D01*
G37*
G36*
G01X1082010Y49748D02*
Y48998D01*
X1077506D01*
Y49498D01*
X1076006D01*
Y52502D01*
X1077506D01*
Y53002D01*
X1082010D01*
Y52252D01*
X1082482D01*
X1082523Y52270D01*
G02Y49730I593J-1270D01*
G01X1082482Y49748D01*
X1082010D01*
G37*
G36*
G01Y588398D02*
Y587798D01*
X1077506D01*
Y588298D01*
X1076006D01*
Y591302D01*
X1077506D01*
Y591802D01*
X1082010D01*
Y591202D01*
X1083073D01*
G02Y588398I35J-1402D01*
G01X1082010D01*
G37*
G36*
G01Y550598D02*
Y549998D01*
X1077506D01*
Y550498D01*
X1076006D01*
Y553502D01*
X1077506D01*
Y554002D01*
X1082010D01*
Y553402D01*
X1083081D01*
G02Y550598I35J-1402D01*
G01X1082010D01*
G37*
G36*
G01X1131617Y385492D02*
G02X1129943I-837J-1596D01*
G03Y386200I-186J354D01*
G02X1131617I837J1596D01*
G03Y385492I186J-354D01*
G37*
G36*
G01X1138377Y381592D02*
G02X1136703I-837J-1596D01*
G03Y382300I-186J354D01*
G02Y385492I837J1596D01*
G03Y386200I-186J354D01*
G02X1138377I837J1596D01*
G03Y385492I186J-354D01*
G02Y382300I-837J-1596D01*
G03Y381592I186J-354D01*
G37*
G36*
G01X1125821Y368371D02*
G02X1124986Y369818I-1800J-74D01*
G03X1125600Y370172I214J338D01*
G02X1126562Y371842I1800J75D01*
G03Y372551I-186J355D01*
G02X1128238I838J1595D01*
G03Y371842I186J-354D01*
G02X1126435Y368725I-838J-1595D01*
G03X1125821Y368371I-214J-338D01*
G37*
G36*
G01X1162037Y360143D02*
G02X1160363I-837J-1596D01*
G03Y360851I-186J354D01*
G02X1159399Y362520I837J1596D01*
G03X1158786Y362875I-400J17D01*
G02X1159621Y364323I-966J1522D01*
G03X1160234Y363968I400J-17D01*
G02X1162166I966J-1521D01*
G03X1162779Y364323I213J338D01*
G02X1163614Y362875I1801J74D01*
G03X1163001Y362520I-213J-338D01*
G02X1162037Y360851I-1801J-73D01*
G03Y360143I186J-354D01*
G37*
G36*
G01X1139954Y356168D02*
G02X1139119Y354720I966J-1522D01*
G03X1138506Y355075I-400J17D01*
G02X1139341Y356523I-966J1522D01*
G03X1139954Y356168I400J-17D01*
G37*
G36*
G01X1169761Y350820D02*
G02X1168925Y352269I-1801J-73D01*
G03X1169538Y352623I214J338D01*
G02X1170374Y351174I1801J73D01*
G03X1169761Y350820I-214J-338D01*
G37*
G36*
G01X1176520Y319620D02*
G02X1175685Y321068I-1801J-74D01*
G03X1176298Y321423I213J338D01*
G02X1177262Y323092I1801J73D01*
G03Y323800I-186J354D01*
G02X1176299Y325471I837J1596D01*
G03X1175685Y325826I-400J17D01*
G02X1172918Y327420I-966J1521D01*
G03X1172305Y327775I-400J17D01*
G02X1170502Y330892I-966J1521D01*
G03Y331600I-186J354D01*
G02X1169539Y333271I837J1596D01*
G03X1168925Y333625I-400J16D01*
G02Y336669I-965J1522D01*
G03X1169538Y337023I214J338D01*
G02X1172176Y335500I1801J73D01*
G03Y334792I186J-354D01*
G02X1173140Y333123I-837J-1596D01*
G03X1173753Y332768I400J-17D01*
G02X1175685I966J-1521D01*
G03X1176298Y333123I213J338D01*
G02X1179900I1801J73D01*
G03X1180513Y332768I400J-17D01*
G02Y329726I966J-1521D01*
G03X1179899Y329371I-214J-338D01*
G02X1178936Y327700I-1800J-75D01*
G03Y326992I186J-354D01*
G02X1179899Y325322I-837J-1596D01*
G03X1180513Y324967I400J-17D01*
G02Y321925I966J-1521D01*
G03X1179899Y321570I-214J-338D01*
G02X1177133Y319975I-1800J-74D01*
G03X1176520Y319620I-213J-338D01*
G37*
G36*
G01X1256332Y93681D02*
Y93397D01*
X1256361Y93349D01*
G02X1253875I-1243J-750D01*
G01X1253904Y93397D01*
Y93681D01*
X1253072D01*
Y93121D01*
X1253085Y93088D01*
G02X1250457I-1314J-489D01*
G01X1250470Y93121D01*
Y93681D01*
X1250271D01*
Y101785D01*
X1256622D01*
Y93681D01*
X1256332D01*
G37*
G36*
G01X1268360Y70411D02*
Y67998D01*
X1263856D01*
Y68498D01*
X1262356D01*
Y71502D01*
X1263856D01*
Y72002D01*
X1266269D01*
X1266674Y72407D01*
Y73154D01*
X1266662Y73187D01*
G02X1269290I1314J489D01*
G01X1269278Y73154D01*
Y71329D01*
X1268360Y70411D01*
G37*
G36*
G01X1266374Y93394D02*
X1266402Y93346D01*
G02X1263916Y93352I-1245J-747D01*
G01X1263944Y93400D01*
Y93682D01*
X1263658D01*
Y101784D01*
X1266032D01*
G03X1266315Y102467I0J400D01*
G01X1263766Y105016D01*
X1263745D01*
X1262867Y105894D01*
Y109854D01*
X1263458Y110445D01*
X1265322D01*
X1265548Y110671D01*
Y112672D01*
X1265555D01*
Y112918D01*
X1265963Y113326D01*
X1273527D01*
X1274101Y112752D01*
Y110924D01*
X1274297Y110728D01*
X1275928D01*
X1276160Y110496D01*
G03X1276713Y110484I283J283D01*
G02X1278328Y108217I947J-1034D01*
G03X1278325Y107515I190J-352D01*
G02X1276861Y104892I-725J-1315D01*
G03X1276265Y104547I-196J-348D01*
G01X1272603Y100886D01*
X1272298D01*
X1272250Y100857D01*
G02X1270273Y101324I-750J1243D01*
G01X1269727D01*
G02X1267127Y101627I-1227J776D01*
G01X1267112Y101670D01*
X1267002Y101781D01*
G03X1266660Y101639I-142J-142D01*
G01Y93682D01*
X1266374D01*
Y93394D01*
G37*
G36*
G01X1312620Y92423D02*
G02X1310492Y92416I-1061J-992D01*
G03X1310490Y92960I-294J271D01*
G02X1310471Y92981I1067J985D01*
G03X1310160Y92964I-149J-134D01*
G02X1308089Y94958I-1177J850D01*
G03X1308087Y95591I-246J316D01*
G02X1309866Y95598I885J1151D01*
G03X1309868Y94965I246J-316D01*
G02X1309934Y94912I-876J-1158D01*
G03X1310488Y94941I262J302D01*
G02X1312618Y92967I1063J-989D01*
G03X1312620Y92423I294J-271D01*
G37*
G36*
G01X1256141Y74888D02*
G02X1254095I-1023J-1031D01*
G03X1253813Y75572I-282J284D01*
G01X1253618D01*
Y83674D01*
X1253904D01*
Y83959D01*
X1253875Y84007D01*
G02X1256361I1243J750D01*
G01X1256332Y83959D01*
Y83674D01*
X1256622D01*
Y75572D01*
X1256423D01*
G03X1256141Y74888I0J-400D01*
G37*
G36*
G01X1267039Y55443D02*
G02X1266824Y53714I983J-1000D01*
G03X1266196Y53785I-342J-208D01*
G02X1263916Y55552I-1038J1015D01*
G01X1263944Y55600D01*
Y55882D01*
X1263658D01*
Y63984D01*
X1263852D01*
G03X1264134Y64668I0J400D01*
G02X1266180I1023J1031D01*
G03X1266462Y63984I282J-284D01*
G01X1266660D01*
Y59626D01*
G03X1267281Y59292I400J0D01*
G02Y56788I830J-1252D01*
G03X1266660Y56454I-221J-334D01*
G01Y55882D01*
X1266374D01*
Y55594D01*
X1266402Y55546D01*
G02X1266413Y55528I-1233J-766D01*
G03X1267039Y55443I346J200D01*
G37*
G36*
G01X1256141Y37088D02*
G02X1254095I-1023J-1031D01*
G03X1253813Y37772I-282J284D01*
G01X1253618D01*
Y45874D01*
X1253904D01*
Y46159D01*
X1253875Y46207D01*
G02X1256361I1243J750D01*
G01X1256332Y46159D01*
Y45874D01*
X1256622D01*
Y37772D01*
X1256423D01*
G03X1256141Y37088I0J-400D01*
G37*
G36*
G01X1266374Y17794D02*
X1266402Y17746D01*
G02X1263916Y17752I-1245J-747D01*
G01X1263944Y17800D01*
Y18082D01*
X1263658D01*
Y26184D01*
X1263852D01*
G03X1264134Y26868I0J400D01*
G02X1266273Y28828I1023J1031D01*
G03X1266618Y28899I153J128D01*
G02X1266646Y28983I1343J-401D01*
G01X1266658Y29016D01*
Y29932D01*
X1266592Y29998D01*
X1263856D01*
Y30498D01*
X1262356D01*
Y33502D01*
X1263856D01*
Y34002D01*
X1268360D01*
Y31770D01*
X1268592Y31538D01*
X1268614Y31525D01*
G02X1269262Y30400I-653J-1125D01*
G01Y29016D01*
X1269274Y28983D01*
G02X1267077Y27405I-1314J-489D01*
G03X1266465Y27268I-252J-311D01*
G02X1266180Y26868I-1308J631D01*
G03X1266462Y26184I282J-284D01*
G01X1266660D01*
Y18082D01*
X1266374D01*
Y17794D01*
G37*
G36*
G01X1256332Y17797D02*
X1256361Y17749D01*
G02X1253875I-1243J-750D01*
G01X1253904Y17797D01*
Y18081D01*
X1253072D01*
Y17521D01*
X1253085Y17488D01*
G02X1250457I-1314J-489D01*
G01X1250470Y17521D01*
Y18081D01*
X1250271D01*
Y26185D01*
X1253813D01*
G03X1254095Y26869I0J400D01*
G02X1256141I1023J1030D01*
G03X1256423Y26185I282J-284D01*
G01X1256622D01*
Y18081D01*
X1256332D01*
Y17797D01*
G37*
G36*
G01X1256141Y-712D02*
G02X1254095I-1023J-1031D01*
G03X1253813Y-28I-282J284D01*
G01X1253618D01*
Y8074D01*
X1253904D01*
Y8359D01*
X1253875Y8407D01*
G02X1256361I1243J750D01*
G01X1256332Y8359D01*
Y8074D01*
X1256622D01*
Y-28D01*
X1256423D01*
G03X1256141Y-712I0J-400D01*
G37*
G36*
G01X1263668Y153851D02*
G03X1263074Y153845I-294J-271D01*
G02X1263200Y155942I-1274J1129D01*
G03X1263788Y155865I329J227D01*
G02X1263668Y153851I912J-1065D01*
G37*
G36*
G01X1265136Y151576D02*
G03X1265691Y151567I282J284D01*
G02X1265656Y149548I955J-1026D01*
G03X1265101Y149557I-282J-284D01*
G02X1263135Y149613I-955J1027D01*
G03X1262557I-289J-277D01*
G02Y151555I-1011J971D01*
G03X1263135I289J277D01*
G02X1265136Y151576I1011J-971D01*
G37*
G36*
G01X1246808Y607454D02*
G03X1246424Y606942I0J-400D01*
G02X1245579Y607858I-1346J-394D01*
G03X1246122Y608232I143J373D01*
G01Y608911D01*
G03X1245587Y609287I-400J0D01*
G02X1246375Y611458I-509J1413D01*
G01X1247124D01*
Y612127D01*
X1247111Y612160D01*
G02X1249739I1314J489D01*
G01X1249726Y612127D01*
Y611458D01*
X1250626D01*
Y610958D01*
X1252126D01*
Y607954D01*
X1250626D01*
Y607454D01*
X1246808D01*
G37*
G36*
G01X1256334Y576572D02*
Y575630D01*
G02X1253906I-1214J-796D01*
G01Y576572D01*
X1253618D01*
Y584676D01*
X1256622D01*
Y576572D01*
X1256334D01*
G37*
G36*
G01X1269410Y570010D02*
X1268100Y568700D01*
X1263000D01*
X1262700Y569000D01*
Y569498D01*
X1262356D01*
Y572502D01*
X1262902D01*
X1263300Y572900D01*
X1263856D01*
Y573002D01*
X1265986D01*
X1266398Y573414D01*
Y574300D01*
G02X1269402I1502J0D01*
G01Y572900D01*
X1269410D01*
Y570010D01*
G37*
G36*
G01X1256334Y538772D02*
Y537830D01*
G02X1253906I-1214J-796D01*
G01Y538772D01*
X1253618D01*
Y546876D01*
X1256622D01*
Y538772D01*
X1256334D01*
G37*
G36*
G01X1268360Y531676D02*
Y530998D01*
X1263856D01*
Y531498D01*
X1262356D01*
Y534502D01*
X1263856D01*
Y535002D01*
X1268360D01*
Y534280D01*
X1269278D01*
X1269311Y534292D01*
G02Y531664I489J-1314D01*
G01X1269278Y531676D01*
X1268360D01*
G37*
G36*
G01X1256622Y509076D02*
Y500972D01*
X1253618D01*
Y509076D01*
X1253906D01*
Y509360D01*
X1253877Y509408D01*
G02X1256363I1243J750D01*
G01X1256334Y509360D01*
Y509076D01*
X1256622D01*
G37*
G36*
G01X1269374Y500334D02*
G03X1269023Y499885I46J-397D01*
G02X1267419Y501137I-1439J-191D01*
G03X1267770Y501586I-46J397D01*
G02X1269374Y500334I1439J191D01*
G37*
G36*
G01X1279109Y497737D02*
G03X1279713Y497592I361J173D01*
G02X1279286Y495810I882J-1153D01*
G03X1278682Y495955I-361J-173D01*
G02X1279109Y497737I-882J1153D01*
G37*
G36*
G01X1256334Y594398D02*
X1256363Y594350D01*
G02X1253877I-1243J-750D01*
G01X1253906Y594398D01*
Y594682D01*
X1253072D01*
Y594121D01*
X1253085Y594088D01*
G02X1250457I-1314J-489D01*
G01X1250470Y594121D01*
Y594682D01*
X1250271D01*
Y602786D01*
X1250537D01*
G03X1250811Y603477I0J400D01*
G02X1252731I960J1022D01*
G03X1253005Y602786I274J-291D01*
G01X1256622D01*
Y594682D01*
X1256334D01*
Y594398D01*
G37*
G36*
G01X1269317Y594641D02*
G02Y592559I1083J-1041D01*
G03X1268756Y592575I-289J-277D01*
G02X1266799Y592618I-956J1025D01*
G03X1266221Y592611I-286J-280D01*
G02X1263916Y594352I-1063J988D01*
G01X1263944Y594400D01*
Y594682D01*
X1263658D01*
Y602786D01*
X1263829D01*
G03X1264116Y603464I0J400D01*
G02X1263775Y604922I1041J1012D01*
G03X1263484Y605434I-381J122D01*
G02X1262748Y607727I316J1366D01*
G01Y611002D01*
X1264248D01*
Y611502D01*
X1268752D01*
Y607498D01*
X1266339D01*
X1265090Y606249D01*
X1265075Y606216D01*
G02X1265072Y606209I-1290J549D01*
G03X1265241Y605926I181J-84D01*
G02X1266198Y603464I-84J-1450D01*
G03X1266485Y602786I287J-278D01*
G01X1266660D01*
Y595243D01*
G03X1267225Y594878I400J0D01*
G02X1268756Y594625I575J-1278D01*
G03X1269317Y594641I272J293D01*
G37*
G36*
G01X1266374Y556594D02*
X1266402Y556546D01*
G02X1263916Y556552I-1245J-747D01*
G01X1263944Y556600D01*
Y556882D01*
X1263658D01*
Y564986D01*
X1263829D01*
G03X1264116Y565664I0J400D01*
G02X1266198I1041J1012D01*
G03X1266485Y564986I287J-278D01*
G01X1266660D01*
Y556882D01*
X1266374D01*
Y556594D01*
G37*
G36*
G01X1279031Y546635D02*
G02X1277895Y545499I287J-1423D01*
G03X1277424Y545970I-393J78D01*
G02X1278560Y547106I-287J1423D01*
G03X1279031Y546635I393J-78D01*
G37*
G36*
G01X1266374Y518794D02*
X1266402Y518746D01*
G02X1263916Y518752I-1245J-747D01*
G01X1263944Y518800D01*
Y519082D01*
X1263658D01*
Y527186D01*
X1263829D01*
G03X1264116Y527864I0J400D01*
G02X1266198I1041J1012D01*
G03X1266485Y527186I287J-278D01*
G01X1266660D01*
Y519082D01*
X1266374D01*
Y518794D01*
G37*
G36*
G01X1273365Y511036D02*
G02X1273218Y509720I1211J-801D01*
G03X1272511Y509799I-374J-142D01*
G02X1272658Y511115I-1211J801D01*
G03X1273365Y511036I374J142D01*
G37*
G36*
G01X1270354Y496555D02*
G02X1267767Y495259I-1348J-539D01*
G03X1267153Y495343I-341J-209D01*
G02X1267401Y497161I-991J1061D01*
G03X1268015Y497077I341J209D01*
G02X1269303Y497437I991J-1061D01*
G03X1269757Y497977I82J392D01*
G02X1270808Y497095I1348J539D01*
G03X1270354Y496555I-82J-392D01*
G37*
G36*
G01X1324841Y132400D02*
G03X1324211I-315J-246D01*
G02Y134246I-1185J923D01*
G03X1324841I315J246D01*
G02Y132400I1185J-923D01*
G37*
G36*
G01X1327413Y144339D02*
G02X1326399Y142975I487J-1421D01*
G03X1325836Y143355I-400J15D01*
G02X1326887Y144769I-736J1645D01*
G03X1327413Y144339I397J-52D01*
G37*
G36*
G01X1318340Y417829D02*
G03X1317800I-270J-295D01*
G02X1315749Y419880I-980J1071D01*
G03Y420420I-295J270D01*
G02X1317891I1071J980D01*
G03Y419880I295J-270D01*
G02X1317919Y419849I-1063J-989D01*
G03X1318221I151J131D01*
G02X1318340Y417829I1099J-949D01*
G37*
G36*
G01X1343123Y462481D02*
G03X1342584Y462460I-258J-306D01*
G02X1342495Y464677I-1056J1068D01*
G03X1343034Y464698I258J306D01*
G02X1345142Y464702I1056J-1068D01*
G03X1345699Y464699I280J285D01*
G02X1345687Y462543I1040J-1084D01*
G03X1345130Y462546I-280J-285D01*
G02X1343123Y462481I-1040J1084D01*
G37*
G36*
G01X1339653Y440176D02*
X1341676Y438153D01*
Y432500D01*
G02X1338524I-1576J0D01*
G01Y436847D01*
X1338347Y437024D01*
X1332948D01*
G02Y440176I-873J1576D01*
G01X1336598D01*
Y441102D01*
X1338602D01*
Y440176D01*
X1339653D01*
G37*
G36*
G01X1302244Y465854D02*
G02X1302201Y467223I-1244J646D01*
G03X1302902Y467250I343J206D01*
G02X1302945Y465870I1298J-650D01*
G03X1302244Y465854I-346J-201D01*
G37*
G36*
G01X1299110Y597327D02*
G03Y596773I288J-277D01*
G02X1297090I-1010J-973D01*
G03Y597327I-288J277D01*
G02X1299110I1010J973D01*
G37*
G36*
G01Y591527D02*
G03Y590973I288J-277D01*
G02X1297090I-1010J-973D01*
G03Y591527I-288J277D01*
G02X1299110I1010J973D01*
G37*
G36*
G01X1382196Y27186D02*
G02X1381043Y24630I-554J-1288D01*
G02X1377988Y29746I-1843J2370D01*
G02X1382162Y27486I2962J486D01*
G02X1382196Y27186I-2962J-488D01*
G37*
G36*
G01X1382648Y394666D02*
G02X1382809Y394531I-1847J-2367D01*
G02Y390069I891J-2231D01*
G02X1377871Y392960I-2009J2231D01*
G03X1377740Y393193I-195J44D01*
G02X1379508Y395214I467J1375D01*
G03X1379756Y395115I179J89D01*
G02X1379890Y395161I1041J-2816D01*
G03X1380143Y395684I-121J381D01*
G02X1382593Y395244I1357J516D01*
G03X1382648Y394666I301J-263D01*
G37*
G36*
G01X1392412Y387004D02*
G03X1392939Y386869I336J217D01*
G02X1391378Y384478I1431J-2639D01*
G03X1391046Y384906I-398J34D01*
G02X1390867Y384938I157J1394D01*
G02X1392312Y387153I-1967J2862D01*
G02X1392412Y387004I-1111J-854D01*
G37*
G36*
G01X1467016Y571224D02*
G03X1467636Y571121I351J193D01*
G02X1467333Y569288I1013J-1109D01*
G03X1466713Y569391I-351J-193D01*
G02X1467016Y571224I-1013J1109D01*
G37*
G36*
G01X1417200Y556696D02*
X1415600D01*
G02X1414698Y557598I0J902D01*
G01Y559198D01*
G02X1414821Y559652I902J-1D01*
G01X1414848Y559699D01*
Y561368D01*
G02X1416901Y563980I734J1536D01*
G03X1417449Y563911I310J252D01*
G02X1419534Y563756I953J-1287D01*
G01X1419704Y563587D01*
X1419886Y563770D01*
X1419899Y563826D01*
G02X1423086Y564209I1661J-371D01*
G01X1423101Y564179D01*
X1423999Y563281D01*
X1425820Y565102D01*
X1427374D01*
G02X1429802Y562674I826J-1602D01*
G01Y561337D01*
X1429452Y560988D01*
Y559736D01*
X1429480Y559689D01*
G02X1429602Y559235I-779J-453D01*
G01Y557635D01*
G02X1428701Y556734I-901J0D01*
G01X1427101D01*
G02X1426408Y557058I-1J901D01*
G03X1425794I-307J-256D01*
G02X1425101Y556734I-692J577D01*
G01X1423501D01*
G02X1422600Y557635I0J901D01*
G01Y559235D01*
G02X1422722Y559689I901J1D01*
G01X1422750Y559736D01*
Y560001D01*
X1422234Y560516D01*
G03X1421552Y560233I-282J-283D01*
G01Y559699D01*
X1421579Y559652D01*
G02X1421702Y559198I-779J-455D01*
G01Y557598D01*
G02X1420800Y556696I-902J0D01*
G01X1419200D01*
G02X1418507Y557021I0J901D01*
G03X1417893I-307J-256D01*
G02X1417200Y556696I-693J576D01*
G37*
G36*
G01X1451897Y571203D02*
G02X1450403I-747J-1303D01*
G03Y571897I-199J347D01*
G02X1451897I747J1303D01*
G03Y571203I199J-347D01*
G37*
G36*
G01X1434115Y560469D02*
G02X1434100Y561885I-1555J692D01*
G03X1434819Y561876I362J171D01*
G02X1434834Y560494I1341J-677D01*
G03X1434115Y560469I-353J-187D01*
G37*
G36*
G01X1467591Y405882D02*
G02Y407664I-1209J891D01*
G03X1468230Y407657I322J237D01*
G02Y405889I1152J-884D01*
G03X1467591Y405882I-317J-244D01*
G37*
G36*
G01X1444170Y407840D02*
G03X1444081Y407303I245J-316D01*
G02X1441912Y407661I-1251J-831D01*
G03X1442001Y408198I-245J316D01*
G02X1444170Y407840I1251J831D01*
G37*
G36*
G01X1440646Y410672D02*
G02X1438852Y410576I-833J-1250D01*
G03X1438818Y411216I-256J307D01*
G02X1440612Y411312I833J1250D01*
G03X1440646Y410672I256J-307D01*
G37*
G36*
G01X1468877Y426983D02*
G03X1468313I-282J-284D01*
G02X1466214Y427039I-1023J1030D01*
G03X1465625Y427043I-296J-269D01*
G02X1465615Y428967I-1025J957D01*
G03X1466204Y428977I290J276D01*
G02X1468313Y429043I1086J-964D01*
G03X1468877I282J284D01*
G02X1470859Y429104I1024J-1030D01*
G03X1471399Y429114I265J300D01*
G02X1471441Y426972I1001J-1052D01*
G03X1470901Y426962I-265J-300D01*
G02X1468877Y426983I-1001J1051D01*
G37*
G36*
G01X1466259Y419336D02*
G03X1465691Y419235I-236J-323D01*
G02X1465176Y421256I-1166J779D01*
G03X1465723Y421439I186J354D01*
G02X1468610Y421750I1539J-728D01*
G03X1469215Y421717I317J244D01*
G02X1471266Y421760I1047J-1006D01*
G03X1471814Y421755I277J289D01*
G02X1471796Y419640I986J-1066D01*
G03X1471248Y419645I-277J-289D01*
G02X1469215Y419705I-986J1066D01*
G03X1468610Y419672I-288J-277D01*
G02X1466259Y419336I-1348J1039D01*
G37*
G36*
G01X1504576Y424939D02*
X1504577Y424855D01*
G02X1502582Y426181I-1452J-21D01*
G01X1502620Y426196D01*
X1502790Y426366D01*
X1502604Y426552D01*
Y426674D01*
G03X1501981Y427007I-400J0D01*
G02X1502596Y428515I-806J1208D01*
G03X1503270Y428315I391J83D01*
G01X1503376Y428422D01*
X1504473D01*
X1505246Y427648D01*
Y427447D01*
X1506252Y427448D01*
Y426754D01*
X1505246D01*
Y426552D01*
X1504876Y426182D01*
Y425240D01*
X1504576Y424939D01*
G37*
G36*
G01X1507320Y516655D02*
G03X1507113Y516413I-12J-200D01*
G02X1505569Y517508I-1370J-296D01*
G03X1505916Y517958I-49J397D01*
G02X1507441Y519657I1489J197D01*
G01X1507444Y519656D01*
X1509445D01*
X1509477Y519668D01*
G02X1510693Y519602I528J-1513D01*
G03X1511205Y519754I171J361D01*
G02X1511950Y517692I1195J-734D01*
G03X1511459Y517482I-128J-379D01*
G02X1509477Y516642I-1454J673D01*
G01X1509445Y516654D01*
X1507444D01*
X1507441Y516653D01*
G02X1507320Y516655I-36J1502D01*
G37*
G36*
G01X1497993Y514621D02*
G03X1497576Y514222I-17J-400D01*
G02X1496160Y515623I-1402J-1D01*
G03X1496555Y516044I-4J400D01*
G02X1498091Y517624I1500J78D01*
G01X1500655D01*
G02X1502156Y516132I-1J-1502D01*
G01Y516037D01*
X1502147Y515953D01*
G02X1500655Y514620I-1492J169D01*
G01X1498091D01*
G02X1497993Y514621I-34J1502D01*
G37*
G36*
G01X1489693Y508542D02*
G03X1490258Y508335I373J144D01*
G02X1489647Y506537I671J-1231D01*
G03X1489073Y506717I-366J-162D01*
G02X1488293Y506498I-781J1283D01*
G01X1486253D01*
X1486221Y506487D01*
G02X1484094Y508103I-528J1513D01*
G03X1483719Y508529I-399J27D01*
G02X1483659Y508534I86J1399D01*
G03X1483443Y508292I-21J-199D01*
G02X1483476Y507985I-1468J-313D01*
G01Y507890D01*
X1483467Y507806D01*
G02X1481975Y506474I-1492J169D01*
G01X1479935D01*
X1479903Y506462D01*
G02X1478509Y506627I-528J1513D01*
G03X1477961Y506515I-217J-336D01*
G02X1477427Y508554I-1161J785D01*
G03X1477959Y508725I178J358D01*
G02X1479903Y509488I1416J-750D01*
G01X1479935Y509476D01*
X1481975D01*
X1481997D01*
G03X1482403Y509888I6J400D01*
G02X1485205Y509984I1401J40D01*
G03X1485622Y509600I400J16D01*
G02X1486221Y509513I73J-1600D01*
G01X1486253Y509502D01*
X1488293D01*
G02X1489693Y508542I0J-1501D01*
G37*
G36*
G01X1613305Y441624D02*
G03X1613313Y441084I299J-266D01*
G02X1611144Y441022I-1057J-996D01*
G03X1611120Y441561I-307J256D01*
G02X1613305Y441624I1063J1062D01*
G37*
G36*
G01X1563916Y416106D02*
X1566960D01*
X1566992Y416116D01*
G02Y413272I483J-1422D01*
G01X1566960Y413282D01*
X1563916D01*
X1563895Y413278D01*
G02Y416110I-320J1416D01*
G01X1563916Y416106D01*
G37*
G36*
G01X1583713Y414774D02*
G03X1583826Y414129I283J-283D01*
G02X1581806Y412438I-618J-1314D01*
G01X1581766Y412586D01*
X1580502D01*
Y411748D01*
X1580002D01*
Y410748D01*
X1577998D01*
Y411748D01*
X1577498D01*
Y414752D01*
X1580502D01*
Y413914D01*
X1580975D01*
X1582201Y415140D01*
G03X1582197Y415710I-283J283D01*
G02X1583872Y415461I1011J1042D01*
G01Y414933D01*
X1583713Y414774D01*
G37*
G36*
G01X1613551Y410798D02*
G03X1613621Y410188I290J-276D01*
G02X1611774Y409976I-796J-1214D01*
G03X1611704Y410586I-290J276D01*
G02X1611286Y412596I796J1214D01*
G01Y413369D01*
G02X1613714I1214J1331D01*
G01Y412596D01*
G02X1613551Y410798I-1214J-796D01*
G37*
G36*
G01X1567816Y409346D02*
X1570860D01*
X1570892Y409356D01*
G02Y406512I483J-1422D01*
G01X1570860Y406522D01*
X1567816D01*
X1567795Y406518D01*
G02Y409350I-320J1416D01*
G01X1567816Y409346D01*
G37*
G36*
G01X1544678Y406252D02*
Y406453D01*
X1543674Y406452D01*
Y407146D01*
X1544678D01*
Y407348D01*
X1545452Y408122D01*
X1546548D01*
X1547322Y407348D01*
Y406251D01*
X1547152Y406081D01*
Y405473D01*
X1547191Y405419D01*
G02X1544815Y405357I-1166J-865D01*
G01X1544848Y405407D01*
Y406082D01*
X1544678Y406252D01*
G37*
G36*
G01X1591241Y410880D02*
G02X1590105Y410035I189J-1440D01*
G03X1589689Y410595I-365J164D01*
G02X1588545Y410941I-189J1440D01*
G03X1588005Y410928I-263J-301D01*
G02X1587955Y413070I-1005J1048D01*
G03X1588495Y413083I263J301D01*
G02X1590825Y411440I1005J-1048D01*
G03X1591241Y410880I365J-164D01*
G37*
G36*
G01X1506489Y436182D02*
G03X1506504Y435641I302J-262D01*
G02X1504365Y435581I-1042J-1011D01*
G03X1504350Y436122I-302J262D01*
G02X1506489Y436182I1042J1011D01*
G37*
G36*
G01X1507802Y451998D02*
X1505798D01*
Y452998D01*
X1505298D01*
Y456002D01*
X1507246D01*
G03X1507620Y456545I1J400D01*
G02X1510121Y456174I1355J521D01*
G03X1510170Y455631I316J-245D01*
G02X1510466Y455261I-971J-1080D01*
G03X1511157Y455250I349J196D01*
G02X1511134Y453789I1243J-750D01*
G03X1510443Y453800I-349J-196D01*
G02X1508586Y453234I-1243J750D01*
G01X1508546Y453253D01*
X1508302D01*
Y452998D01*
X1507802D01*
Y451998D01*
G37*
G36*
G01X1544173Y584628D02*
G03X1543627I-273J-292D01*
G02Y586820I-1027J1096D01*
G03X1544173I273J292D01*
G02Y584628I1027J-1096D01*
G37*
G36*
G01X1586689Y396288D02*
G03X1586156Y396285I-265J-300D01*
G02X1586144Y398526I-1006J1115D01*
G03X1586677Y398529I265J300D01*
G02X1586689Y396288I1006J-1115D01*
G37*
G36*
G01X1559334Y420042D02*
X1556116D01*
X1556095Y420038D01*
G02Y422870I-320J1416D01*
G01X1556116Y422866D01*
X1559334D01*
X1559355Y422870D01*
G02Y420038I320J-1416D01*
G01X1559334Y420042D01*
G37*
G36*
G01X1554166Y419486D02*
X1557210D01*
X1557242Y419496D01*
G02Y416652I483J-1422D01*
G01X1557210Y416662D01*
X1554166D01*
X1554145Y416658D01*
G02Y419490I-320J1416D01*
G01X1554166Y419486D01*
G37*
G36*
G01X1589910Y441559D02*
G03X1590466Y441544I286J280D01*
G02X1590406Y439459I980J-1072D01*
G03X1589850Y439474I-286J-280D01*
G02X1589910Y441559I-980J1072D01*
G37*
G36*
G01X1604781Y488209D02*
G03X1605313Y488186I279J286D01*
G02X1605221Y486096I887J-1086D01*
G03X1604689Y486119I-279J-286D01*
G02X1604781Y488209I-887J1086D01*
G37*
G36*
G01X1570865Y480910D02*
G02X1569612Y482166I-1440J-184D01*
G03X1570059Y482621I51J396D01*
G02X1571321Y481357I1486J221D01*
G03X1570865Y480910I-59J-396D01*
G37*
G36*
G01X1589419Y473474D02*
G02Y471266I1161J-1104D01*
G03X1588872Y471297I-290J-276D01*
G02X1586827Y471559I-902J1073D01*
G03X1586170Y471552I-326J-232D01*
G02Y473188I-1200J818D01*
G03X1586827Y473181I331J225D01*
G02X1588872Y473443I1143J-811D01*
G03X1589419Y473474I257J307D01*
G37*
G36*
G01X1616626Y465451D02*
Y463157D01*
G02X1613496I-1565J0D01*
G01Y467081D01*
X1613500Y467085D01*
Y467600D01*
X1615100Y469200D01*
Y470900D01*
X1615800Y471600D01*
X1620300D01*
X1621100Y470800D01*
Y470110D01*
X1621101Y470099D01*
G02Y469791I-1494J-154D01*
G01X1621100Y469780D01*
Y469300D01*
X1620200Y468400D01*
X1617600D01*
X1617100Y467900D01*
Y466859D01*
X1617101Y466850D01*
G02X1616626Y465451I-1794J-171D01*
G37*
G36*
G01X1642276Y129272D02*
Y128272D01*
X1640272D01*
Y129272D01*
X1639772D01*
Y129298D01*
X1627762D01*
X1626152Y130909D01*
Y134183D01*
X1624774Y135561D01*
Y136498D01*
X1624248D01*
Y138502D01*
X1624774D01*
Y138905D01*
X1625815Y139946D01*
X1629875D01*
X1631182Y138640D01*
X1634201D01*
X1635038Y139476D01*
X1639392D01*
X1640539Y140624D01*
X1643174D01*
X1643860Y139938D01*
Y139594D01*
X1644356D01*
Y137590D01*
X1643860D01*
Y136972D01*
X1642922Y136035D01*
Y132913D01*
X1643290Y132546D01*
Y129961D01*
X1642776Y129447D01*
Y129272D01*
X1642276D01*
G37*
G36*
G01X1816735Y55800D02*
G03X1817315Y55795I292J273D01*
G02X1817298Y53727I1081J-1043D01*
G03X1816718Y53732I-292J-273D01*
G02X1816735Y55800I-1081J1043D01*
G37*
G36*
G01X1873330Y212602D02*
G03X1872782Y212541I-242J-319D01*
G02X1872489Y214606I-1074J901D01*
G03X1873033Y214699I223J332D01*
G02X1873330Y212602I1203J-899D01*
G37*
G36*
G01X1847878Y503856D02*
X1847519Y503497D01*
X1844990D01*
X1844945Y503542D01*
X1844142D01*
X1843752Y503152D01*
X1843108D01*
G02X1842892I-108J1848D01*
G01X1842139D01*
X1840822Y504469D01*
Y508260D01*
X1843405Y510843D01*
X1845207D01*
X1846108Y509942D01*
Y508808D01*
X1847033Y507883D01*
X1847771D01*
X1847878Y507776D01*
Y503856D01*
G37*
G36*
G01X1910268Y202937D02*
G03X1910141Y202376I208J-342D01*
G02X1908123Y202728I-1174J-767D01*
G03X1908193Y203299I-241J319D01*
G02X1910268Y202937I1245J1008D01*
G37*
G36*
G01X1910116Y210136D02*
G02X1908533Y210016I-695J-1331D01*
G03X1908494Y210687I-236J323D01*
G02X1910054Y210805I692J1219D01*
G03X1910116Y210136I247J-314D01*
G37*
G54D266*
X1024271Y-8361D03*
X1008220Y620380D03*
G54D248*
X5120Y276058D03*
X2269Y273532D03*
X280Y524350D03*
X106000Y17260D03*
X105898Y55194D03*
X118220Y360500D03*
X359117Y253960D03*
X291519Y320260D03*
X284759D03*
X291519Y324160D03*
X277999D03*
X294899Y326109D03*
X298279Y324160D03*
X304328Y34100D03*
Y71900D03*
X408068Y607292D03*
X428147Y612657D03*
X434840D03*
X528491Y266896D03*
X538631Y272747D03*
X531871D03*
X538631Y276646D03*
X531871Y280547D03*
X538631Y264947D03*
Y268847D03*
X542011Y278596D03*
X535251Y274696D03*
X521731Y262996D03*
X525111Y264947D03*
X843503Y-3700D03*
X840157Y-9901D03*
X812999Y-4100D03*
X810039Y-9901D03*
X836810Y-3700D03*
X833464Y-9901D03*
X849810Y-4100D03*
X846850Y-9901D03*
X806692Y-3700D03*
X803346Y-9901D03*
X799999Y-3700D03*
X796653Y-9901D03*
X819378Y-4100D03*
X816732Y-9901D03*
X856189Y-4100D03*
X853543Y-9901D03*
X880314Y-3700D03*
X876968Y-9901D03*
X873621Y-3700D03*
X870275Y-9901D03*
X893000Y-4100D03*
X890354Y-9901D03*
X913779D03*
X886621Y-4100D03*
X883661Y-9901D03*
X910432Y-3700D03*
X907086Y-9901D03*
X957765Y-7180D03*
X970669Y-7108D03*
X974015Y-9901D03*
Y-4536D03*
X963976Y-7108D03*
X960629Y-4536D03*
X917125Y-3700D03*
X929811Y-4100D03*
X927165Y-9901D03*
X953936Y-3700D03*
X950590Y-9901D03*
X923432Y-4100D03*
X920472Y-9901D03*
X947243Y-3700D03*
X943897Y-9901D03*
X980708Y-9786D03*
X1004134Y-7108D03*
X1000787Y-9901D03*
X994094Y-4536D03*
Y-9786D03*
X987401Y-4536D03*
X990748Y-7108D03*
X984055D03*
X1004134Y607292D03*
X997441Y612357D03*
X994094Y609864D03*
X760100Y17255D03*
X753100Y92111D03*
X755500Y55200D03*
X763544Y522236D03*
X944507Y326110D03*
X995206Y218860D03*
Y222760D03*
X1045904Y213009D03*
X1147680Y229847D03*
X1154440Y237647D03*
X1157820Y227896D03*
X1147680Y241547D03*
X1161200Y237647D03*
X1174719Y222047D03*
X1171339Y227896D03*
X1164580Y231797D03*
X978306Y372909D03*
X953936Y34100D03*
Y71900D03*
X1110520Y-4100D03*
X1107874Y-9901D03*
X1104141Y-4100D03*
X1101181Y-9901D03*
X1087795Y-4536D03*
X1050984Y612658D03*
X1064369Y612657D03*
X1151060Y337096D03*
X1147680Y292247D03*
X1154440D03*
X1161200D03*
X1137540Y301996D03*
X1140920Y342947D03*
X1154440Y370246D03*
X1157820Y376096D03*
X1151060Y372196D03*
X1147680Y378047D03*
X1144300Y379996D03*
Y387796D03*
X1161200Y366347D03*
X1157820Y368296D03*
Y372196D03*
X1154440Y374146D03*
X1151060Y376096D03*
X1147680Y381947D03*
X1144300Y383896D03*
X1161200Y354647D03*
X1147680Y374146D03*
X1161200Y389747D03*
X1174719Y323446D03*
X1171339Y340996D03*
X1191619Y344896D03*
Y340996D03*
X1188239Y331247D03*
Y327347D03*
X1191619Y325396D03*
X1178099Y352696D03*
X1164580Y368296D03*
X1167960Y354647D03*
X1164580Y360496D03*
X1167960Y346847D03*
X1178099Y387796D03*
X1171339Y391696D03*
X1164580Y395597D03*
X1171339Y383896D03*
X1174719Y389747D03*
X1171339Y395596D03*
X1178099Y376096D03*
X1188239Y354647D03*
Y358547D03*
Y362447D03*
X1181479D03*
Y366347D03*
X1184859Y372197D03*
Y376096D03*
Y379996D03*
X1188239Y350747D03*
X1191619Y356596D03*
X1184859Y360496D03*
X1181479Y358547D03*
X1184859Y364396D03*
Y368296D03*
X1188239Y374146D03*
X1181479Y378047D03*
X1191619Y379996D03*
X1198379Y383896D03*
Y376096D03*
X1164580D03*
X1194999Y350747D03*
X1198379Y348796D03*
X1267959Y47245D03*
X1267800Y161800D03*
X1271400Y161900D03*
X1240309D03*
X1262843Y497553D03*
X1273200Y582200D03*
X1277200Y539100D03*
X1327168Y61483D03*
X1327452Y55544D03*
X1355500Y83000D03*
X1359500D03*
X1306900Y131744D03*
X1320500Y145000D03*
X1335100Y427500D03*
Y432500D03*
X1347546Y476897D03*
X1347196Y472941D03*
X1350500Y475100D03*
X1400216Y560128D03*
X1441409Y561117D03*
X1501175Y421454D03*
X1493375Y428214D03*
X1489475Y421454D03*
X1493375D03*
X1555775Y407934D03*
X1561625Y411314D03*
X1612250Y435500D03*
X1621226Y445026D03*
X1489475Y407934D03*
X1493375D03*
X1550990Y586588D03*
X1535565Y591658D03*
X1565525Y453686D03*
X1563575Y421454D03*
X1565525Y424834D03*
X1567475Y443546D03*
X1559675Y463826D03*
X1542125Y460446D03*
X1557725Y467206D03*
X1565525D03*
X1561625D03*
X1567475Y463826D03*
X1569425Y467206D03*
X1553825Y460446D03*
X1565525D03*
X1563575Y463826D03*
X1546025Y460446D03*
X1557725D03*
X1559675Y470586D03*
Y477346D03*
X1571375D03*
X1563575Y470586D03*
X1561625Y473966D03*
X1565525D03*
X1567475Y477346D03*
X1611642Y461877D03*
X1802119Y56581D03*
X1884340Y217866D03*
X1878789Y213663D03*
G54D271*
X741774Y376463D03*
G54D269*
X773419Y270414D03*
X753098Y338316D03*
X744698Y332816D03*
X757500Y374000D03*
G54D249*
X24400Y519500D03*
X-9600Y526100D03*
X122044Y162340D03*
X84300Y289000D03*
X102456Y393756D03*
X109500Y370000D03*
X1281799Y193190D03*
X1358500Y74500D03*
X1363500Y77400D03*
X1301240Y476228D03*
X1380872Y378098D03*
X1776828Y155211D03*
X1768886Y156173D03*
X1778900Y165800D03*
G54D270*
X757956Y328095D03*
G54D264*
X438187Y609864D03*
X646520Y297400D03*
X1336900Y61600D03*
X1351488Y74000D03*
X1379025Y-9799D03*
X1876001Y105438D03*
G54D245*
X40500Y-42250D03*
Y-52250D03*
X60500Y-42250D03*
X80500D03*
X100500D03*
X60500Y-52250D03*
X80500D03*
X100500D03*
X120500Y-42250D03*
Y-52250D03*
X467246Y-52301D03*
Y-42301D03*
X487246Y-52301D03*
Y-42301D03*
X507246Y-52301D03*
Y-42301D03*
X527246Y-52301D03*
Y-42301D03*
X547246Y-52301D03*
Y-42301D03*
X798984Y-52057D03*
Y-42057D03*
X818984Y-52057D03*
Y-42057D03*
X838984Y-52057D03*
Y-42057D03*
X858984Y-52057D03*
Y-42057D03*
X878984Y-52057D03*
Y-42057D03*
X1135583Y-52285D03*
Y-42285D03*
X1155583Y-52285D03*
Y-42285D03*
X1392258Y-52257D03*
Y-42257D03*
X1412258Y-52257D03*
Y-42257D03*
X1432258Y-52257D03*
Y-42257D03*
G54D274*
X1392264Y23976D03*
G54D250*
X10932Y523601D03*
X14700Y517000D03*
X288139Y322209D03*
X281379D03*
X298279Y320260D03*
X964786Y326110D03*
X971546D03*
X947887Y320260D03*
X941127D03*
X934367D03*
X927607Y324160D03*
X930987Y216909D03*
X958026D03*
X944507D03*
X937747Y228610D03*
X934367Y222760D03*
X944507Y232509D03*
X968166Y222760D03*
X1018865Y213009D03*
X1015485Y218860D03*
X1032385Y213009D03*
X1012105D03*
Y224709D03*
X1005345D03*
X1008725Y230559D03*
X1057314Y216909D03*
X1065242Y216196D03*
X1126280Y235696D03*
X1119521D03*
X1157820Y243496D03*
X1133040Y239596D03*
X937747Y372909D03*
X927607Y378760D03*
X934367D03*
X958026Y376809D03*
X944507D03*
X951267Y372909D03*
X971546D03*
X964786D03*
X991826Y384609D03*
X1025625Y372909D03*
X1018865D03*
X1012105D03*
X1022245Y378760D03*
X1015485D03*
X1001965D03*
X1032385Y372909D03*
X1029005Y378760D03*
X1012105Y384609D03*
X1008725Y378760D03*
X1005345Y372909D03*
Y384609D03*
X1035765Y378760D03*
X998586Y384609D03*
X1049284Y378760D03*
X1039145Y372909D03*
X1042524Y378760D03*
X1045904Y372909D03*
X1052664D03*
X1060963Y370959D03*
X1064371Y367060D03*
X1157820Y309797D03*
X1124021Y383896D03*
X1140920Y393647D03*
X1130780Y364396D03*
X1134160Y374146D03*
X1147680Y370247D03*
X1157820Y383896D03*
X1181479Y315647D03*
X1191619Y337096D03*
X1164580Y391696D03*
X1178099Y368296D03*
X1315180Y169950D03*
G54D260*
X105892Y8700D03*
Y45290D03*
X108385Y84291D03*
X81324Y316119D03*
X109640Y376070D03*
X105958Y518550D03*
X105412Y556580D03*
X105352Y594770D03*
X602163Y65699D03*
X620092Y13078D03*
X620070Y50878D03*
X620092Y88678D03*
X625430Y490100D03*
X632113Y496892D03*
X619392Y514700D03*
X618892Y555800D03*
X684100Y338200D03*
X812999Y-7851D03*
X806692D03*
X799999D03*
X819378Y-7700D03*
X843503Y-7851D03*
X849810D03*
X836810D03*
X873621D03*
X856189Y-7700D03*
X910432Y-7851D03*
X880314D03*
X886621D03*
X893000Y-7700D03*
X923432Y-7851D03*
X929811Y-7700D03*
X917125Y-7851D03*
X947243D03*
X953936D03*
X1026700Y1700D03*
X722050Y221150D03*
X720369Y205199D03*
X718300Y227400D03*
X742937Y218574D03*
X742897Y229573D03*
X716267Y522020D03*
X755500Y8700D03*
Y46700D03*
Y84361D03*
X732734Y82626D03*
X763350Y81220D03*
X763706Y514250D03*
X754910Y556400D03*
X752500Y585150D03*
X763677Y547783D03*
X913787Y328060D03*
X947887Y324160D03*
X937747Y322209D03*
X930987D03*
X941127Y324160D03*
X913787Y226660D03*
X913700Y222710D03*
X1269700Y13078D03*
X1268581Y92706D03*
X1269000Y514700D03*
X1268500Y555800D03*
X1248425Y604499D03*
X1360100Y452500D03*
Y457500D03*
X1349800Y458200D03*
X1350100Y447500D03*
Y452500D03*
X1301000Y460900D03*
X1385608Y-17485D03*
X1389523Y4966D03*
X1388627Y35032D03*
X1397500Y51000D03*
X1389138Y58499D03*
X1389068Y78556D03*
X1389100Y74600D03*
X1394760Y394720D03*
X1389450Y372250D03*
X1384531Y382957D03*
X1370100Y442500D03*
X1365100D03*
X1375100D03*
X1392500Y592000D03*
X1501934Y513047D03*
X1621010Y435870D03*
X1603650Y415469D03*
X1599900Y487100D03*
X1871855Y104188D03*
X1878950Y137400D03*
G54D268*
X761480Y242720D03*
G54D259*
X-1190Y53240D03*
X104500Y-1850D03*
X114680Y17320D03*
X114082Y55100D03*
X110397Y402603D03*
X277999Y277360D03*
X291519Y285160D03*
Y292959D03*
X284759Y285160D03*
X277999Y300760D03*
Y292959D03*
Y285160D03*
X291519Y308560D03*
X284759D03*
Y300760D03*
X291519D03*
X284759Y292959D03*
X321938Y283209D03*
X315178Y279310D03*
Y283209D03*
X318558Y281260D03*
X328698Y283209D03*
X332078Y281260D03*
X325318D03*
X338838D03*
X335458Y283209D03*
X348978Y263709D03*
X355737Y259809D03*
X352357Y261760D03*
X345598Y273460D03*
Y269560D03*
X342218Y271509D03*
Y283209D03*
Y279310D03*
Y275409D03*
X311798Y292959D03*
X305039D03*
X318558D03*
X311798Y285160D03*
X332078Y300760D03*
Y292959D03*
X298279Y308560D03*
X315178Y310509D03*
X305039Y308560D03*
X311798D03*
X305039Y300760D03*
X325318D03*
X311798D03*
X298279D03*
X318558D03*
X325318Y292959D03*
X305039Y285160D03*
X298279D03*
Y292959D03*
X338838Y300760D03*
Y292959D03*
X342218Y310509D03*
X379397Y250060D03*
X386157D03*
X365877Y253960D03*
X362497Y255909D03*
X359117Y257860D03*
X392916Y250060D03*
X399676D03*
X281379Y318309D03*
X274619Y326110D03*
Y322209D03*
X277999Y320260D03*
Y316360D03*
X284759Y324160D03*
X288139Y318309D03*
X284759Y316360D03*
X294899Y322209D03*
Y318309D03*
X281379Y326110D03*
X288139D03*
X271239Y320260D03*
Y324160D03*
X270939Y316160D03*
X267359Y318309D03*
X267859Y326110D03*
X267392Y322000D03*
X270892Y311960D03*
Y308560D03*
X274619Y310509D03*
X277999Y312460D03*
X274619Y314409D03*
X281379D03*
X274619Y318309D03*
X311798Y324160D03*
X315178Y322209D03*
X321938D03*
X328698Y326110D03*
X325318Y324160D03*
X318558Y320260D03*
X301659Y318309D03*
X308418D03*
Y326110D03*
X338838Y316360D03*
X345598Y328060D03*
X342218Y322209D03*
Y318309D03*
Y326110D03*
X345598Y320260D03*
Y324160D03*
X318558D03*
X357987Y327609D03*
X348978Y322209D03*
Y318309D03*
Y326110D03*
X357057Y320260D03*
Y324160D03*
X361367Y329560D03*
X405306Y347109D03*
X441743Y348497D03*
X445123Y346546D03*
X528491Y274696D03*
X531871Y268847D03*
Y276646D03*
X535251Y266896D03*
X521731Y259096D03*
X542011Y274696D03*
X518352Y261047D03*
X525111D03*
X518352Y257147D03*
X528491Y262996D03*
X542011Y266896D03*
X538631Y280547D03*
X535251Y278596D03*
Y270796D03*
X545391Y280547D03*
X647600Y84200D03*
X605510Y612657D03*
X623600Y521700D03*
X658500Y284500D03*
X731210Y-15134D03*
X960629Y-9786D03*
X967322D03*
Y-4536D03*
X987401Y-9901D03*
X997441Y-7108D03*
X977362D03*
X990748Y612457D03*
X1000787Y609864D03*
X764100Y17100D03*
X755000Y17255D03*
X764100Y55100D03*
X761650Y94550D03*
X927607Y277360D03*
X964786Y283209D03*
X971546D03*
X964786Y279310D03*
X974926Y281260D03*
X968166D03*
X934367Y285160D03*
Y300760D03*
X927607D03*
X934367Y308560D03*
X927607Y285160D03*
Y292959D03*
X934367D03*
X961406D03*
Y285160D03*
X954647Y292959D03*
Y285160D03*
X968166Y292959D03*
Y300760D03*
X964786Y310509D03*
X954647Y308560D03*
X961406D03*
X954647Y300760D03*
X961406D03*
X974926D03*
X947887Y308560D03*
X941127D03*
Y300760D03*
X947887D03*
X941127Y285160D03*
Y292959D03*
X947887D03*
Y285160D03*
X974926Y292959D03*
X981686Y281260D03*
X995206Y269560D03*
X998586Y263709D03*
X991826Y271509D03*
X995206Y273460D03*
X991826Y283209D03*
Y279310D03*
Y275409D03*
X988446Y281260D03*
X985066Y283209D03*
X978306D03*
X1035765Y250060D03*
X1029005D03*
X1001965Y261760D03*
X1012105Y255909D03*
X1015485Y253960D03*
X1005345Y259809D03*
X1008725Y257860D03*
X981686Y292959D03*
Y300760D03*
X988446D03*
X991826Y310509D03*
X988446Y292959D03*
X1042524Y250060D03*
X1049284D03*
X840871Y391380D03*
X837272Y391420D03*
X937747Y318309D03*
Y326110D03*
X920847Y328060D03*
X930987Y326110D03*
X927607Y328060D03*
X934367Y324160D03*
X924227Y322209D03*
X927607Y320260D03*
X930987Y318309D03*
X927607Y316360D03*
X924227Y326110D03*
X958026Y318309D03*
X951267D03*
X961406Y324160D03*
X974926D03*
X954647Y328060D03*
X971546Y322209D03*
X968166Y320260D03*
X964786Y322209D03*
X958026Y326110D03*
X944507Y322209D03*
Y318309D03*
X947887Y328060D03*
X941127D03*
X934367D03*
X968166D03*
Y324160D03*
X974926Y328060D03*
X961406D03*
X920500Y311960D03*
X924227Y310509D03*
X920500Y308560D03*
X924227Y314409D03*
X930987D03*
X927607Y312460D03*
X920847Y324160D03*
X924227Y318309D03*
X920547Y316160D03*
X917167Y318309D03*
Y322209D03*
X917467Y326110D03*
X920847Y320260D03*
X995206Y328060D03*
X991826Y326110D03*
X978306D03*
X995206Y324160D03*
X988446Y316360D03*
X991826Y318309D03*
X995206Y320260D03*
X991826Y322209D03*
X998586Y318309D03*
Y322209D03*
Y326110D03*
X1007595Y327609D03*
X1010975Y329560D03*
X1006665Y324160D03*
Y320260D03*
X930987Y220809D03*
X934367Y214960D03*
X927607D03*
X937747Y216909D03*
X924227D03*
Y220809D03*
X968166Y218860D03*
X947887D03*
X941127D03*
Y214960D03*
X961406D03*
Y218860D03*
X954647D03*
X971546Y220809D03*
X964786Y216909D03*
Y220809D03*
X927607Y218860D03*
X934367D03*
X947887Y214960D03*
X958026Y220809D03*
X944507D03*
X954647Y214960D03*
X937747Y220809D03*
X934367Y226660D03*
X924227Y232509D03*
X927607Y230559D03*
X930987Y232509D03*
X924227Y228610D03*
Y224709D03*
X937747Y232509D03*
X944507Y228610D03*
Y224709D03*
X941127Y222760D03*
X947887Y226660D03*
X941127Y230559D03*
Y226660D03*
X958026Y228610D03*
X951267D03*
X954647Y226660D03*
X958026Y224709D03*
Y232509D03*
X954647Y230559D03*
X961406Y222760D03*
X974926Y226660D03*
X968166D03*
X974926Y230559D03*
Y222760D03*
X964786Y232509D03*
X937747Y224709D03*
X934367Y230559D03*
X951267Y224709D03*
X930987D03*
X947887Y230559D03*
X961406D03*
X971546Y224709D03*
X964786D03*
X971546Y232509D03*
X998586Y220809D03*
X981686Y218860D03*
X991826Y220809D03*
X985066Y216909D03*
X988446Y211058D03*
X979426Y214958D03*
X978306Y220809D03*
X1005345D03*
X1001965Y211060D03*
X1012105Y220809D03*
X1018865D03*
X1032385D03*
X1022245Y211060D03*
X998586Y216909D03*
X1012105D03*
X1035765Y211060D03*
X1018865Y216909D03*
X1032385D03*
X1008725Y211060D03*
X988446Y218860D03*
X995206Y214960D03*
X1001965D03*
X1035765D03*
X1015485D03*
X1022245D03*
X1029005D03*
X1008725D03*
X985066Y224709D03*
X978306Y232509D03*
X988446Y230560D03*
X995206Y230559D03*
X1015485Y222760D03*
X1001965D03*
X1008725D03*
X1012105Y228610D03*
X1005345D03*
X1025625D03*
X998586Y232509D03*
X991826D03*
X995206Y226660D03*
X1035765D03*
X1018865Y232509D03*
X1015485Y226660D03*
X1022245D03*
X1012105Y232509D03*
X1029005Y226660D03*
X1008725D03*
X1005345Y232509D03*
X1001965Y226660D03*
X1045904Y220809D03*
X1057314D03*
X1039145D03*
X1072202Y216196D03*
X1099241D03*
X1065242Y212296D03*
X1095861Y218147D03*
X1099241Y220096D03*
X1092481Y216196D03*
X1075582Y218147D03*
X1082341D03*
X1078962Y216196D03*
Y220096D03*
X1085721Y216196D03*
X1095861Y222047D03*
X1082341D03*
X1089101D03*
X1065242Y220096D03*
X1068822Y218147D03*
X1039145Y216909D03*
X1042524Y214960D03*
X1049284D03*
Y222760D03*
X1042524Y226660D03*
X1116141Y218147D03*
X1102621D03*
X1119521Y220096D03*
Y216196D03*
X1106001D03*
X1112761D03*
X1116141Y222047D03*
X1109381D03*
X1112761Y223996D03*
X1119521D03*
Y227896D03*
X1116141Y229847D03*
X1129660Y237647D03*
X1126280Y223996D03*
Y231797D03*
X1122900Y229847D03*
Y237647D03*
X1129660Y233746D03*
Y241547D03*
X1126280Y243496D03*
X1144300D03*
X1154440Y245447D03*
X1136420D03*
X1154440Y241547D03*
X1136420D03*
X1157820Y239596D03*
X1144300Y235696D03*
X1136420Y229847D03*
Y233746D03*
Y225947D03*
Y237647D03*
X1133040Y235696D03*
Y243496D03*
X1147680Y225947D03*
Y233746D03*
X1154440Y229847D03*
X1157820Y231797D03*
X1126280Y227896D03*
X1133040D03*
X1129660Y225947D03*
X1109381D03*
X1126280Y239596D03*
X1122900Y233746D03*
X1119521Y231797D03*
X1129660Y245447D03*
X1151060Y243496D03*
X1144300Y239596D03*
X1151060Y235696D03*
X1144300Y227896D03*
X1154440Y233746D03*
X1147680Y237647D03*
X1151060Y239596D03*
X1144300Y231797D03*
X1151060D03*
Y227896D03*
X1157820Y235696D03*
X1171339Y220096D03*
X1164580Y235696D03*
X1167960Y229847D03*
X1164580Y223996D03*
Y227896D03*
Y239596D03*
X1161200Y241547D03*
X1171339Y235696D03*
Y231797D03*
X1178099Y227896D03*
X1188239Y225947D03*
X1161200Y245447D03*
X1167960Y237647D03*
X1174719Y229847D03*
X1167960Y225947D03*
X1174719Y233746D03*
X1161200D03*
Y229847D03*
X1171339Y223996D03*
X1174719Y225947D03*
X1181479D03*
X1161200D03*
X930987Y376809D03*
X924227Y372909D03*
X917100Y380709D03*
X937747D03*
X924227D03*
Y376809D03*
X968166Y370959D03*
X954647D03*
X958026Y369010D03*
X974926Y370959D03*
X958026Y372909D03*
X974926Y374860D03*
X941127D03*
X961406D03*
X944507Y372909D03*
X941127Y378760D03*
X947887D03*
X964786Y376809D03*
X971546D03*
X968166Y378760D03*
X961406D03*
X954647D03*
X974926D03*
X971546Y380709D03*
X968166Y382660D03*
X930987Y380709D03*
X927607Y374860D03*
X947887D03*
X958026Y380709D03*
X944507D03*
X954647Y374860D03*
X934367D03*
X951267Y376809D03*
X937747D03*
X930987Y372909D03*
X951267Y380709D03*
X968166Y374860D03*
X971546Y369010D03*
X961406Y370959D03*
X964786Y369010D03*
X985066Y372909D03*
Y384609D03*
X998586Y376809D03*
X991826D03*
X978306D03*
X981686Y378760D03*
X985066Y380709D03*
X1032385Y376809D03*
X1005345D03*
X1025625D03*
X1018865D03*
X1012105D03*
X991826Y380709D03*
X998586D03*
X991826Y372909D03*
X988446Y374860D03*
X1012105Y380709D03*
X1022245Y374860D03*
X1015485D03*
X1025625Y380709D03*
X1035765Y374860D03*
X1018865Y380709D03*
X1001965Y374860D03*
X1032385Y380709D03*
X1029005Y374860D03*
X1005345Y380709D03*
X1008725Y374860D03*
X998586Y369010D03*
X991826D03*
X1005345D03*
X995206Y370959D03*
X988446Y382660D03*
X995206D03*
X1008725Y370959D03*
X1001965D03*
X1022245D03*
X1015485D03*
X1029005D03*
X1035765D03*
X1008725Y382660D03*
X1001965D03*
X1015485D03*
X1039145Y376809D03*
X1045904D03*
X1052664D03*
X1060694Y374860D03*
X1045904Y380709D03*
X1052664D03*
X1049284Y374860D03*
X1042524D03*
X1039145Y380709D03*
X1049284Y370959D03*
X1042524D03*
X1076435Y343595D03*
X1094731Y346546D03*
X1091351Y348497D03*
X1130780Y290296D03*
X1151060Y298096D03*
X1144300Y294196D03*
X1157820D03*
X1140920Y300047D03*
X1134160Y292247D03*
Y300047D03*
X1140920Y292247D03*
X1144300Y309797D03*
X1147680Y303947D03*
X1154440Y307847D03*
X1157820Y313696D03*
Y337096D03*
Y333196D03*
X1147680Y342947D03*
X1151060Y340996D03*
Y333196D03*
X1154440Y319547D03*
X1157820Y317596D03*
Y329296D03*
X1147680Y327347D03*
X1154440Y342947D03*
Y335147D03*
X1144300Y340996D03*
Y337096D03*
X1140920Y339047D03*
Y331247D03*
X1154440Y323446D03*
Y315647D03*
X1144300Y344896D03*
X1147680Y319547D03*
X1157820Y325396D03*
X1151060Y344896D03*
X1154440Y339047D03*
Y331247D03*
X1140920Y323446D03*
X1147680Y307847D03*
X1151060Y309797D03*
Y305896D03*
X1144300Y301996D03*
Y298096D03*
X1137540D03*
X1140920Y303947D03*
X1137540Y305896D03*
X1140920Y296147D03*
X1137540Y294196D03*
X1154440Y311747D03*
X1157820Y305896D03*
X1154440Y303947D03*
X1157820Y301996D03*
X1154440Y300047D03*
X1151060Y294196D03*
X1147680Y300047D03*
Y296147D03*
X1140920Y307847D03*
Y311747D03*
X1151060Y301996D03*
X1144300Y305896D03*
X1147680Y311747D03*
X1157820Y298096D03*
X1154440Y296147D03*
X1140920Y319547D03*
X1144300Y313696D03*
X1151060D03*
X1144300Y325396D03*
Y321496D03*
X1151060Y329296D03*
X1147680Y335147D03*
Y331247D03*
X1140920Y335147D03*
X1144300Y333196D03*
X1151060Y325396D03*
Y321496D03*
X1147680Y323446D03*
X1144300Y329296D03*
X1140920Y327347D03*
X1147680Y315647D03*
X1151060Y317596D03*
X1137540Y344896D03*
X1144300Y317596D03*
X1151060Y368296D03*
X1147680Y366347D03*
X1127400Y362447D03*
Y354647D03*
Y358547D03*
X1130780Y360496D03*
X1134160Y362447D03*
Y366347D03*
Y370247D03*
X1151060Y356596D03*
Y360496D03*
X1144300D03*
X1137540D03*
X1144300Y356596D03*
X1140920Y358547D03*
X1147680Y346847D03*
Y350747D03*
X1151060Y352696D03*
Y348796D03*
X1147680Y358547D03*
X1157820Y360496D03*
X1154440Y358547D03*
Y354647D03*
X1157820Y352696D03*
X1147680Y354647D03*
X1144300Y348796D03*
X1140920Y346847D03*
Y350747D03*
X1154440Y346847D03*
X1140920Y362447D03*
X1154440Y366347D03*
X1144300Y372197D03*
X1137540D03*
Y368296D03*
X1140920Y366347D03*
Y370247D03*
X1151060Y364396D03*
X1144300D03*
X1137540D03*
X1147680Y362447D03*
X1130780Y352696D03*
X1124021Y372197D03*
X1130780D03*
X1124021Y364396D03*
Y391696D03*
X1130780Y395596D03*
X1127400Y385847D03*
Y389747D03*
X1130780Y391696D03*
X1124021Y379996D03*
X1127400Y381947D03*
X1130780Y379996D03*
X1137540Y395597D03*
Y376096D03*
X1157820Y387796D03*
X1140920Y378047D03*
Y381947D03*
X1147680Y393647D03*
X1140920Y374146D03*
X1151060Y395597D03*
Y391696D03*
X1147680Y385847D03*
X1151060Y379996D03*
X1154440Y378047D03*
Y381947D03*
X1140920Y389747D03*
X1134160Y393647D03*
Y385847D03*
Y378047D03*
X1140920Y385847D03*
X1144300Y391696D03*
X1124021Y387796D03*
X1134160Y381947D03*
Y389747D03*
X1144300Y395597D03*
X1137540Y391696D03*
X1124021Y376096D03*
X1130780Y368296D03*
Y376096D03*
X1127400Y378047D03*
Y366347D03*
X1154440Y397546D03*
Y393647D03*
X1151060Y387796D03*
X1157820Y395597D03*
X1154440Y389747D03*
X1157820Y391696D03*
X1154440Y385847D03*
X1134160Y358547D03*
X1137540Y352696D03*
X1130780Y356596D03*
X1134160Y354647D03*
Y350747D03*
X1137540Y348796D03*
X1164580Y294196D03*
Y301996D03*
X1171339D03*
X1161200Y307847D03*
Y335147D03*
Y339047D03*
X1164580Y329296D03*
Y333196D03*
Y337096D03*
X1167960Y339047D03*
Y327347D03*
X1161200Y331247D03*
Y327347D03*
X1178099Y337096D03*
Y317596D03*
X1164580Y321496D03*
Y317596D03*
X1161200Y323446D03*
Y319547D03*
Y315647D03*
X1167960Y342947D03*
Y323446D03*
Y315647D03*
Y319547D03*
X1174719Y315647D03*
X1171339Y317596D03*
X1164580Y325396D03*
X1171339D03*
X1174719Y342947D03*
Y335147D03*
X1181479Y311747D03*
Y307847D03*
X1194999Y335147D03*
Y331247D03*
X1181479Y327347D03*
Y319547D03*
Y335147D03*
X1188239Y319547D03*
X1184859Y321496D03*
X1188239Y339047D03*
Y335147D03*
X1184859Y329296D03*
X1191619Y321496D03*
X1198379Y325396D03*
Y340996D03*
X1184859Y337096D03*
X1178099Y340996D03*
X1181479Y339047D03*
Y342947D03*
X1178099Y344896D03*
X1201759Y342947D03*
X1198379Y344896D03*
Y333196D03*
X1161200Y311747D03*
Y300047D03*
Y303947D03*
X1184859Y344896D03*
X1194999Y327347D03*
X1184859Y317596D03*
X1191619D03*
X1184859Y340996D03*
X1188239Y342947D03*
X1194999Y339047D03*
X1191619Y333196D03*
Y329296D03*
X1188239Y323446D03*
X1184859Y313696D03*
X1188239Y315647D03*
X1174719Y303947D03*
X1167960D03*
X1178099Y309797D03*
X1171339Y305896D03*
X1164580Y309797D03*
Y305896D03*
X1167960Y307847D03*
Y311747D03*
X1171339Y309797D03*
X1174719Y311747D03*
Y307847D03*
X1178099Y305896D03*
Y313696D03*
X1171339D03*
X1164580D03*
X1167960Y300047D03*
X1164580Y298096D03*
X1167960Y296147D03*
X1161200D03*
X1171339Y298096D03*
X1167960Y370247D03*
X1164580Y372197D03*
X1171339Y356596D03*
Y360496D03*
X1164580Y356596D03*
X1171339Y348796D03*
X1174719Y354647D03*
X1161200Y370247D03*
X1171339Y372197D03*
X1167960Y362447D03*
X1178099Y364396D03*
X1171339Y399496D03*
X1178099Y403396D03*
X1167960Y389747D03*
X1161200Y397546D03*
X1167960Y397547D03*
X1174719Y393647D03*
X1161200Y378047D03*
X1164580Y379996D03*
X1174719Y381947D03*
X1194999Y346847D03*
Y354647D03*
X1181479Y346847D03*
X1188239Y366347D03*
X1194999D03*
X1191619Y348796D03*
X1184859Y356596D03*
X1191619Y360496D03*
X1201759Y350747D03*
X1205139Y360496D03*
X1181479Y374146D03*
Y389747D03*
X1184859Y383896D03*
X1188239Y393647D03*
X1201759Y389747D03*
X1197258Y397546D03*
X1194999Y385847D03*
X1188239Y378047D03*
X1201759D03*
X1174719Y346847D03*
X1178099Y348796D03*
X1201759Y346847D03*
X1184859Y348796D03*
X1188239Y346847D03*
X1171339Y387796D03*
X1167960Y393647D03*
X1178099Y379996D03*
Y383896D03*
X1174719Y385847D03*
X1164580Y387796D03*
X1181479Y381947D03*
X1174719Y370247D03*
X1181479D03*
X1171339Y364396D03*
X1178099Y360496D03*
Y356596D03*
X1184859Y352696D03*
X1161200Y393647D03*
Y385847D03*
X1167960D03*
Y381947D03*
Y378047D03*
X1174719D03*
Y374146D03*
Y366347D03*
Y362447D03*
Y358547D03*
X1181479Y354647D03*
Y350747D03*
X1161200Y381947D03*
X1164580Y383896D03*
X1171339Y379996D03*
X1167960Y374146D03*
X1171339Y376096D03*
X1178099Y372197D03*
X1194999Y378047D03*
X1201759Y374146D03*
X1194999D03*
X1198379Y364396D03*
Y360496D03*
Y356596D03*
X1174719Y401447D03*
X1178099Y395596D03*
X1184859Y399496D03*
X1181479Y393647D03*
X1188239Y389747D03*
Y385847D03*
X1167960Y401447D03*
X1198379Y372197D03*
X1194999Y370247D03*
Y362447D03*
X1201759Y358547D03*
X1198379Y352696D03*
X1178099Y399496D03*
X1181479Y397546D03*
X1184859Y395596D03*
Y391696D03*
Y387796D03*
X1191619Y383896D03*
X1194999Y381947D03*
X1198379Y379996D03*
X1276346Y-10250D03*
X1270350Y98300D03*
X1275470Y99390D03*
X1295581Y94320D03*
X1301219Y89141D03*
X1301770Y101300D03*
X1269810Y154398D03*
X1233902Y173337D03*
X1241381Y172040D03*
X1246655Y176395D03*
X1310098Y150040D03*
X1287790Y156575D03*
X1299907Y159808D03*
X1295500Y159970D03*
X1305171Y164767D03*
X1278573Y519596D03*
X1255120Y612634D03*
X1287770Y501897D03*
X1318054Y460507D03*
X1304200Y462030D03*
X1380900Y383164D03*
X1377492Y516892D03*
X1369757Y517465D03*
X1495325Y424834D03*
X1497275Y428214D03*
X1482000Y426595D03*
Y422658D03*
Y418720D03*
X1499225Y424834D03*
X1489475Y428214D03*
X1491400Y424600D03*
X1487500D03*
X1526525Y404554D03*
X1534325D03*
X1538225D03*
X1542125D03*
X1569425Y411314D03*
X1563575Y407934D03*
X1551875D03*
X1559675D03*
X1565525Y411314D03*
X1611935Y429515D03*
X1617900Y409900D03*
X1595200Y412700D03*
X1520675Y457066D03*
X1503125Y453786D03*
X1516775Y457066D03*
X1482000Y406909D03*
X1485250Y408017D03*
X1557725Y453686D03*
X1569425D03*
X1553825D03*
X1582200Y456200D03*
X1587550Y456550D03*
X1557725Y424834D03*
X1567475Y421454D03*
X1551875Y428214D03*
X1551990Y421158D03*
X1561625Y424834D03*
X1569425D03*
X1555775Y443546D03*
X1559675D03*
X1557725Y446926D03*
X1561625D03*
X1553825Y440166D03*
Y446926D03*
X1587573Y445300D03*
X1571375Y443546D03*
X1530425Y460446D03*
X1569425D03*
X1571390Y464480D03*
X1551875Y463826D03*
X1534325Y460446D03*
X1555775Y463826D03*
X1561625Y460446D03*
X1538225D03*
X1549925D03*
X1569425Y473966D03*
X1571375Y470586D03*
X1567475D03*
X1557725Y473966D03*
X1555775Y470586D03*
X1563575Y477346D03*
X1890974Y105600D03*
X1872254Y138618D03*
X1856874Y219443D03*
X1877517Y217988D03*
G54D243*
X16117Y-43892D03*
X1926693Y646063D03*
G54D275*
X1773347Y528523D03*
G54D267*
X762616Y270113D03*
X756114Y316209D03*
X762842Y302434D03*
X765730Y335064D03*
X758952Y384100D03*
G54D273*
X1311869Y153148D03*
X1320869D03*
G54D262*
X224409Y301378D03*
X874016D03*
X1251969Y214764D03*
G54D265*
X637793Y69778D03*
Y50878D03*
Y532955D03*
Y514079D03*
Y570755D03*
Y589679D03*
Y551879D03*
Y608555D03*
X1287403Y-5822D03*
Y31978D03*
Y13078D03*
Y69778D03*
Y88678D03*
Y50878D03*
Y514079D03*
Y532955D03*
G54D247*
X-7874Y325315D03*
G54D254*
X576200Y649750D03*
G54D244*
X-3937Y-43307D03*
X1956693D03*
X-3937Y646063D03*
X1956693D03*
G54D252*
X388050Y649750D03*
G54D261*
X88000Y310500D03*
X90000D03*
X86500Y314000D03*
Y316500D03*
X88500D03*
X193100Y231098D03*
X196100D03*
X193100Y250098D03*
X196100D03*
X248000Y259600D03*
X193100Y281250D03*
X196100D03*
X193100Y310250D03*
X196100D03*
X193100Y342980D03*
X196100D03*
X193100Y370850D03*
X196100D03*
X194200Y387300D03*
X196200D03*
X193100Y361850D03*
X196100D03*
X319692Y34050D03*
Y30150D03*
X346250Y34050D03*
Y30150D03*
X331892Y34050D03*
Y11700D03*
X344892D03*
X346250D03*
X331892Y14700D03*
X344892D03*
X346250D03*
X319692Y67950D03*
Y71850D03*
X331892D03*
X346250D03*
Y67950D03*
X369642Y29850D03*
Y33750D03*
X368308Y49242D03*
X331892Y49500D03*
X344892D03*
X346250D03*
X368308Y52242D03*
X331892Y52500D03*
X344892D03*
X346250D03*
X368842Y67450D03*
Y71350D03*
X316042Y105150D03*
X314742Y107550D03*
X316042Y109050D03*
X305942Y497550D03*
X316420Y492725D03*
X314942Y493650D03*
X316420Y496625D03*
X314942Y497550D03*
X319692Y531150D03*
Y535050D03*
X346250D03*
Y531150D03*
X331892Y535050D03*
X368120Y550320D03*
X331892Y550500D03*
X344892D03*
X346250D03*
X368120Y553320D03*
X331892Y553500D03*
X344892D03*
X346250D03*
X319692Y568950D03*
Y572850D03*
X346250D03*
Y568950D03*
X331892Y572850D03*
X367340Y588180D03*
X331892Y588300D03*
X344892D03*
X346250D03*
X367340Y591180D03*
X331892Y591300D03*
X344892D03*
X346250D03*
X422900Y34050D03*
Y30150D03*
X397450Y34050D03*
X409900Y30150D03*
Y34050D03*
X368292Y11578D03*
Y14578D03*
X422900Y71850D03*
Y67950D03*
X397450Y71850D03*
X409900D03*
Y67950D03*
X438300Y111760D03*
X452648Y297341D03*
X455648D03*
X376330Y499720D03*
X397450Y572850D03*
X409900D03*
Y568950D03*
X422900Y572850D03*
Y568950D03*
X436758Y535050D03*
X422900D03*
X409900D03*
X422900Y531150D03*
X409900D03*
X436758D03*
X368212Y530850D03*
Y534750D03*
X368232Y568510D03*
Y572410D03*
X422900Y588300D03*
Y591300D03*
X435258Y30150D03*
Y67950D03*
X447300Y111760D03*
X452648Y281091D03*
Y290091D03*
X455648D03*
X452648Y306341D03*
X435258Y568950D03*
X607250Y-8200D03*
X609250D03*
X607250Y-5200D03*
X609250D03*
X606250Y30500D03*
X609250D03*
X606250Y33500D03*
X609250D03*
X606250Y68500D03*
X609250D03*
X606250Y71500D03*
X609250D03*
X607242Y610878D03*
X608142Y531478D03*
X609642D03*
X608142Y534478D03*
X609642D03*
X608142Y569278D03*
X609642D03*
X608142Y572278D03*
X609642D03*
X607242Y607878D03*
X608742D03*
Y610878D03*
X663750Y12100D03*
Y15100D03*
Y17000D03*
Y20000D03*
X666000Y287550D03*
X669000D03*
X663319Y576112D03*
Y579112D03*
X721635Y6702D03*
X724635D03*
X727835D03*
X730835D03*
X713450Y10300D03*
X716450D03*
X672750Y12100D03*
Y15100D03*
Y17000D03*
Y20000D03*
X675800Y20356D03*
Y23356D03*
X724635Y-2298D03*
X727835D03*
X730835D03*
X672319Y576112D03*
X710601Y595512D03*
X713601D03*
X715703Y595752D03*
X843000Y278750D03*
X846000D03*
X843000Y310450D03*
X846000D03*
X843000Y342000D03*
X846000D03*
X843000Y364550D03*
X846000D03*
X843000Y373550D03*
X846000D03*
X969300Y30150D03*
Y34050D03*
X981500Y11700D03*
X994500D03*
X995858D03*
X981500Y14700D03*
X994500D03*
X995858D03*
X1019250Y29850D03*
Y33750D03*
X1018050Y49000D03*
X981500Y49500D03*
X994500D03*
X995858D03*
X1018050Y52000D03*
X981500Y52500D03*
X994500D03*
X995858D03*
X1019250Y67450D03*
Y71350D03*
X969300Y67950D03*
Y71850D03*
X965650Y105150D03*
X964350Y107550D03*
X1016050Y494650D03*
Y498550D03*
X964550Y496265D03*
X966028D03*
X1018350Y550400D03*
X981500Y550500D03*
X994500D03*
X995858D03*
X1018350Y553400D03*
X981500Y553500D03*
X994500D03*
X995858D03*
X981500Y588300D03*
X994500D03*
X995858D03*
X981500Y591300D03*
X994500D03*
X995858D03*
X969300Y531150D03*
Y535050D03*
Y568950D03*
Y572850D03*
X995858Y34050D03*
Y30150D03*
X981500Y34050D03*
X995858Y71850D03*
Y67950D03*
X981500Y71850D03*
X1028050Y102150D03*
X1102256Y290091D03*
X1105256D03*
X1102256Y297341D03*
X1105256D03*
X1025050Y494650D03*
Y498550D03*
X1017050Y588200D03*
Y591200D03*
X1018750Y530850D03*
Y534750D03*
X981500Y535050D03*
X995858D03*
Y531150D03*
X1018300Y568450D03*
Y572350D03*
X995858Y572850D03*
Y568950D03*
X981500Y572850D03*
X1047058Y34050D03*
X1059508D03*
Y30150D03*
X1072508Y34050D03*
Y30150D03*
X1084866D03*
X1047058Y71850D03*
X1059508D03*
Y67950D03*
X1072508Y71850D03*
Y67950D03*
X1084866D03*
X1096650Y109450D03*
X1087650D03*
X1102256Y281091D03*
X1088538Y492910D03*
Y496810D03*
X1072508Y588300D03*
Y591300D03*
X1047058Y572850D03*
X1059508D03*
Y568950D03*
X1072508Y572850D03*
Y568950D03*
X1084866D03*
X1047058Y553500D03*
X1086366Y535050D03*
X1072508D03*
X1059508D03*
X1072508Y531150D03*
X1059508D03*
X1086366D03*
X1102256Y306341D03*
X1256858Y-8200D03*
X1258858D03*
X1256858Y-5200D03*
X1258858D03*
X1255858Y30500D03*
X1258858D03*
X1255858Y33500D03*
X1258858D03*
X1255858Y68500D03*
X1258858D03*
X1255858Y71500D03*
X1258858D03*
X1311869Y157617D03*
X1263700Y487643D03*
X1265700D03*
X1255858Y531500D03*
X1258858D03*
X1255858Y534500D03*
X1258858D03*
X1255858Y569500D03*
X1258858D03*
Y572500D03*
X1255624Y607956D03*
X1259250Y608000D03*
Y611000D03*
X1330250Y45500D03*
X1320869Y148679D03*
Y157617D03*
X1303000Y611750D03*
X1306000D03*
X1464600Y409400D03*
Y411400D03*
Y414400D03*
X1442297Y403785D03*
X1445250Y406500D03*
Y411500D03*
X1451297Y400785D03*
Y403785D03*
X1455600Y406400D03*
X1454250Y406500D03*
X1455600Y409400D03*
X1454250Y409500D03*
X1455600Y411400D03*
X1454250Y411500D03*
X1455600Y414400D03*
X1454250Y414500D03*
X1514850Y431000D03*
X1516850Y431100D03*
X1529600Y433850D03*
X1514850Y434000D03*
X1516850Y434100D03*
X1461050Y525300D03*
X1463250Y514250D03*
X1466950D03*
X1575020Y554250D03*
X1570084Y554259D03*
X1573084D03*
X1466950Y523650D03*
X1459000Y542000D03*
X1466850Y539700D03*
X1500900Y543250D03*
X1502800D03*
X1505800D03*
X1508100D03*
X1511100D03*
X1513100D03*
X1516100D03*
X1474000Y545500D03*
X1476000D03*
X1573800Y406600D03*
X1576800D03*
X1578500D03*
X1602500Y410500D03*
X1605500D03*
X1589100Y415000D03*
X1592100D03*
X1593800D03*
X1596800D03*
X1598500D03*
X1543885Y432380D03*
X1497900Y534250D03*
X1500900D03*
X1502800D03*
X1505800D03*
X1508100D03*
X1511100D03*
X1513100D03*
X1516100D03*
X1481450Y525700D03*
X1490450D03*
X1496150Y527050D03*
X1499850D03*
X1575020Y563250D03*
X1578020D03*
X1570084Y563259D03*
X1573084D03*
X1489550Y539750D03*
X1489950Y541200D03*
X1586364Y114799D03*
X1581500Y397600D03*
X1578500D03*
X1576800D03*
X1592100Y424000D03*
X1593800D03*
X1596800D03*
X1598500D03*
X1578314Y432264D03*
X1581314D03*
X1574000Y432750D03*
X1577000D03*
X1594000Y458000D03*
X1592000D03*
X1578314Y441264D03*
X1581314D03*
X1609050Y485200D03*
Y488200D03*
X1609450Y489650D03*
X1597000Y467000D03*
X1594000D03*
X1592000D03*
X1589000D03*
X1606500Y462796D03*
X1618549Y97038D03*
X1617000Y92500D03*
X1615599Y92038D03*
X1633849Y157938D03*
X1599250Y370448D03*
Y368748D03*
X1618050Y488200D03*
X1625500Y512700D03*
Y511000D03*
X1616500Y512700D03*
Y511000D03*
X1613150Y499050D03*
X1609450D03*
X1604950Y472850D03*
X1606500Y471796D03*
X1836613Y144948D03*
X1845100Y156450D03*
X1896650Y162000D03*
X1910600Y163650D03*
X1913600D03*
X1896650Y165000D03*
X1915350Y165900D03*
Y168900D03*
X1897900Y177100D03*
X1914763Y177968D03*
X1897900Y180100D03*
X1914763Y180968D03*
Y182968D03*
X1909000Y184000D03*
X1912000D03*
X1914763Y185968D03*
Y187968D03*
X1896637Y112502D03*
X1891939Y136217D03*
Y139217D03*
X1867990Y105730D03*
X1893637Y103502D03*
X1867990Y114730D03*
X1882939Y139217D03*
X1880000Y135250D03*
X1876500D03*
X1845613Y141948D03*
Y144948D03*
G54D256*
X1203800Y649750D03*
G54D255*
X942600D03*
G54D257*
X1256850D03*
G54D258*
X1518450D03*
G54D246*
X-7874Y216181D03*
G54D253*
X440050Y649750D03*
G54D251*
X253700D03*
%LPD*%
G75*
G36*
G01X197600Y269100D02*
X191500D01*
X190700Y269900D01*
Y274900D01*
X191500Y275700D01*
X197700D01*
X198400Y275000D01*
Y269900D01*
X197600Y269100D01*
G37*
G36*
G01X191332Y236600D02*
X190432Y237500D01*
Y243700D01*
X191332Y244600D01*
X193098D01*
Y244596D01*
X196102D01*
Y244600D01*
X197700D01*
X198700Y243600D01*
Y237400D01*
X197900Y236600D01*
X191332D01*
G37*
G36*
G01X197600Y330830D02*
X191500D01*
X190700Y331630D01*
Y336630D01*
X191500Y337430D01*
X197700D01*
X198400Y336730D01*
Y331630D01*
X197600Y330830D01*
G37*
G36*
G01Y298100D02*
X191500D01*
X190700Y298900D01*
Y303900D01*
X191500Y304700D01*
X197700D01*
X198400Y304000D01*
Y298900D01*
X197600Y298100D01*
G37*
G36*
G01X191900Y377200D02*
X191100Y378000D01*
Y383000D01*
X191900Y383800D01*
X194198D01*
Y383798D01*
X196202D01*
Y383800D01*
X198100D01*
X198800Y383100D01*
Y378000D01*
X198000Y377200D01*
X191900D01*
G37*
G36*
G01X415520Y105800D02*
G03I-700J0D01*
G37*
G36*
G01X408826Y105750D02*
G03I-700J0D01*
G37*
G36*
G01X402075Y105800D02*
G03I-700J0D01*
G37*
G36*
G01X422203D02*
G03I-700J0D01*
G37*
G36*
G01X428396D02*
G03I-700J0D01*
G37*
G36*
G01X653900Y306200D02*
X652000Y308100D01*
Y315498D01*
X652002D01*
Y317502D01*
X652000D01*
Y319498D01*
X652002D01*
Y321502D01*
X652000D01*
Y332498D01*
X652002D01*
Y334502D01*
X652300Y334800D01*
X661800D01*
X663000Y333600D01*
X667498D01*
Y333498D01*
X669502D01*
Y333600D01*
X678800D01*
X679700Y334500D01*
X681500D01*
X681950Y334050D01*
Y308150D01*
X680000Y306200D01*
X653900D01*
G37*
G36*
G01X847700Y266700D02*
X842500D01*
X841600Y267600D01*
Y272200D01*
X842400Y273000D01*
X847200D01*
X848600Y271600D01*
Y267600D01*
X847700Y266700D01*
G37*
G36*
G01X842868Y237984D02*
G03X842532Y239287I-1468J316D01*
G02Y239813I302J263D01*
G03Y241787I-1132J987D01*
G02Y242313I302J263D01*
G03X842900Y243379I-1132J987D01*
G02X843299Y243800I399J21D01*
G01X847200D01*
X848600Y242400D01*
Y238400D01*
X847700Y237500D01*
X843259D01*
G02X842868Y237984I0J400D01*
G37*
G36*
G01X847700Y330000D02*
X842500D01*
X841600Y330900D01*
Y335500D01*
X842400Y336300D01*
X847200D01*
X848600Y334900D01*
Y330900D01*
X847700Y330000D01*
G37*
G36*
G01Y298400D02*
X842500D01*
X841600Y299300D01*
Y303900D01*
X842400Y304700D01*
X847200D01*
X848600Y303300D01*
Y299300D01*
X847700Y298400D01*
G37*
G36*
G01X1051683Y105800D02*
G03I-700J0D01*
G37*
G36*
G01X1058434Y105750D02*
G03I-700J0D01*
G37*
G36*
G01X1065128Y105800D02*
G03I-700J0D01*
G37*
G36*
G01X1071811D02*
G03I-700J0D01*
G37*
G36*
G01X1078004D02*
G03I-700J0D01*
G37*
G36*
G01X1628177Y130300D02*
X1627153Y131324D01*
Y134598D01*
X1625775Y135976D01*
Y138490D01*
X1626230Y138945D01*
X1629460D01*
X1631261Y137144D01*
Y136704D01*
X1631357Y136608D01*
X1634369D01*
X1634449Y136688D01*
Y137471D01*
X1635453Y138475D01*
X1639807D01*
X1640954Y139622D01*
X1642759D01*
X1642852Y139528D01*
Y137382D01*
X1642236Y136765D01*
X1641470D01*
X1640901Y136196D01*
Y133070D01*
X1641712Y132259D01*
X1642160D01*
X1642288Y132131D01*
Y130376D01*
X1642212Y130300D01*
X1628177D01*
G37*
%LPC*%
G75*
G54D272*
X846000Y240730D03*
G54D263*
X193100Y240598D03*
X196100D03*
G54D261*
X193100Y272250D03*
X196100D03*
X193100Y333980D03*
X196100D03*
X193100Y301250D03*
X196100D03*
X843000Y269750D03*
X846000D03*
X843000Y333000D03*
X846000D03*
X843000Y301450D03*
X846000D03*
X1634349Y133138D03*
X1631349D03*
%LPD*%
G75*
G54D100*
X634044Y184570D03*
G54D200*
X1887327Y532541D03*
X1929453Y511202D03*
G54D101*
X638108Y385368D03*
G54D110*
X1224391Y365477D03*
G54D120*
X1354650Y340363D03*
Y338788D03*
Y337213D03*
Y351387D03*
Y349812D03*
Y348237D03*
Y346662D03*
Y345087D03*
Y343513D03*
Y341938D03*
G54D210*
X1906500Y214650D03*
Y223650D03*
G54D111*
X1238475Y360530D03*
G54D102*
X634137Y404629D03*
G54D201*
X1851250Y584622D03*
Y576748D03*
Y568874D03*
G54D121*
X1357213Y334650D03*
X1358788D03*
X1360363D03*
X1361938D03*
X1363513D03*
X1365087D03*
X1366662D03*
X1368237D03*
X1369812D03*
X1371387D03*
G54D130*
X1457000Y101300D03*
X1474100Y234400D03*
X1585849Y105088D03*
X1582849Y96088D03*
X1825700Y26300D03*
X1938600Y455317D03*
G54D220*
X1969883Y207007D03*
Y242441D03*
G54D103*
X671371Y193310D03*
G54D211*
X1952250Y240355D03*
G54D202*
X1851250Y561000D03*
G54D112*
X1246438Y366646D03*
G54D10*
G01X1091141Y35957D02*
X1091260Y36076D01*
X-17936Y-49379D03*
Y-53779D03*
Y-44979D03*
Y-40579D03*
X-18079Y-35764D03*
Y-58764D03*
X-14186Y196989D03*
Y199989D03*
X-14839Y445588D03*
X-14753Y448601D03*
X-17179Y643156D03*
X-17194Y638753D03*
X-17179Y647556D03*
Y660756D03*
Y651956D03*
Y656356D03*
X-13636Y-40479D03*
Y-44879D03*
Y-53679D03*
X-9079Y-50164D03*
X-4679D03*
X-279D03*
X-9079Y-54264D03*
X-4679D03*
X-279D03*
X22964Y-40379D03*
Y-44779D03*
Y-53579D03*
Y-49179D03*
X18964Y-53579D03*
Y-49179D03*
X13964Y-53579D03*
Y-49179D03*
X8964Y-40379D03*
Y-44779D03*
Y-53579D03*
Y-49179D03*
X3964Y-40379D03*
Y-44779D03*
Y-53579D03*
Y-49179D03*
X25921Y-35764D03*
X30321D03*
X43521D03*
X39121D03*
X34721D03*
X8321D03*
X12721D03*
X21521D03*
X17121D03*
X-13679D03*
X-9279D03*
X3921D03*
X-4879D03*
X-479D03*
X17121Y-58764D03*
X21521D03*
X12721D03*
X8321D03*
X34721D03*
X39121D03*
X43521D03*
X30321D03*
X25921D03*
X-479D03*
X-13679D03*
X-4879D03*
X3921D03*
X-13636Y-49279D03*
X-9279Y-58764D03*
X875Y211336D03*
X6074Y211293D03*
X3474Y211263D03*
X875Y208352D03*
X36200Y208600D03*
X33200D03*
X20700D03*
X17700Y211600D03*
X20700D03*
X17700Y208600D03*
X23700Y211600D03*
Y208600D03*
X33200Y211600D03*
X30200D03*
Y208600D03*
X36200Y211600D03*
X6074Y208321D03*
X3474Y208263D03*
X5500Y218500D03*
X-5300Y200191D03*
X-7900D03*
X-2700Y200202D03*
X-11586Y196989D03*
Y199989D03*
X-2600Y232300D03*
X-5246Y232351D03*
X-7846D03*
X20500Y221000D03*
Y224000D03*
X17500Y221000D03*
Y224000D03*
X23500D03*
Y221000D03*
X33300Y224000D03*
Y221000D03*
X30300D03*
Y224000D03*
X36300D03*
Y221000D03*
X-14129Y235221D03*
X-11484Y235215D03*
Y232215D03*
X-14084D03*
X2678Y221018D03*
X5277Y221110D03*
X5173Y224042D03*
X2574Y223963D03*
X-26Y223982D03*
X19800Y257900D03*
X28868Y457576D03*
Y454576D03*
X28988Y460876D03*
X23718Y460866D03*
X26318D03*
X21118D03*
X20998Y457566D03*
Y454566D03*
X23598D03*
X26198D03*
Y457566D03*
X23598D03*
X8343Y446875D03*
X1108Y455879D03*
X5743Y446875D03*
Y444275D03*
X-261Y450873D03*
X-11652Y445530D03*
Y448530D03*
X-261Y453473D03*
X2339Y448273D03*
Y450873D03*
Y453473D03*
X-261Y445673D03*
X2339D03*
X-261Y448273D03*
X22421Y647556D03*
X26821D03*
X31221D03*
X18021D03*
Y643156D03*
X31221D03*
X26821D03*
X22421D03*
X18006Y638753D03*
X9221Y647556D03*
X13621D03*
Y643156D03*
X9221D03*
X4821D03*
Y647556D03*
X22406Y638753D03*
X26806D03*
X31206D03*
X-12794D03*
X-12779Y647556D03*
Y643156D03*
X40006Y638753D03*
X44406D03*
X35606D03*
X35621Y647556D03*
Y643156D03*
X-9599Y610630D03*
X-3301Y619643D03*
Y601615D03*
X4549Y620682D03*
X4548Y600577D03*
X13801Y624130D03*
Y597130D03*
X23360Y620172D03*
X23352Y601079D03*
X27301Y610630D03*
X18021Y660756D03*
X35621Y656356D03*
X26821Y660756D03*
X18021Y651956D03*
X31221D03*
X22421Y660756D03*
X26821Y651956D03*
X22421D03*
X4821D03*
X13621D03*
X9221D03*
X-8379Y660756D03*
X4821Y656356D03*
X9221D03*
X13621D03*
X-3979D03*
X421D03*
X13621Y660756D03*
X-3979D03*
X421D03*
X4821D03*
X-12779Y651956D03*
X22421Y656356D03*
X26821D03*
X31221D03*
X18021D03*
X-8379D03*
X-12779D03*
X31221Y660756D03*
X35621Y651956D03*
Y660756D03*
X44421D03*
X40021D03*
X-12779D03*
X9221D03*
X107921Y-58764D03*
X102921D03*
X97921D03*
X92921D03*
X87921D03*
X82921D03*
X77921D03*
X72921D03*
X67921D03*
X62921D03*
X57921D03*
X52921D03*
X47921Y-35764D03*
Y-58764D03*
X107921Y-35764D03*
X102921D03*
X97921D03*
X92921D03*
X87921D03*
X82921D03*
X77921D03*
X72921D03*
X67921D03*
X62921D03*
X57921D03*
X52921D03*
X91536Y78481D03*
X95041Y78451D03*
X98633Y78481D03*
X96249Y204722D03*
X64700Y210100D03*
Y212800D03*
X64778Y218062D03*
X58000Y206500D03*
X50500Y205696D03*
X56900Y197800D03*
X93870Y199131D03*
X97730Y188584D03*
X108174Y164127D03*
X58200Y230400D03*
Y233400D03*
X55600Y230400D03*
X53000Y230300D03*
Y233300D03*
X55600Y233400D03*
X58200Y227400D03*
X53000Y227300D03*
X55600Y227400D03*
X58200Y239400D03*
X99000Y230450D03*
Y227450D03*
Y233450D03*
X93800Y236450D03*
X96400D03*
Y230450D03*
Y227450D03*
X93800D03*
Y230450D03*
X96400Y233450D03*
X93800D03*
X99000Y236450D03*
X91200Y227450D03*
Y230450D03*
Y236450D03*
Y233450D03*
X88600D03*
Y236450D03*
Y230450D03*
Y227450D03*
X53000Y239300D03*
X55600Y239400D03*
X58200Y236400D03*
X55600D03*
X53000Y236300D03*
X71500Y263300D03*
X68800D03*
X53004Y244632D03*
X55275Y245900D03*
X57875D03*
X57457Y248537D03*
Y251237D03*
X88200Y250400D03*
Y247400D03*
Y244400D03*
Y253400D03*
Y256300D03*
Y258900D03*
X57444Y257456D03*
X57600Y262800D03*
X57500Y260200D03*
X62800Y265500D03*
X71500Y266000D03*
X65500Y265500D03*
X68800Y266000D03*
X60000Y265500D03*
X90800Y244400D03*
Y250400D03*
Y247400D03*
X98600Y250400D03*
Y247400D03*
Y244400D03*
X93400Y250400D03*
Y247400D03*
Y244400D03*
X96000D03*
Y250400D03*
Y247400D03*
X90800Y253400D03*
Y256300D03*
Y258900D03*
X93400Y253400D03*
X96000D03*
X98600D03*
X96000Y258900D03*
X93400D03*
Y256300D03*
X96000D03*
X98600D03*
Y258900D03*
X76540Y397355D03*
X81900Y398300D03*
X79140Y397355D03*
X103700Y397200D03*
X106400D03*
X101000D03*
X109100D03*
Y399900D03*
X101000D03*
X106400D03*
X103700D03*
X98149Y399769D03*
X102456Y393756D03*
X76052Y420935D03*
X78000Y423100D03*
X80100Y425000D03*
X81500Y427400D03*
X79700Y409700D03*
X77400Y407800D03*
X81500Y412100D03*
X84913Y434471D03*
X87013Y436371D03*
X104517Y406279D03*
X105761Y409208D03*
X108010Y411479D03*
X107571Y406291D03*
X93040Y496810D03*
X92990Y494210D03*
X93040Y499410D03*
X98240Y496810D03*
X95640D03*
X98240Y499410D03*
X95640D03*
X87790Y494210D03*
X90390D03*
X90440Y496810D03*
X87840D03*
X90390Y491610D03*
X87790D03*
X90440Y499410D03*
X87840D03*
X95777Y494213D03*
X48806Y638753D03*
X75206D03*
X106006D03*
X70806D03*
X53206D03*
X66406D03*
X92806D03*
X97206D03*
X101606D03*
X57606D03*
X62006D03*
X79606D03*
X84006D03*
X88406D03*
X53221Y660756D03*
X101621D03*
X97221D03*
X92821D03*
X106021D03*
X48821D03*
X70821D03*
X66421D03*
X62021D03*
X57621D03*
X75221D03*
X88421D03*
X84021D03*
X79621D03*
X167921Y-58764D03*
X162921D03*
X157921D03*
X152921D03*
X147921D03*
X142921D03*
X137921D03*
X132921D03*
X127921D03*
X122921D03*
X117921D03*
X112921D03*
X162921Y-35764D03*
X157921D03*
X152921D03*
X147921D03*
X142921D03*
X137921D03*
X132921D03*
X127921D03*
X122921D03*
X117921D03*
X112921D03*
X167921D03*
X166000Y212900D03*
X168600D03*
X164300Y207870D03*
X160800Y212900D03*
X163400D03*
X157800Y207300D03*
X161216Y209533D03*
Y206933D03*
X154500Y205500D03*
X150600Y212900D03*
X151000Y205500D03*
X140889Y211972D03*
X137615Y212039D03*
X143900Y204600D03*
X147500Y205500D03*
X137300Y204500D03*
X140200Y204400D03*
X153200Y212900D03*
X122044Y162340D03*
X123624Y164600D03*
X139815Y268974D03*
X137900Y272800D03*
X139800Y237000D03*
X165825Y239543D03*
X168425Y236943D03*
Y239543D03*
X165825Y236943D03*
X163225D03*
X152825D03*
X145025D03*
X147625D03*
X150225D03*
X142425D03*
X122231Y234716D03*
X125564Y237816D03*
X122632D03*
X163225Y239543D03*
X158025Y236943D03*
X155425D03*
X160625D03*
X142371Y244384D03*
X122231Y266716D03*
X122531Y269816D03*
X125463D03*
X142466Y268982D03*
X142700Y276200D03*
X136729Y276386D03*
X139683Y276174D03*
X163225Y242143D03*
X168425Y244743D03*
X165825D03*
X163225D03*
X168425Y242143D03*
X165825D03*
X150700Y276800D03*
X169150Y259470D03*
Y255470D03*
X157633Y268727D03*
X162833D03*
X160233D03*
X165433D03*
X168033Y271327D03*
X162833Y276527D03*
Y273927D03*
Y271327D03*
X165433Y276527D03*
Y273927D03*
Y271327D03*
X159983Y276507D03*
X168033Y276527D03*
Y273927D03*
Y268727D03*
X153300Y276800D03*
X139866Y333016D03*
X160233Y306257D03*
Y308857D03*
Y303657D03*
X157518Y335391D03*
X157745Y332800D03*
X139900Y302400D03*
X142433Y301057D03*
X147633D03*
X150233D03*
X145033D03*
X125500Y333500D03*
X122231Y330716D03*
X122731Y333916D03*
X145200Y341300D03*
X148200D03*
X142465Y332940D03*
X152833Y301057D03*
X163233Y306257D03*
Y308857D03*
X168433Y306257D03*
Y308857D03*
Y301057D03*
X165833D03*
X163233D03*
X160633D03*
X158033D03*
X155433D03*
X169150Y287600D03*
Y291600D03*
X165833Y306257D03*
X163233Y303657D03*
X168433D03*
X165833D03*
Y308857D03*
X151000Y341300D03*
X169150Y323600D03*
Y319600D03*
X160501Y332965D03*
X160274Y335556D03*
X165701Y338165D03*
Y335565D03*
X163101Y332965D03*
X168301D03*
X165701D03*
X163101Y335565D03*
X168301Y340765D03*
Y338165D03*
Y335565D03*
X163101Y338165D03*
Y340765D03*
X165701D03*
X154200Y341100D03*
X125663Y301716D03*
X122231Y298716D03*
X122731Y301716D03*
X139767Y364883D03*
X147833Y364457D03*
X125600Y364900D03*
X122600Y365500D03*
X122331Y362716D03*
X142421Y364908D03*
X145033Y364457D03*
X142863Y402829D03*
X140219Y402894D03*
X137619Y402900D03*
X134992D03*
X142818Y400163D03*
X143073Y397194D03*
X140475Y397310D03*
X140218Y400163D03*
X137529Y400296D03*
X134929D03*
X114084Y399937D03*
X122840Y400827D03*
X111561Y398819D03*
X122000Y397600D03*
X125300Y397700D03*
X122231Y394716D03*
X150633Y364457D03*
X167433Y369657D03*
X169150Y355600D03*
Y351600D03*
X167700Y363900D03*
X161833Y364457D03*
X164633D03*
X159033D03*
X156233D03*
X153433D03*
X164633Y369657D03*
X161833D03*
X161933Y372357D03*
X164733D03*
X167533D03*
X166340Y374785D03*
X167670Y383993D03*
Y387993D03*
X130613Y429647D03*
X123648Y425041D03*
X125328Y427269D03*
X127932Y428571D03*
X110519Y410307D03*
X110199Y413852D03*
X110406Y638753D03*
X145606D03*
X141206D03*
X136806D03*
X132406D03*
X158806D03*
X119206D03*
X123606D03*
X114806D03*
X128006D03*
X163206D03*
X154406D03*
X167606D03*
X150006D03*
X132421Y660756D03*
X145621D03*
X141221D03*
X136821D03*
X123621D03*
X114821D03*
X128021D03*
X110421D03*
X119221D03*
X150021D03*
X167621D03*
X163221D03*
X158821D03*
X154421D03*
X182921Y-58764D03*
X177921D03*
X172921D03*
X227921Y-35764D03*
X222921D03*
X217921D03*
X212921D03*
X207921D03*
X202921D03*
X197921D03*
X192921D03*
X187921D03*
X182921D03*
X177921D03*
X227921Y-58764D03*
X222921D03*
X217921D03*
X212921D03*
X207921D03*
X202921D03*
X197921D03*
X192921D03*
X187921D03*
X172921Y-35764D03*
X176300Y211900D03*
X182300Y216108D03*
X179300D03*
Y213208D03*
X176300Y217308D03*
Y214500D03*
X173300Y217700D03*
Y214800D03*
Y211900D03*
X176400Y234300D03*
X176508Y231609D03*
X179400Y234300D03*
X182400D03*
X176400Y239900D03*
X182400D03*
X179400D03*
X173400D03*
Y231400D03*
Y234300D03*
Y237000D03*
X176400D03*
X182400D03*
X179400D03*
X188200Y236800D03*
X188300Y234000D03*
X185250Y239850D03*
X204200Y249500D03*
X201100Y246500D03*
X198200Y249500D03*
Y246500D03*
X201200Y249500D03*
X203900Y246500D03*
X207200Y249500D03*
X185768Y270065D03*
X173835Y277804D03*
X198082Y277995D03*
X203847Y274933D03*
X203947Y277933D03*
X188510Y272666D03*
X176835Y277804D03*
X182935Y278204D03*
Y275604D03*
X191400Y278400D03*
X188475Y270065D03*
X185735Y275604D03*
X188600Y278300D03*
X188535Y275604D03*
X185735Y278204D03*
X195300Y229250D03*
X188100Y239800D03*
X185250Y234250D03*
Y236950D03*
X176835Y275204D03*
X185754Y272689D03*
X179835Y277804D03*
Y275204D03*
X195100Y252000D03*
X201200Y252500D03*
X198200D03*
X204200D03*
X207200D03*
X200947Y277933D03*
X200847Y274933D03*
X200947Y280933D03*
X173835Y275204D03*
X230800Y265200D03*
X224390Y258920D03*
X219500Y254500D03*
X190800Y295500D03*
X196956Y295583D03*
X193800Y295500D03*
X190665Y306877D03*
X198119Y339710D03*
X191792Y327743D03*
X197792Y327643D03*
X194792D03*
X184800Y295500D03*
X187956Y295583D03*
X181800Y295500D03*
X201177Y330728D03*
Y333728D03*
Y336728D03*
X201163Y339476D03*
Y342476D03*
X204177Y336728D03*
X204060Y342527D03*
X204163Y339476D03*
X188654Y330973D03*
Y327973D03*
X197684Y307227D03*
X200251Y306548D03*
X188630Y333923D03*
X190570Y309539D03*
X185630Y333923D03*
X172800Y295500D03*
Y298400D03*
X198182Y280995D03*
X178956Y295583D03*
X175800Y295500D03*
X187900Y306900D03*
X191300Y339800D03*
X172800Y304000D03*
X175800D03*
X178800D03*
X187800D03*
X181800D03*
X184800D03*
X172800Y301100D03*
X175800D03*
X178800D03*
X181800D03*
X187800D03*
X184800D03*
Y298400D03*
X181800D03*
X175800D03*
X178800D03*
X187800D03*
X185300Y336900D03*
X173300Y337000D03*
Y339900D03*
X188300D03*
Y336900D03*
X179300Y337000D03*
X176300Y339900D03*
X179300D03*
X182300D03*
Y337000D03*
X198223Y342430D03*
X176300Y337000D03*
X185300Y339900D03*
X224000Y330900D03*
X229100Y325900D03*
X219000Y335900D03*
X214000Y340900D03*
X197730Y309959D03*
X204060Y345527D03*
X191300Y343248D03*
X173300Y343448D03*
X188300Y343348D03*
X201045Y345449D03*
X198233Y345402D03*
X195233D03*
X176300Y343448D03*
X201045Y348449D03*
X198233Y348402D03*
Y351402D03*
X195233D03*
X173424Y359621D03*
X188424D03*
X188400Y369787D03*
X176400D03*
X179400Y366787D03*
Y369787D03*
X176400Y366787D03*
X173400Y369787D03*
Y366787D03*
X199900Y370400D03*
X182400Y366787D03*
Y369787D03*
X185400Y366787D03*
Y369787D03*
X188400Y366787D03*
X182424Y359621D03*
X185424D03*
X176424D03*
X179424D03*
X182300Y343448D03*
X173471Y363281D03*
X188471D03*
X182471D03*
X185471D03*
X176471D03*
X179471D03*
X174750Y386308D03*
Y383308D03*
X171158Y382768D03*
Y385768D03*
Y388768D03*
X187100Y394000D03*
X190100Y393000D03*
X197411Y374812D03*
X199754Y376090D03*
X174750Y389308D03*
X199900Y373400D03*
X179300Y343448D03*
X185300Y343348D03*
X211606Y638753D03*
X224806D03*
X220406D03*
X216006D03*
X189606D03*
X198406D03*
X202806D03*
X207206D03*
X176406D03*
X172006D03*
X185206D03*
X180806D03*
X194006D03*
X226500Y649900D03*
X229206Y638753D03*
X224821Y660756D03*
X220421D03*
X198421D03*
X211621D03*
X189621D03*
X202821D03*
X207221D03*
X194021D03*
X185221D03*
X172021D03*
X176421D03*
X180821D03*
X229221D03*
X216021D03*
X292921Y-35764D03*
X287921D03*
X282921D03*
X277921D03*
X272921D03*
X267921D03*
X262921D03*
X257921D03*
X252921D03*
X247921D03*
X242921D03*
X237921D03*
X232921D03*
X292921Y-58764D03*
X287921D03*
X282921D03*
X277921D03*
X272921D03*
X267921D03*
X262921D03*
X257921D03*
X252921D03*
X247921D03*
X242921D03*
X237921D03*
X232921D03*
X234501Y270392D03*
X234000Y320900D03*
X261125Y646784D03*
X251213D03*
X290806Y638753D03*
X268806D03*
X273206D03*
X277606D03*
X282006D03*
X260006D03*
X264406D03*
X255606D03*
X251206D03*
X286406D03*
X242406D03*
X246806D03*
X233606D03*
X238006D03*
X261125Y652784D03*
X251213D03*
X286421Y660756D03*
X268821D03*
X282021D03*
X273221D03*
X277621D03*
X264421D03*
X251221D03*
X255621D03*
X260021D03*
X246821D03*
X242421D03*
X238021D03*
X233621D03*
X290821D03*
X352921Y-58764D03*
Y-35764D03*
X347921Y-58764D03*
Y-35764D03*
X342921Y-58764D03*
Y-35764D03*
X337921Y-58764D03*
Y-35764D03*
X332921Y-58764D03*
Y-35764D03*
X327921Y-58764D03*
Y-35764D03*
X322921Y-58764D03*
Y-35764D03*
X317921Y-58764D03*
Y-35764D03*
X312921Y-58764D03*
X307921D03*
Y-35764D03*
X302921Y-58764D03*
Y-35764D03*
X297921D03*
Y-58764D03*
X312921Y-35764D03*
X330406Y638753D03*
X348006D03*
X326006D03*
X312806D03*
X317206D03*
X321606D03*
X352406D03*
X295206D03*
X299606D03*
X308406D03*
X304006D03*
X334806D03*
X339206D03*
X343606D03*
X312821Y660756D03*
X317221D03*
X308421D03*
X304021D03*
X352421D03*
X295221D03*
X326021D03*
X321621D03*
X339221D03*
X299621D03*
X334821D03*
X330421D03*
X343621D03*
X348021D03*
X392921Y-35764D03*
X387921Y-58764D03*
Y-35764D03*
X382921Y-58764D03*
Y-35764D03*
X377921Y-58764D03*
Y-35764D03*
X372921Y-58764D03*
Y-35764D03*
X367921Y-58764D03*
Y-35764D03*
X362921Y-58764D03*
Y-35764D03*
X357921Y-58764D03*
Y-35764D03*
X392921Y-58764D03*
X402921Y-35764D03*
X397921Y-58764D03*
Y-35764D03*
X412921Y-58764D03*
Y-35764D03*
X407921Y-58764D03*
Y-35764D03*
X402921Y-58764D03*
X404594Y264899D03*
X407594D03*
X411188D03*
X414188D03*
X417190D03*
X380885Y273876D03*
Y270876D03*
X382494Y278904D03*
X371094D03*
X378294D03*
X375294D03*
X368094D03*
X389694D03*
X392694D03*
X385945Y278480D03*
X407094Y278910D03*
X414207D03*
X411288D03*
X404094D03*
X400842Y278914D03*
X368094Y295904D03*
X371094D03*
X385494D03*
X375294D03*
X378294D03*
X382494D03*
X389694D03*
X392694D03*
X365693Y311893D03*
X385494Y309904D03*
X367914Y309910D03*
X371237Y309846D03*
X389502Y309910D03*
X389528Y292910D03*
X392694Y292904D03*
X368116Y293087D03*
X371094Y292904D03*
X373736Y293068D03*
X382625Y293207D03*
X378294Y292904D03*
X385494D03*
X392694Y309904D03*
X374994Y309910D03*
X382497D03*
X378577Y309795D03*
X366822Y324459D03*
X377894Y326777D03*
X378785Y329580D03*
X375223Y326798D03*
X369748Y326902D03*
X367121Y327057D03*
X372391Y326746D03*
X375848Y329512D03*
X391144Y324173D03*
X388394D03*
X385494D03*
X407094Y292904D03*
X396897Y293058D03*
X399894Y292904D03*
X404266Y293030D03*
X407094Y309904D03*
X396709Y309910D03*
X399894Y309904D03*
X404117Y309910D03*
X411294Y295904D03*
X414294D03*
X407094D03*
X404094D03*
X399894D03*
X396894D03*
Y324173D03*
X408894D03*
X411894D03*
X405894D03*
X414894D03*
X393894D03*
X402894D03*
X399894D03*
X389473Y646508D03*
X379561D03*
X383206Y638753D03*
X387606D03*
X392006D03*
X396406D03*
X400806D03*
X405206D03*
X409606D03*
X414006D03*
X370006D03*
X365606D03*
X374406D03*
X378806D03*
X356806D03*
X361206D03*
X379561Y652508D03*
X389473D03*
X374421Y660756D03*
X387621D03*
X383221D03*
X400821D03*
X396421D03*
X392021D03*
X405221D03*
X409621D03*
X414021D03*
X361221D03*
X365621D03*
X356821D03*
X370021D03*
X378821D03*
X477921Y-58764D03*
Y-35764D03*
X472921Y-58764D03*
Y-35764D03*
X467921Y-58764D03*
Y-35764D03*
X462921Y-58764D03*
Y-35764D03*
X457921Y-58764D03*
Y-35764D03*
X452921Y-58764D03*
Y-35764D03*
X447921Y-58764D03*
Y-35764D03*
X442921Y-58764D03*
Y-35764D03*
X437921Y-58764D03*
Y-35764D03*
X432921Y-58764D03*
X422921Y-35764D03*
X417921Y-58764D03*
Y-35764D03*
X432921D03*
X427921Y-58764D03*
Y-35764D03*
X422921Y-58764D03*
X425911Y264710D03*
X420188Y264899D03*
X423092Y264697D03*
X436519Y262232D03*
X436329Y264826D03*
X432643Y264508D03*
X418523Y278910D03*
X428694D03*
X432894D03*
X425694D03*
X435894Y278938D03*
X443094Y278904D03*
X440094D03*
X421523Y278944D03*
X451675Y291739D03*
X449148Y292841D03*
X446209Y292842D03*
X451816Y295904D03*
X435894D03*
X418494D03*
X443094D03*
X440094D03*
X446383Y295841D03*
X428694Y295904D03*
X432894D03*
X425694D03*
X421494D03*
X418494Y324173D03*
X451267Y324476D03*
X448694Y323949D03*
X421494Y324173D03*
X446094Y323904D03*
X425694Y324173D03*
X428694D03*
X432894D03*
X435894D03*
X455226Y291686D03*
X454922Y295841D03*
X438681Y646514D03*
X448593D03*
X466806Y638753D03*
X462406D03*
X475606D03*
X471206D03*
X418406D03*
X422806D03*
X427206D03*
X440406D03*
X436006D03*
X431606D03*
X449206D03*
X458006D03*
X453606D03*
X444806D03*
X448593Y652514D03*
X458021Y660756D03*
X449221D03*
X462421D03*
X466821D03*
X471221D03*
X418421D03*
X438681Y652514D03*
X475621Y660756D03*
X453621D03*
X422821D03*
X427221D03*
X440421D03*
X431621D03*
X436021D03*
X444821D03*
X537921Y-58764D03*
Y-35764D03*
X532921Y-58764D03*
Y-35764D03*
X527921Y-58764D03*
Y-35764D03*
X522921Y-58764D03*
Y-35764D03*
X517921Y-58764D03*
Y-35764D03*
X512921Y-58764D03*
Y-35764D03*
X507921Y-58764D03*
Y-35764D03*
X502921Y-58764D03*
Y-35764D03*
X497921Y-58764D03*
Y-35764D03*
X492921Y-58764D03*
Y-35764D03*
X487921Y-58764D03*
Y-35764D03*
X482921Y-58764D03*
Y-35764D03*
X480006Y638753D03*
X484406D03*
X488806D03*
X493206D03*
X497606D03*
X510806D03*
X537206D03*
X519606D03*
X524006D03*
X532806D03*
X528406D03*
X515206D03*
X502006D03*
X506406D03*
X524021Y660756D03*
X480021D03*
X484421D03*
X497621D03*
X493221D03*
X488821D03*
X519621D03*
X532821D03*
X537221D03*
X528421D03*
X515221D03*
X510821D03*
X506421D03*
X502021D03*
X597921Y-35764D03*
Y-58764D03*
X592921Y-35764D03*
Y-58764D03*
X587921Y-35764D03*
Y-58764D03*
X582921Y-35764D03*
Y-58764D03*
X577921Y-35764D03*
Y-58764D03*
X572921Y-35764D03*
Y-58764D03*
X567921Y-35764D03*
Y-58764D03*
X562921Y-35764D03*
Y-58764D03*
X557921Y-35764D03*
Y-58764D03*
X552921Y-35764D03*
Y-58764D03*
X547921D03*
Y-35764D03*
X542921Y-58764D03*
Y-35764D03*
X576941Y646238D03*
X567029D03*
X590006Y638753D03*
X572406D03*
X559206D03*
X568006D03*
X563606D03*
X550406D03*
X581206D03*
X585606D03*
X576806D03*
X598806D03*
X594406D03*
X601500Y649500D03*
X554806Y638753D03*
X541606D03*
X546006D03*
X576941Y652238D03*
X567029D03*
X559221Y660756D03*
X546021D03*
X554821D03*
X598821D03*
X572421D03*
X568021D03*
X563621D03*
X585621D03*
X541621D03*
X594421D03*
X576821D03*
X590021D03*
X581221D03*
X550421D03*
X637921Y-58764D03*
X632921Y-35764D03*
Y-58764D03*
X627921Y-35764D03*
Y-58764D03*
X622921Y-35764D03*
Y-58764D03*
X617921Y-35764D03*
Y-58764D03*
X612921Y-35764D03*
Y-58764D03*
X607921Y-35764D03*
Y-58764D03*
X602921Y-35764D03*
Y-58764D03*
X652921Y-35764D03*
Y-58764D03*
X647921Y-35764D03*
Y-58764D03*
X642921Y-35764D03*
Y-58764D03*
X637921Y-35764D03*
X662921D03*
Y-58764D03*
X657921Y-35764D03*
Y-58764D03*
X653750Y225500D03*
X641600Y221400D03*
Y226600D03*
Y224000D03*
Y229200D03*
X644500D03*
Y224000D03*
Y226600D03*
X641600Y231800D03*
X644500D03*
X650700Y224000D03*
X647600D03*
X650700Y226600D03*
X647600D03*
X650700Y231800D03*
X647600D03*
Y229200D03*
X650700D03*
X641541Y236028D03*
Y238628D03*
X637001Y227337D03*
Y222137D03*
Y224737D03*
Y229937D03*
X641541Y243828D03*
Y241228D03*
X628589Y463649D03*
X629359Y469583D03*
X632771Y473269D03*
X605176Y487581D03*
X641107Y471989D03*
X634033Y467638D03*
X638406Y638753D03*
X634006D03*
X642806D03*
X629606D03*
X616406D03*
X612006D03*
X603206D03*
X625206D03*
X651606D03*
X647206D03*
X660406D03*
X620806D03*
X656006D03*
X607606D03*
X607621Y660756D03*
X638421D03*
X647221D03*
X616421D03*
X634021D03*
X612021D03*
X620821D03*
X625221D03*
X629621D03*
X642821D03*
X603221D03*
X656021D03*
X660421D03*
X651621D03*
X692921Y-58764D03*
X687921Y-35764D03*
Y-58764D03*
X682921Y-35764D03*
Y-58764D03*
X677921Y-35764D03*
Y-58764D03*
X672921Y-35764D03*
Y-58764D03*
X667921Y-35764D03*
Y-58764D03*
X697921Y-35764D03*
Y-58764D03*
X692921Y-35764D03*
X722921D03*
Y-58764D03*
X717921Y-35764D03*
Y-58764D03*
X712921Y-35764D03*
Y-58764D03*
X707921Y-35764D03*
Y-58764D03*
X702921Y-35764D03*
Y-58764D03*
X704466Y-7874D03*
X690966Y-21374D03*
X700525Y1668D03*
X700517Y-17425D03*
X681713Y-17927D03*
X690966Y5626D03*
X681714Y2178D03*
X673864Y-16889D03*
X667566Y-7874D03*
X673864Y1139D03*
X706164Y390143D03*
X708975Y390174D03*
X711575Y390150D03*
Y393150D03*
X706164Y393143D03*
X708975Y393174D03*
X703160Y392939D03*
X700391Y389737D03*
X703160Y390139D03*
X700291Y392637D03*
X700458Y395503D03*
X703169Y395986D03*
X711575Y396150D03*
X708975Y396174D03*
X706164Y396143D03*
X705673Y387012D03*
Y384412D03*
X711173Y387012D03*
X708373D03*
Y384412D03*
X700204Y386610D03*
X702973Y387012D03*
X700204Y384010D03*
X702973Y384412D03*
X711173Y384312D03*
X695790Y351300D03*
X695606Y638753D03*
X673606D03*
X708806D03*
X704406D03*
X700006D03*
X722006D03*
X717606D03*
X713206D03*
X664806D03*
X669206D03*
X686806D03*
X682406D03*
X678006D03*
X691206D03*
X690966Y624130D03*
Y597130D03*
X700525Y620172D03*
X700517Y601079D03*
X704466Y610630D03*
X667566D03*
X673864Y619643D03*
Y601615D03*
X681714Y620682D03*
X681713Y600577D03*
X664821Y660756D03*
X695621D03*
X708821D03*
X700021D03*
X704421D03*
X669221D03*
X686821D03*
X691221D03*
X678021D03*
X673621D03*
X682421D03*
X722021D03*
X717621D03*
X713221D03*
X777921Y-58764D03*
X772921Y-35764D03*
Y-58764D03*
X767921Y-35764D03*
Y-58764D03*
X762921Y-35764D03*
Y-58764D03*
X757921Y-35764D03*
Y-58764D03*
X752921Y-35764D03*
Y-58764D03*
X787921Y-35764D03*
Y-58764D03*
X782921Y-35764D03*
Y-58764D03*
X777921Y-35764D03*
X747921D03*
Y-58764D03*
X742921Y-35764D03*
Y-58764D03*
X737921Y-35764D03*
Y-58764D03*
X732921Y-35764D03*
Y-58764D03*
X727921Y-35764D03*
Y-58764D03*
X786674Y211463D03*
X785920Y204763D03*
X786300Y207400D03*
X787200Y244200D03*
Y271900D03*
X787100Y241100D03*
X770632Y234833D03*
X770965Y237519D03*
X773800Y237700D03*
X768382Y237861D03*
X769637Y266647D03*
X770485Y269489D03*
X772630Y266810D03*
X773419Y270414D03*
X787200Y276400D03*
X787100Y303900D03*
X775200Y301200D03*
X770900Y301800D03*
X768290Y301780D03*
X753098Y338316D03*
X747498Y335516D03*
X750298Y338316D03*
Y335516D03*
X744698Y338316D03*
Y335516D03*
X747498Y338316D03*
X744698Y332816D03*
X769440Y298735D03*
X772400Y299400D03*
X787000Y308300D03*
X771730Y330665D03*
X775732Y332989D03*
X770278Y333272D03*
X772949Y333009D03*
X787400Y340400D03*
X747000Y386000D03*
X743500D03*
X750500D03*
X754000D03*
X750298Y344833D03*
X744698Y347833D03*
X747498D03*
X750298D03*
X747673Y364009D03*
X745073D03*
X750273D03*
X747573Y366909D03*
X744973D03*
X750173D03*
X744698Y344833D03*
X747498D03*
X747000Y380000D03*
X743500D03*
X753874Y379863D03*
X750500Y380000D03*
Y374000D03*
X754000D03*
X747000D03*
X743500D03*
X741774Y376463D03*
X769380Y366440D03*
X775070Y365070D03*
X772290Y365020D03*
X769440Y363810D03*
X785400Y372400D03*
X757500Y374000D03*
X775420Y397110D03*
X772742Y397209D03*
X766860Y396240D03*
X769770Y396070D03*
X770406Y638753D03*
X779206D03*
X774806D03*
X730806D03*
X726406D03*
X739606D03*
X735206D03*
X748406D03*
X744006D03*
X766006D03*
X761606D03*
X757206D03*
X752806D03*
X783606D03*
X744021Y660756D03*
X735221D03*
X779221D03*
X770421D03*
X774821D03*
X726421D03*
X730821D03*
X739621D03*
X748421D03*
X783621D03*
X757221D03*
X761621D03*
X752821D03*
X766021D03*
X842921Y-35764D03*
X837921Y-58764D03*
Y-35764D03*
X832921Y-58764D03*
X847921D03*
Y-35764D03*
X842921Y-58764D03*
X832921Y-35764D03*
X827921Y-58764D03*
Y-35764D03*
X822921Y-58764D03*
Y-35764D03*
X817921Y-58764D03*
Y-35764D03*
X812921Y-58764D03*
Y-35764D03*
X807921Y-58764D03*
Y-35764D03*
X802921Y-58764D03*
Y-35764D03*
X797921D03*
Y-58764D03*
X792921Y-35764D03*
Y-58764D03*
X816900Y216300D03*
X816874Y212863D03*
X814274D03*
X811674D03*
X808818Y211179D03*
X808618Y208579D03*
X803200Y213100D03*
X800600D03*
X794474Y211463D03*
X791874D03*
X789274D03*
X788522Y204343D03*
X791122Y204339D03*
X829327Y214740D03*
X832276Y214754D03*
X827322Y217430D03*
X826700Y214802D03*
X824072Y214865D03*
X824446Y217476D03*
X821775Y217617D03*
X821466Y214925D03*
X814849Y205001D03*
X792514Y201290D03*
X797717Y201907D03*
X803134Y202969D03*
X808165Y203529D03*
X818960Y202230D03*
X789432Y236947D03*
X789400Y273700D03*
X811983Y244843D03*
Y242243D03*
X814583Y239643D03*
X815432Y237000D03*
X814583Y244843D03*
Y242243D03*
X812832Y237000D03*
X811983Y239643D03*
X802432Y237000D03*
X799832D03*
X792032D03*
X794632D03*
X810232D03*
X797232D03*
X805032D03*
X807632D03*
X791000Y244400D03*
X793600D03*
X816800Y234300D03*
X816900Y230900D03*
X817000Y252500D03*
X789800Y276400D03*
X792400D03*
X801991Y276557D03*
X804591D03*
X792191Y269101D03*
X789591D03*
X814891Y271657D03*
Y274257D03*
Y276857D03*
Y269057D03*
X812291D03*
Y274257D03*
Y276857D03*
Y271657D03*
X817000Y255100D03*
Y257700D03*
X848282Y251727D03*
X828180Y231748D03*
X828682Y237027D03*
X831682D03*
X828682Y234327D03*
X837500Y239500D03*
X845050Y229400D03*
X837500Y234050D03*
Y236650D03*
X834682Y236877D03*
X840155Y234245D03*
X834700Y234200D03*
X831682Y234327D03*
X834682Y239627D03*
X831682D03*
X828682D03*
X848282Y246427D03*
Y249027D03*
X825682Y239627D03*
Y234327D03*
Y237027D03*
X825313Y231753D03*
X848382Y279727D03*
Y277027D03*
Y274427D03*
X825464Y277510D03*
Y274910D03*
Y280110D03*
X822464D03*
Y277510D03*
Y274910D03*
X834464Y280110D03*
X831464D03*
X828464Y277510D03*
Y274910D03*
Y280110D03*
X834464Y277510D03*
X831464D03*
X834464Y274910D03*
X845050Y252250D03*
X817491Y276857D03*
Y274257D03*
Y271657D03*
Y269057D03*
X837264Y274910D03*
Y280110D03*
Y277510D03*
X840064D03*
Y280110D03*
X817183Y242243D03*
Y239643D03*
Y244843D03*
X818032Y237000D03*
X822682Y234327D03*
Y231727D03*
Y237027D03*
Y239627D03*
X831464Y274910D03*
X844400Y280500D03*
X848282Y254327D03*
X788600Y306100D03*
X789500Y301200D03*
X797300D03*
X799900D03*
X810300D03*
X802500D03*
X812900D03*
X807700D03*
X805100D03*
X815500D03*
X811991Y308957D03*
Y306357D03*
Y303757D03*
X814591Y306357D03*
Y308957D03*
Y303757D03*
X792900Y308400D03*
X789900D03*
X794700Y301200D03*
X792100D03*
X793000Y340400D03*
X790300Y340300D03*
X816991Y337357D03*
Y334757D03*
Y339957D03*
X814391D03*
Y337357D03*
Y334757D03*
X811791Y337357D03*
Y339957D03*
Y334757D03*
X791879Y332798D03*
X794600Y332600D03*
X816938Y319888D03*
Y323888D03*
X817100Y317000D03*
X848382Y282327D03*
X834682Y298527D03*
X828682D03*
X825682D03*
Y295527D03*
Y301227D03*
Y303927D03*
X822682D03*
Y301227D03*
Y295527D03*
Y298527D03*
X844300Y312450D03*
X831682Y298527D03*
X837782Y298127D03*
Y301027D03*
Y303927D03*
X818100Y301200D03*
X817191Y303757D03*
Y306357D03*
Y308957D03*
X834682Y301227D03*
X831682D03*
X828682D03*
X831682Y303927D03*
X834682D03*
X822482Y339827D03*
Y337027D03*
X831482D03*
X834482D03*
X828482Y339827D03*
X831482D03*
X834482D03*
X840282Y340227D03*
X840382Y337427D03*
X837382Y339877D03*
Y337077D03*
X847682Y314627D03*
X847982Y338327D03*
Y341327D03*
X828482Y337027D03*
X828682Y303927D03*
X847682Y309327D03*
Y312027D03*
Y306727D03*
X825482Y339827D03*
Y337027D03*
X789860Y364947D03*
X820218Y385950D03*
Y382950D03*
X826097Y385923D03*
X816591Y369857D03*
Y372457D03*
X811391Y369857D03*
X813991D03*
Y372457D03*
X811391D03*
X790900Y372300D03*
X788300Y372400D03*
X802759Y364575D03*
X816672Y358809D03*
X795310Y364721D03*
X816593Y356210D03*
X807959Y364575D03*
X805359D03*
X810559D03*
X815759D03*
X813159D03*
X816900Y361400D03*
X792610Y364821D03*
X816591Y375057D03*
X792238Y396753D03*
X789600Y396809D03*
X811515Y397289D03*
X808915D03*
X813648Y395557D03*
X815472Y390442D03*
X814877Y393138D03*
X792000Y399409D03*
X789400D03*
X822089Y362782D03*
Y359782D03*
X822482Y342827D03*
X828482D03*
X831482D03*
X834482D03*
X828089Y359841D03*
X834089D03*
X831089D03*
X844350Y344000D03*
X840262Y343011D03*
X837382Y342877D03*
X821658Y369463D03*
X832058Y366863D03*
Y369463D03*
X834658D03*
Y366863D03*
X837363Y366829D03*
X826858Y366863D03*
Y369463D03*
X824258Y366863D03*
Y369463D03*
X829458D03*
Y366863D03*
X821658D03*
X847982Y344327D03*
X834089Y362782D03*
X831089D03*
X826216Y383108D03*
X823218Y382950D03*
X848608Y376068D03*
Y378668D03*
X846008Y376068D03*
Y378668D03*
X848932Y373257D03*
X823218Y385950D03*
X828089Y362782D03*
X825482Y342827D03*
X825089Y359841D03*
Y362782D03*
X849606Y638753D03*
X836406D03*
X832006D03*
X796806D03*
X801206D03*
X792406D03*
X827606D03*
X818806D03*
X823206D03*
X810006D03*
X788006D03*
X845206D03*
X814406D03*
X805606D03*
X840806D03*
X849621Y660756D03*
X832021D03*
X810021D03*
X818821D03*
X836421D03*
X788021D03*
X814421D03*
X801221D03*
X805621D03*
X823221D03*
X827621D03*
X840821D03*
X796821D03*
X792421D03*
X845221D03*
X907921Y-58764D03*
Y-35764D03*
X902921Y-58764D03*
Y-35764D03*
X897921Y-58764D03*
Y-35764D03*
X892921Y-58764D03*
Y-35764D03*
X887921Y-58764D03*
Y-35764D03*
X882921Y-58764D03*
Y-35764D03*
X877921Y-58764D03*
Y-35764D03*
X872921Y-58764D03*
Y-35764D03*
X867921Y-58764D03*
Y-35764D03*
X862921Y-58764D03*
Y-35764D03*
X857921Y-58764D03*
Y-35764D03*
X852921Y-58764D03*
Y-35764D03*
X854282Y251727D03*
X857282D03*
X851282D03*
X857282Y249027D03*
Y246427D03*
X851282D03*
Y249027D03*
X854282D03*
Y246427D03*
X851382Y277027D03*
Y274427D03*
X857382Y277027D03*
X854382Y279727D03*
X857382D03*
X854382Y274427D03*
X857382D03*
X854382Y277027D03*
X874586Y259278D03*
X854282Y254327D03*
X857282D03*
X869586Y254278D03*
X851282Y254327D03*
X851382Y279727D03*
X884586Y269278D03*
X879586Y264278D03*
X889586Y274278D03*
X851382Y282327D03*
X854382D03*
X857382D03*
X851075Y335405D03*
X857075D03*
X856982Y338327D03*
X853982D03*
X856682Y314627D03*
X853682D03*
X850682D03*
X856982Y341327D03*
X853982D03*
X862008Y341100D03*
X850982Y338327D03*
Y341327D03*
X872008Y331100D03*
X867008Y336100D03*
X850682Y306727D03*
Y309327D03*
Y312027D03*
X856682Y309327D03*
X853682D03*
X856682Y306727D03*
X853682D03*
X856682Y312027D03*
X853682D03*
X877008Y326100D03*
X854075Y335405D03*
X856982Y344327D03*
X853982D03*
X850982D03*
X851208Y376068D03*
Y378668D03*
X851727Y373197D03*
X858406Y638753D03*
X854006D03*
X884806D03*
X880406D03*
X876006D03*
X871606D03*
X867206D03*
X911206D03*
X906806D03*
X889206D03*
X898006D03*
X902406D03*
X893606D03*
X862806D03*
X854021Y660756D03*
X858421D03*
X862821D03*
X898021D03*
X902421D03*
X871621D03*
X884821D03*
X893621D03*
X867221D03*
X889221D03*
X911221D03*
X906821D03*
X880421D03*
X876021D03*
X937921Y-35764D03*
X932921Y-58764D03*
Y-35764D03*
X927921Y-58764D03*
Y-35764D03*
X922921Y-58764D03*
Y-35764D03*
X917921Y-58764D03*
Y-35764D03*
X912921Y-58764D03*
Y-35764D03*
X942921D03*
X967921D03*
X962921Y-58764D03*
Y-35764D03*
X957921Y-58764D03*
Y-35764D03*
X952921Y-58764D03*
Y-35764D03*
X947921Y-58764D03*
Y-35764D03*
X942921Y-58764D03*
X972921D03*
Y-35764D03*
X967921Y-58764D03*
X937921D03*
X941883Y646234D03*
X951795D03*
X924406Y638753D03*
X920006D03*
X915606D03*
X972806D03*
X968406D03*
X964006D03*
X917100Y649300D03*
X942006Y638753D03*
X937606D03*
X933206D03*
X928806D03*
X959606D03*
X955206D03*
X950806D03*
X946406D03*
X941883Y652234D03*
X951795D03*
X959621Y660756D03*
X964021D03*
X968421D03*
X972821D03*
X920021D03*
X915621D03*
X924421D03*
X946421D03*
X942021D03*
X937621D03*
X933221D03*
X928821D03*
X955221D03*
X950821D03*
X1002921Y-58764D03*
Y-35764D03*
X997921Y-58764D03*
Y-35764D03*
X992921Y-58764D03*
Y-35764D03*
X987921Y-58764D03*
Y-35764D03*
X982921Y-58764D03*
Y-35764D03*
X977921Y-58764D03*
Y-35764D03*
X1032921Y-58764D03*
Y-35764D03*
X1027921Y-58764D03*
Y-35764D03*
X1022921Y-58764D03*
Y-35764D03*
X1017921Y-58764D03*
Y-35764D03*
X1012921Y-58764D03*
Y-35764D03*
X1007921Y-58764D03*
Y-35764D03*
X1030489Y270889D03*
Y273889D03*
X1027902Y278904D03*
X1020702D03*
X1017702D03*
X1024902D03*
X1032102D03*
X1024994Y292918D03*
X1017630Y292910D03*
X1020702Y292904D03*
X1027902D03*
X1031953Y292910D03*
X1024140Y309910D03*
X1021065Y309759D03*
X1017083Y309910D03*
X1032042D03*
X1028136Y309815D03*
X1017567Y295859D03*
X1024767D03*
X1020567D03*
X1031967D03*
X1027767D03*
X1015293Y311955D03*
X1003606Y638753D03*
X1012406D03*
X977206D03*
X990406D03*
X986006D03*
X994806D03*
X1016806D03*
X1021206D03*
X981606D03*
X999206D03*
X1025606D03*
X1008006D03*
X1030006D03*
X1034406D03*
X999221Y660756D03*
X1034421D03*
X1030021D03*
X1008021D03*
X1012421D03*
X1003621D03*
X1016821D03*
X977221D03*
X981621D03*
X1021221D03*
X1025621D03*
X994821D03*
X986021D03*
X990421D03*
X1067921Y-58764D03*
Y-35764D03*
X1062921Y-58764D03*
Y-35764D03*
X1057921Y-58764D03*
Y-35764D03*
X1052921Y-58764D03*
Y-35764D03*
X1047921Y-58764D03*
Y-35764D03*
X1042921Y-58764D03*
Y-35764D03*
X1037921Y-58764D03*
Y-35764D03*
X1092921Y-58764D03*
Y-35764D03*
X1087921Y-58764D03*
Y-35764D03*
X1082921Y-58764D03*
Y-35764D03*
X1077921Y-58764D03*
Y-35764D03*
X1072921Y-58764D03*
Y-35764D03*
X1075865Y264766D03*
X1070300Y264900D03*
X1073200Y264991D03*
X1057202Y264899D03*
X1060402Y264799D03*
X1066300Y264700D03*
X1063402Y264799D03*
X1054202Y264899D03*
X1042302Y278904D03*
X1039302D03*
X1056602Y278910D03*
X1035814Y278775D03*
X1049867Y278999D03*
X1053459Y278910D03*
X1060958D03*
X1075302D03*
X1078302D03*
X1082330D03*
X1070926D03*
X1063652D03*
X1067783D03*
X1082432Y264620D03*
X1085518Y278910D03*
X1089702Y278904D03*
X1086061Y262300D03*
X1086000Y264900D03*
X1077282Y338533D03*
X1080282D03*
X1056792Y338673D03*
X1063992D03*
X1060992D03*
X1071192D03*
X1068192D03*
X1046276Y292910D03*
X1049502Y292904D03*
X1053684Y292910D03*
X1056702Y292904D03*
X1039182Y292919D03*
X1042302Y292904D03*
X1035102D03*
X1049547Y309904D03*
X1046612Y309910D03*
X1056747Y309904D03*
X1053594Y309910D03*
X1042347Y309904D03*
X1039383Y309910D03*
X1035147Y309904D03*
X1039167Y295859D03*
X1042167D03*
X1034967D03*
X1046367D03*
X1056567D03*
X1049367D03*
X1053567D03*
X1038720Y324174D03*
X1044220D03*
X1035820D03*
X1050220D03*
X1047220D03*
X1053220D03*
X1056220D03*
X1041470D03*
X1059220D03*
X1060767Y295859D03*
X1095756Y292841D03*
X1082367Y295859D03*
X1085367D03*
X1075167D03*
X1078167D03*
X1089567D03*
X1092567D03*
X1095567Y295841D03*
X1070967Y295859D03*
X1063767D03*
X1067967D03*
X1086126Y338758D03*
X1083301Y338841D03*
X1062220Y324174D03*
X1095402Y323904D03*
X1083220Y324174D03*
X1076020D03*
X1079020D03*
X1071820D03*
X1065220D03*
X1068820D03*
X1096006Y638753D03*
X1078406D03*
X1082806D03*
X1074006D03*
X1069606D03*
X1091606D03*
X1052006D03*
X1038806D03*
X1087206D03*
X1060806D03*
X1056406D03*
X1065206D03*
X1043206D03*
X1047606D03*
X1078421Y660756D03*
X1060821D03*
X1087221D03*
X1038821D03*
X1091621D03*
X1052021D03*
X1074021D03*
X1065221D03*
X1096021D03*
X1056421D03*
X1043221D03*
X1047621D03*
X1082821D03*
X1069621D03*
X1157921Y-58764D03*
Y-35764D03*
X1152921Y-58764D03*
Y-35764D03*
X1147921Y-58764D03*
Y-35764D03*
X1142921Y-58764D03*
Y-35764D03*
X1137921Y-58764D03*
Y-35764D03*
X1132921Y-58764D03*
Y-35764D03*
X1127921Y-58764D03*
Y-35764D03*
X1122921Y-58764D03*
Y-35764D03*
X1117921Y-58764D03*
Y-35764D03*
X1112921Y-58764D03*
Y-35764D03*
X1107921Y-58764D03*
Y-35764D03*
X1102921Y-58764D03*
Y-35764D03*
X1097921Y-58764D03*
Y-35764D03*
X1104256Y291841D03*
X1101615Y292447D03*
X1098756Y292841D03*
X1101567Y295859D03*
X1104221Y295696D03*
X1098567Y295841D03*
X1112490Y312723D03*
X1112515Y315369D03*
X1101200Y324013D03*
X1098402Y324017D03*
X1135606Y638753D03*
X1126806D03*
X1144406D03*
X1140006D03*
X1118006D03*
X1122406D03*
X1153206D03*
X1157606D03*
X1104806D03*
X1100406D03*
X1131206D03*
X1148806D03*
X1109206D03*
X1113606D03*
X1157621Y660756D03*
X1148821D03*
X1122421D03*
X1126821D03*
X1100421D03*
X1118021D03*
X1140021D03*
X1113621D03*
X1109221D03*
X1153221D03*
X1144421D03*
X1104821D03*
X1131221D03*
X1135621D03*
X1217921Y-58764D03*
Y-35764D03*
X1212921Y-58764D03*
Y-35764D03*
X1207921Y-58764D03*
Y-35764D03*
X1202921Y-58764D03*
Y-35764D03*
X1197921Y-58764D03*
Y-35764D03*
X1192921Y-58764D03*
Y-35764D03*
X1187921Y-58764D03*
Y-35764D03*
X1182921Y-58764D03*
Y-35764D03*
X1177921Y-58764D03*
Y-35764D03*
X1172921Y-58764D03*
Y-35764D03*
X1167921Y-58764D03*
Y-35764D03*
X1162921Y-58764D03*
Y-35764D03*
X1196198Y646206D03*
X1206110D03*
X1188406Y638753D03*
X1214806D03*
X1197206D03*
X1201606D03*
X1192806D03*
X1170806D03*
X1162006D03*
X1166406D03*
X1206006D03*
X1219206D03*
X1179606D03*
X1175206D03*
X1210406D03*
X1184006D03*
X1196198Y652206D03*
X1206110D03*
X1184021Y660756D03*
X1219221D03*
X1192821D03*
X1188421D03*
X1201621D03*
X1179621D03*
X1214821D03*
X1206021D03*
X1166421D03*
X1210421D03*
X1170821D03*
X1162021D03*
X1175221D03*
X1197221D03*
X1232921Y-58764D03*
Y-35764D03*
X1227921Y-58764D03*
Y-35764D03*
X1222921Y-58764D03*
Y-35764D03*
X1252921Y-58764D03*
Y-35764D03*
X1247921Y-58764D03*
Y-35764D03*
X1242921Y-58764D03*
Y-35764D03*
X1237921Y-58764D03*
Y-35764D03*
X1257921D03*
X1272921Y-58764D03*
Y-35764D03*
X1267921Y-58764D03*
Y-35764D03*
X1262921Y-58764D03*
Y-35764D03*
X1257921Y-58764D03*
X1277921D03*
Y-35764D03*
X1265293Y646264D03*
X1255381D03*
X1263206Y638753D03*
X1223606D03*
X1228006D03*
X1258806D03*
X1241206D03*
X1236806D03*
X1250006D03*
X1245606D03*
X1276406D03*
X1254406D03*
X1280806D03*
X1272006D03*
X1267606D03*
X1232406D03*
X1265293Y652264D03*
X1255381D03*
X1228021Y660756D03*
X1232421D03*
X1280821D03*
X1245621D03*
X1236821D03*
X1223621D03*
X1276421D03*
X1241221D03*
X1272021D03*
X1258821D03*
X1250021D03*
X1254421D03*
X1263221D03*
X1267621D03*
X1342921Y-35764D03*
Y-58764D03*
X1317921D03*
X1312921Y-35764D03*
Y-58764D03*
X1307921Y-35764D03*
Y-58764D03*
X1302921Y-35764D03*
Y-58764D03*
X1297921D03*
Y-35764D03*
X1292921Y-58764D03*
Y-35764D03*
X1287921Y-58764D03*
Y-35764D03*
X1282921Y-58764D03*
Y-35764D03*
X1322921D03*
Y-58764D03*
X1317921Y-35764D03*
X1337921D03*
Y-58764D03*
X1332921Y-35764D03*
Y-58764D03*
X1327921Y-35764D03*
Y-58764D03*
X1324806Y638753D03*
X1298406D03*
X1285206D03*
X1294006D03*
X1302806D03*
X1333606D03*
X1338006D03*
X1320406D03*
X1311606D03*
X1329206D03*
X1307206D03*
X1342406D03*
X1289606D03*
X1316006D03*
X1329221Y660756D03*
X1311621D03*
X1316021D03*
X1333621D03*
X1342421D03*
X1285221D03*
X1324821D03*
X1338021D03*
X1298421D03*
X1289621D03*
X1294021D03*
X1320421D03*
X1302821D03*
X1307221D03*
X1402921Y-58764D03*
X1397921D03*
X1402921Y-35764D03*
X1392921Y-58764D03*
X1397921Y-35764D03*
X1387921Y-58764D03*
X1392921Y-35764D03*
X1382921Y-58764D03*
X1387921Y-35764D03*
X1377921Y-58764D03*
X1382921Y-35764D03*
X1372921Y-58764D03*
X1377921Y-35764D03*
X1367921Y-58764D03*
X1362921Y-35764D03*
Y-58764D03*
X1357921Y-35764D03*
Y-58764D03*
X1352921Y-35764D03*
Y-58764D03*
X1347921Y-35764D03*
Y-58764D03*
X1395913Y-7874D03*
X1402211Y1139D03*
Y-16889D03*
X1351206Y638753D03*
X1360006D03*
X1404506Y638853D03*
X1355606Y638753D03*
X1386906Y638853D03*
X1364406Y638753D03*
X1391306Y638853D03*
X1346806Y638753D03*
X1400106Y638853D03*
X1382006Y638753D03*
X1377606D03*
X1373206D03*
X1395706Y638853D03*
X1368806Y638753D03*
X1402211Y601615D03*
Y619643D03*
X1395913Y610630D03*
X1368821Y660756D03*
X1346821D03*
X1355621D03*
X1360021D03*
X1364421D03*
X1351221D03*
X1404521Y660856D03*
X1400121D03*
X1395721D03*
X1386921D03*
X1377621Y660756D03*
X1382021D03*
X1373221D03*
X1391321Y660856D03*
X1407921Y-58764D03*
X1412921Y-35764D03*
X1407921D03*
X1442921Y-58764D03*
X1447921Y-35764D03*
X1437921Y-58764D03*
X1442921Y-35764D03*
X1432921Y-58764D03*
X1437921Y-35764D03*
X1427921Y-58764D03*
X1432921Y-35764D03*
X1422921Y-58764D03*
X1427921Y-35764D03*
X1417921Y-58764D03*
X1422921Y-35764D03*
X1412921Y-58764D03*
X1417921Y-35764D03*
X1462921Y-58764D03*
X1457921D03*
X1462921Y-35764D03*
X1452921Y-58764D03*
X1457921Y-35764D03*
X1447921Y-58764D03*
X1452921Y-35764D03*
X1410061Y2178D03*
X1410060Y-17927D03*
X1419313Y5626D03*
Y-21374D03*
X1428872Y1668D03*
X1428864Y-17425D03*
X1432813Y-7874D03*
X1431664Y190213D03*
X1456080Y547540D03*
X1463369Y561763D03*
X1446600Y563900D03*
X1449300D03*
X1454600D03*
X1451900D03*
X1457300D03*
X1452392Y544998D03*
X1453166Y547481D03*
X1422106Y638853D03*
X1466106D03*
X1448506D03*
X1457306D03*
X1417706D03*
X1413306D03*
X1461706D03*
X1452906D03*
X1408906D03*
X1444106D03*
X1435306D03*
X1426506D03*
X1430906D03*
X1439706D03*
X1432813Y610630D03*
X1428864Y601079D03*
X1428872Y620172D03*
X1419313Y597130D03*
Y624130D03*
X1410060Y600577D03*
X1410061Y620682D03*
X1457321Y660856D03*
X1417721D03*
X1413321D03*
X1408921D03*
X1422121D03*
X1426521D03*
X1435321D03*
X1444121D03*
X1439721D03*
X1430921D03*
X1448521D03*
X1452921D03*
X1466121D03*
X1461721D03*
X1502921Y-58764D03*
X1507921Y-35764D03*
X1497921Y-58764D03*
X1502921Y-35764D03*
X1492921Y-58764D03*
X1497921Y-35764D03*
X1487921Y-58764D03*
X1492921Y-35764D03*
X1482921Y-58764D03*
X1487921Y-35764D03*
X1477921Y-58764D03*
X1482921Y-35764D03*
X1472921Y-58764D03*
X1477921Y-35764D03*
X1467921Y-58764D03*
X1472921Y-35764D03*
X1467921D03*
X1527921Y-58764D03*
X1522921D03*
X1527921Y-35764D03*
X1517921Y-58764D03*
X1522921Y-35764D03*
X1512921Y-58764D03*
X1517921Y-35764D03*
X1507921Y-58764D03*
X1512921Y-35764D03*
X1514372Y248616D03*
Y243361D03*
X1514370Y246016D03*
X1473018Y562003D03*
X1470314Y561923D03*
X1467714Y561896D03*
X1526586Y559860D03*
X1527285Y562386D03*
X1524538Y562286D03*
X1495187Y561842D03*
X1497918Y561872D03*
X1492187Y561842D03*
X1489316Y561742D03*
X1500530Y561872D03*
X1492130Y545910D03*
X1495130D03*
X1497866Y545797D03*
X1519608Y646236D03*
X1509696D03*
X1496906Y638853D03*
X1492506D03*
X1501706Y638753D03*
X1506106D03*
X1514906D03*
X1483706Y638853D03*
X1523706Y638753D03*
X1510506D03*
X1488106Y638853D03*
X1474906D03*
X1519306Y638753D03*
X1479306Y638853D03*
X1528106Y638753D03*
X1470506Y638853D03*
X1519608Y652236D03*
X1509696D03*
X1496921Y660856D03*
X1483721D03*
X1488121D03*
X1492521D03*
X1479321D03*
X1510521Y660756D03*
X1528121D03*
X1523721D03*
X1501721D03*
X1506121D03*
X1514921D03*
X1519321D03*
X1474921Y660856D03*
X1470521D03*
X1587921Y-58764D03*
X1582921D03*
X1587921Y-35764D03*
X1532921D03*
X1542921D03*
X1532921Y-58764D03*
X1537921Y-35764D03*
X1577921Y-58764D03*
X1582921Y-35764D03*
X1572921Y-58764D03*
X1577921Y-35764D03*
X1567921Y-58764D03*
X1572921Y-35764D03*
X1562921Y-58764D03*
X1567921Y-35764D03*
X1557921Y-58764D03*
X1562921Y-35764D03*
X1552921Y-58764D03*
X1557921Y-35764D03*
X1547921Y-58764D03*
X1552921Y-35764D03*
X1542921Y-58764D03*
X1547921Y-35764D03*
X1537921Y-58764D03*
X1567425Y144373D03*
X1583078Y260122D03*
X1583047Y257171D03*
X1586399Y257099D03*
X1589030Y259807D03*
X1588999Y257104D03*
X1586430Y259824D03*
X1570020Y295340D03*
X1531986Y559860D03*
X1529286D03*
X1529985Y562386D03*
X1532685D03*
X1546795Y563316D03*
X1546685Y568656D03*
X1546825Y565986D03*
X1549395Y563541D03*
X1549285Y568881D03*
X1549425Y566211D03*
X1535385Y562386D03*
X1534897Y559808D03*
X1541267Y563185D03*
X1543967D03*
X1541080Y565859D03*
X1538331Y563913D03*
X1538385Y560978D03*
X1544080Y568859D03*
Y565859D03*
X1580121Y647556D03*
X1555106Y638753D03*
X1555121Y647556D03*
X1590121D03*
X1590106Y638753D03*
X1590121Y643156D03*
X1585121Y647556D03*
X1585106Y638753D03*
X1585121Y643156D03*
X1565121Y647556D03*
X1570121Y643156D03*
X1570106Y638753D03*
X1565106D03*
X1565121Y643156D03*
X1570121Y647556D03*
X1560121D03*
X1560106Y638753D03*
X1560121Y643156D03*
X1575121D03*
X1575106Y638753D03*
X1575121Y647556D03*
X1555121Y643156D03*
X1580106Y638753D03*
X1580121Y643156D03*
X1550121Y647556D03*
X1541306Y638753D03*
X1545706D03*
X1550106D03*
X1550121Y643156D03*
X1536906Y638753D03*
X1532506D03*
X1565121Y651956D03*
X1570121Y660756D03*
Y656356D03*
X1565121Y660756D03*
X1555121Y651956D03*
X1590121Y660756D03*
Y656356D03*
Y651956D03*
X1585121Y660756D03*
Y656356D03*
Y651956D03*
X1580121Y660756D03*
Y656356D03*
Y651956D03*
X1560121Y660756D03*
Y656356D03*
Y651956D03*
X1555121Y660756D03*
Y656356D03*
X1570121Y651956D03*
X1575121D03*
Y656356D03*
Y660756D03*
X1565121Y656356D03*
X1550121Y651956D03*
Y656356D03*
X1541321Y660756D03*
X1550121D03*
X1545721D03*
X1532521D03*
X1536921D03*
X1642921Y-35764D03*
Y-58764D03*
X1637921Y-35764D03*
Y-58764D03*
X1632921Y-35764D03*
Y-58764D03*
X1627921D03*
X1622921D03*
X1627921Y-35764D03*
X1617921Y-58764D03*
X1622921Y-35764D03*
X1612921Y-58764D03*
X1617921Y-35764D03*
X1607921Y-58764D03*
X1612921Y-35764D03*
X1602921Y-58764D03*
X1607921Y-35764D03*
X1597921Y-58764D03*
X1602921Y-35764D03*
X1592921Y-58764D03*
X1597921Y-35764D03*
X1592921D03*
X1647921D03*
Y-58764D03*
X1608099Y197125D03*
X1591598Y257028D03*
X1591628Y259924D03*
X1608280Y249234D03*
X1625106Y638753D03*
X1625121Y647556D03*
X1630121Y643156D03*
X1630106Y638753D03*
X1630121Y647556D03*
X1635121Y643156D03*
X1635106Y638753D03*
X1635121Y647556D03*
X1640121Y643156D03*
Y647556D03*
X1640106Y638753D03*
X1650121Y647556D03*
X1650106Y638753D03*
X1650121Y643156D03*
X1645121Y647556D03*
X1645106Y638753D03*
X1645121Y643156D03*
X1625121D03*
X1620121Y647556D03*
X1620106Y638753D03*
X1620121Y643156D03*
X1615121Y647556D03*
X1615106Y638753D03*
X1615121Y643156D03*
X1610121Y647556D03*
X1610106Y638753D03*
X1610121Y643156D03*
X1605121Y647556D03*
X1605106Y638753D03*
X1605121Y643156D03*
X1600121Y647556D03*
X1600106Y638753D03*
X1600121Y643156D03*
X1595121Y647556D03*
X1595106Y638753D03*
X1595121Y643156D03*
X1625121Y651956D03*
Y660756D03*
X1630121Y651956D03*
Y656356D03*
Y660756D03*
X1635121Y651956D03*
Y656356D03*
Y660756D03*
X1625121Y656356D03*
X1640121D03*
Y651956D03*
X1650121Y660756D03*
Y656356D03*
Y651956D03*
X1645121Y660756D03*
Y656356D03*
Y651956D03*
X1640121Y660756D03*
X1620121D03*
Y656356D03*
Y651956D03*
X1615121Y660756D03*
Y656356D03*
Y651956D03*
X1610121Y660756D03*
Y656356D03*
Y651956D03*
X1605121Y660756D03*
Y656356D03*
Y651956D03*
X1600121Y660756D03*
Y656356D03*
Y651956D03*
X1595121Y660756D03*
Y656356D03*
Y651956D03*
X1692921Y-40764D03*
X1702921Y-54764D03*
X1687921D03*
X1682921D03*
X1677921D03*
X1672921D03*
X1692921D03*
X1697921D03*
X1707921D03*
X1712921D03*
X1697921Y-40764D03*
X1692921Y-50764D03*
X1687921D03*
X1682921D03*
X1677921D03*
X1672921D03*
X1712921D03*
X1707921D03*
X1702921D03*
X1697921Y-45764D03*
X1707921D03*
X1702921D03*
X1712921D03*
X1697921Y-50764D03*
X1667921Y-35764D03*
X1712921D03*
Y-58764D03*
X1707921Y-35764D03*
Y-58764D03*
X1702921Y-35764D03*
Y-58764D03*
X1697921Y-35764D03*
Y-58764D03*
X1687921Y-40764D03*
X1672921Y-45764D03*
X1677921D03*
X1682921D03*
Y-40764D03*
X1687921Y-45764D03*
X1692921D03*
X1667921Y-58764D03*
X1662921Y-35764D03*
Y-58764D03*
X1657921Y-35764D03*
Y-58764D03*
X1652921Y-35764D03*
Y-58764D03*
X1712921Y-40764D03*
X1707921D03*
X1702921D03*
X1677921D03*
X1672921D03*
X1677921Y-35764D03*
Y-58764D03*
X1672921Y-35764D03*
Y-58764D03*
X1682921Y-35764D03*
Y-58764D03*
X1692921Y-35764D03*
Y-58764D03*
X1687921Y-35764D03*
Y-58764D03*
X1702005Y499163D03*
X1704596Y498876D03*
X1704544Y501627D03*
X1701874Y501795D03*
X1690121Y647556D03*
X1710121D03*
X1710106Y638753D03*
X1710121Y643156D03*
X1705121Y647556D03*
X1705106Y638753D03*
X1695121Y643156D03*
X1695106Y638753D03*
X1695121Y647556D03*
X1700121Y643156D03*
X1700106Y638753D03*
X1685121Y647556D03*
X1685106Y638753D03*
X1685121Y643156D03*
X1680121Y647556D03*
X1680106Y638753D03*
X1680121Y643156D03*
X1675121Y647556D03*
X1675106Y638753D03*
X1675121Y643156D03*
X1670121Y647556D03*
X1670106Y638753D03*
X1670121Y643156D03*
X1665121Y647556D03*
X1665106Y638753D03*
X1665121Y643156D03*
X1660121Y647556D03*
X1660106Y638753D03*
X1660121Y643156D03*
X1655121Y647556D03*
X1655106Y638753D03*
X1655121Y643156D03*
X1690121D03*
X1690106Y638753D03*
X1700121Y647556D03*
X1705121Y643156D03*
X1690121Y656356D03*
Y651956D03*
X1710121Y660756D03*
Y656356D03*
Y651956D03*
X1705121Y660756D03*
Y656356D03*
Y651956D03*
X1690121Y660756D03*
X1695121Y651956D03*
Y656356D03*
Y660756D03*
X1685121Y651956D03*
X1680121Y660756D03*
Y656356D03*
Y651956D03*
X1675121Y660756D03*
Y656356D03*
Y651956D03*
X1670121Y660756D03*
Y656356D03*
Y651956D03*
X1665121Y660756D03*
Y656356D03*
Y651956D03*
X1660121Y660756D03*
Y656356D03*
Y651956D03*
X1655121Y660756D03*
Y656356D03*
Y651956D03*
X1685121Y660756D03*
Y656356D03*
X1700121Y651956D03*
Y656356D03*
Y660756D03*
X1737921Y-50764D03*
X1722921Y-45764D03*
X1727921D03*
X1732921D03*
X1747921D03*
X1752921D03*
X1727921Y-54764D03*
X1757921D03*
X1717921D03*
X1722921D03*
X1767921Y-40764D03*
Y-50764D03*
X1762921D03*
X1757921D03*
X1762921Y-54764D03*
X1752921D03*
X1747921D03*
X1742921D03*
X1737921D03*
X1732921D03*
X1772921D03*
X1767921D03*
X1762921Y-40764D03*
X1772921D03*
X1722921Y-50764D03*
X1717921D03*
X1732921D03*
X1757921Y-40764D03*
X1717921Y-45764D03*
Y-58764D03*
X1742921Y-50764D03*
X1747921D03*
X1752921D03*
X1742921Y-58764D03*
X1737921Y-35764D03*
Y-58764D03*
X1732921Y-35764D03*
Y-58764D03*
X1727921Y-35764D03*
Y-58764D03*
X1722921Y-35764D03*
Y-58764D03*
X1717921Y-35764D03*
X1757921Y-45764D03*
X1762921D03*
X1742921D03*
X1752921Y-40764D03*
X1747921D03*
X1742921D03*
X1737921D03*
X1732921D03*
X1727921D03*
X1722921D03*
X1717921D03*
X1727921Y-50764D03*
X1767921Y-45764D03*
X1772921D03*
X1737921D03*
X1772921Y-35764D03*
Y-58764D03*
X1767921Y-35764D03*
Y-58764D03*
X1762921Y-35764D03*
Y-58764D03*
X1757921Y-35764D03*
Y-58764D03*
X1752921Y-35764D03*
Y-58764D03*
X1747921Y-35764D03*
Y-58764D03*
X1742921Y-35764D03*
X1772921Y-50764D03*
X1727600Y211300D03*
X1724800D03*
X1758000Y250000D03*
X1758324Y232657D03*
X1741000Y250000D03*
X1738000D03*
X1735000D03*
X1747227Y237314D03*
X1744308Y237295D03*
X1741668Y237314D03*
X1739044Y237284D03*
X1728139Y496807D03*
X1725566Y497186D03*
X1723591Y499135D03*
X1725600Y501000D03*
X1775121Y643156D03*
Y647556D03*
X1775106Y638753D03*
X1730121Y647556D03*
X1730106Y638753D03*
X1730121Y643156D03*
X1725121Y647556D03*
X1725106Y638753D03*
X1725121Y643156D03*
X1720121Y647556D03*
X1720106Y638753D03*
X1720121Y643156D03*
X1715121Y647556D03*
X1715106Y638753D03*
X1715121Y643156D03*
X1770121Y647556D03*
X1770106Y638753D03*
X1770121Y643156D03*
X1765121Y647556D03*
X1765106Y638753D03*
X1765121Y643156D03*
X1760121Y647556D03*
X1760106Y638753D03*
X1760121Y643156D03*
X1755121Y647556D03*
X1755106Y638753D03*
X1755121Y643156D03*
X1750121Y647556D03*
X1750106Y638753D03*
X1750121Y643156D03*
X1745121Y647556D03*
X1745106Y638753D03*
X1745121Y643156D03*
X1740121Y647556D03*
X1740106Y638753D03*
X1740121Y643156D03*
X1735121Y647556D03*
X1735106Y638753D03*
X1735121Y643156D03*
X1770121Y660756D03*
X1775121D03*
Y656356D03*
Y651956D03*
X1725121Y660756D03*
Y656356D03*
Y651956D03*
X1720121Y660756D03*
Y656356D03*
Y651956D03*
X1715121Y660756D03*
Y656356D03*
Y651956D03*
X1770121D03*
X1765121Y660756D03*
Y656356D03*
Y651956D03*
X1760121Y660756D03*
Y656356D03*
Y651956D03*
X1755121Y660756D03*
Y656356D03*
Y651956D03*
X1750121Y660756D03*
Y656356D03*
Y651956D03*
X1745121Y660756D03*
Y656356D03*
Y651956D03*
X1740121Y660756D03*
Y656356D03*
Y651956D03*
X1735121Y660756D03*
Y656356D03*
Y651956D03*
X1730121Y660756D03*
Y656356D03*
X1770121D03*
X1730121Y651956D03*
X1817921Y-40764D03*
X1832921Y-45764D03*
Y-54764D03*
X1827921D03*
X1822921D03*
X1817921D03*
X1812921D03*
X1807921D03*
X1802921D03*
X1797921D03*
X1792921D03*
X1787921D03*
X1782921D03*
X1777921D03*
X1832921Y-50764D03*
X1827921D03*
X1822921D03*
X1817921D03*
X1812921D03*
X1807921D03*
X1802921D03*
X1797921D03*
X1792921D03*
X1787921D03*
X1782921Y-40764D03*
X1792921D03*
X1802921D03*
X1807921D03*
X1822921D03*
X1827921D03*
X1832921D03*
X1812921D03*
X1797921D03*
X1777921Y-45764D03*
X1782921D03*
X1787921D03*
X1792921D03*
X1797921D03*
X1802921D03*
X1807921D03*
X1812921D03*
X1817921D03*
X1822921D03*
X1787921Y-40764D03*
X1832921Y-35764D03*
Y-58764D03*
X1827921Y-35764D03*
Y-58764D03*
X1822921Y-35764D03*
Y-58764D03*
X1817921Y-35764D03*
Y-58764D03*
X1812921Y-35764D03*
Y-58764D03*
X1807921Y-35764D03*
Y-58764D03*
X1802921Y-35764D03*
Y-58764D03*
X1797921Y-35764D03*
Y-58764D03*
X1792921Y-35764D03*
Y-58764D03*
X1787921Y-35764D03*
Y-58764D03*
X1782921Y-35764D03*
Y-58764D03*
X1777921Y-35764D03*
Y-58764D03*
X1782921Y-50764D03*
X1777921D03*
Y-40764D03*
X1827921Y-45764D03*
X1835121Y21532D03*
X1832071D03*
X1832771Y26818D03*
X1835921D03*
X1811967Y92168D03*
X1809267Y89468D03*
X1811967D03*
X1825930Y52900D03*
X1824410Y58030D03*
X1824350Y55180D03*
X1821270Y69470D03*
X1824180Y69460D03*
X1794992Y61342D03*
X1797664Y61334D03*
X1797645Y64153D03*
X1792382Y61363D03*
X1792363Y64182D03*
X1794973Y64161D03*
X1807891Y62180D03*
X1810563Y62172D03*
X1810693Y59493D03*
X1808021Y59501D03*
X1805411Y59522D03*
X1813393Y59493D03*
X1813363Y62172D03*
X1810578Y56866D03*
X1805282Y56880D03*
X1807916Y56895D03*
X1813278Y56866D03*
X1805281Y62201D03*
X1835714Y75029D03*
X1826900Y56500D03*
X1823830Y60700D03*
X1811967Y86868D03*
X1809267D03*
X1814667D03*
Y89468D03*
Y92168D03*
Y94868D03*
X1811967D03*
X1809267D03*
Y92168D03*
X1834059Y70501D03*
X1831460Y70600D03*
X1824060Y72460D03*
X1821070Y72480D03*
X1831460Y73300D03*
X1823155Y77329D03*
X1823188Y79943D03*
X1820488D03*
X1820455Y77329D03*
X1831148Y144592D03*
X1836200Y153424D03*
X1833000D03*
X1833600Y145900D03*
X1828390Y165600D03*
X1832000Y165800D03*
X1793205Y165531D03*
X1793268Y162774D03*
X1780121Y643156D03*
X1780106Y638753D03*
X1780121Y647556D03*
X1785121Y643156D03*
X1790121D03*
X1835121Y647556D03*
X1835106Y638753D03*
X1835121Y643156D03*
X1830121Y647556D03*
X1830106Y638753D03*
X1830121Y643156D03*
X1825121Y647556D03*
X1825106Y638753D03*
X1825121Y643156D03*
X1820121Y647556D03*
X1820106Y638753D03*
X1820121Y643156D03*
X1815121Y647556D03*
X1815106Y638753D03*
X1815121Y643156D03*
X1810121Y647556D03*
X1810106Y638753D03*
X1810121Y643156D03*
X1805121Y647556D03*
X1805106Y638753D03*
X1805121Y643156D03*
X1800121Y647556D03*
X1800106Y638753D03*
X1800121Y643156D03*
X1795121Y647556D03*
X1795106Y638753D03*
X1795121Y643156D03*
X1790121Y647556D03*
X1790106Y638753D03*
X1785121Y647556D03*
X1785106Y638753D03*
X1800121Y656356D03*
X1780121Y651956D03*
Y656356D03*
Y660756D03*
X1835121D03*
Y656356D03*
Y651956D03*
X1830121Y660756D03*
Y656356D03*
Y651956D03*
X1825121Y660756D03*
Y656356D03*
Y651956D03*
X1820121Y660756D03*
Y656356D03*
Y651956D03*
X1815121Y660756D03*
Y656356D03*
Y651956D03*
X1810121Y660756D03*
Y656356D03*
Y651956D03*
X1805121Y660756D03*
Y656356D03*
Y651956D03*
X1800121Y660756D03*
Y651956D03*
X1795121Y660756D03*
Y656356D03*
Y651956D03*
X1790121Y660756D03*
Y656356D03*
Y651956D03*
X1785121Y660756D03*
Y656356D03*
Y651956D03*
X1857921Y-45764D03*
X1837921D03*
X1897921D03*
X1892921D03*
X1887921D03*
X1882921D03*
X1877921D03*
X1872921D03*
X1867921D03*
X1862921D03*
X1842921Y-54764D03*
X1852921Y-45764D03*
X1847921D03*
X1842921D03*
X1897921Y-54764D03*
X1892921D03*
X1887921D03*
X1882921D03*
X1877921D03*
X1872921D03*
X1867921D03*
X1862921D03*
X1857921D03*
X1852921D03*
X1847921D03*
X1837921D03*
X1897921Y-50764D03*
X1892921D03*
X1887921D03*
X1882921D03*
X1877921D03*
X1872921D03*
X1867921D03*
X1862921D03*
X1857921D03*
X1852921D03*
X1847921D03*
X1842921D03*
X1837921D03*
X1892921Y-40764D03*
X1897921D03*
X1877921D03*
X1882921D03*
X1887921D03*
X1857921D03*
X1862921D03*
X1867921D03*
X1872921D03*
X1837921D03*
X1842921D03*
X1847921D03*
X1852921D03*
Y-35764D03*
Y-58764D03*
X1847921Y-35764D03*
Y-58764D03*
X1842921Y-35764D03*
Y-58764D03*
X1837921Y-35764D03*
Y-58764D03*
X1862921D03*
X1857921Y-35764D03*
Y-58764D03*
X1882921D03*
X1877921Y-35764D03*
Y-58764D03*
X1872921Y-35764D03*
Y-58764D03*
X1867921Y-35764D03*
Y-58764D03*
X1862921Y-35764D03*
X1897921D03*
Y-58764D03*
X1892921Y-35764D03*
Y-58764D03*
X1887921Y-35764D03*
Y-58764D03*
X1882921Y-35764D03*
X1838700Y26638D03*
X1838100Y21500D03*
X1847797Y26331D03*
X1847564Y21636D03*
X1862636Y26780D03*
X1851040Y24130D03*
X1855836Y21118D03*
X1852236D03*
X1859436D03*
X1862936D03*
X1865450Y22000D03*
X1860981Y23894D03*
X1857381D03*
X1853781D03*
X1864020Y24470D03*
X1851936Y26780D03*
X1859036D03*
X1855436D03*
X1844732Y-7874D03*
X1851030Y1139D03*
Y-16889D03*
X1858880Y2178D03*
X1858879Y-17927D03*
X1868132Y5626D03*
Y-21374D03*
X1877691Y1668D03*
X1877683Y-17425D03*
X1881632Y-7874D03*
X1837077Y77429D03*
X1837129Y72526D03*
X1837161Y69926D03*
X1838342Y75014D03*
X1846675Y67362D03*
X1844025D03*
X1849325D03*
X1839985Y77522D03*
X1842783Y77599D03*
X1842515Y70042D03*
X1839865D03*
X1845165D03*
X1842515Y72692D03*
X1839865D03*
X1844048Y75184D03*
X1846667Y75106D03*
X1841250Y75107D03*
X1845165Y72692D03*
X1847654Y164624D03*
X1852654D03*
X1883723Y263029D03*
Y260029D03*
X1880633Y260109D03*
Y263109D03*
X1886200Y454280D03*
X1882669Y454368D03*
X1886330Y448010D03*
X1892118Y454383D03*
X1888968D03*
X1888976Y448054D03*
X1892126D03*
X1895275D03*
X1895121Y647556D03*
X1895106Y638753D03*
X1895121Y643156D03*
X1890121Y647556D03*
X1890106Y638753D03*
X1890121Y643156D03*
X1885121Y647556D03*
X1885106Y638753D03*
X1885121Y643156D03*
X1880121Y647556D03*
X1880106Y638753D03*
X1880121Y643156D03*
X1875121Y647556D03*
X1875106Y638753D03*
X1875121Y643156D03*
X1870121Y647556D03*
X1870106Y638753D03*
X1870121Y643156D03*
X1865121Y647556D03*
X1865106Y638753D03*
X1865121Y643156D03*
X1860121Y647556D03*
X1860106Y638753D03*
X1860121Y643156D03*
X1855121Y647556D03*
X1855106Y638753D03*
X1855121Y643156D03*
X1850121Y647556D03*
X1850106Y638753D03*
X1850121Y643156D03*
X1845121Y647556D03*
X1845106Y638753D03*
X1845121Y643156D03*
X1840121Y647556D03*
X1840106Y638753D03*
X1840121Y643156D03*
X1844732Y610630D03*
X1851030Y619643D03*
Y601615D03*
X1858880Y620682D03*
X1858879Y600577D03*
X1868132Y624130D03*
Y597130D03*
X1877691Y620172D03*
X1877683Y601079D03*
X1881632Y610630D03*
X1895121Y660756D03*
Y656356D03*
Y651956D03*
X1890121Y660756D03*
Y656356D03*
Y651956D03*
X1885121Y660756D03*
Y656356D03*
Y651956D03*
X1880121Y660756D03*
Y656356D03*
Y651956D03*
X1875121Y660756D03*
Y656356D03*
Y651956D03*
X1870121Y660756D03*
Y656356D03*
Y651956D03*
X1865121Y660756D03*
Y656356D03*
Y651956D03*
X1860121Y660756D03*
Y656356D03*
Y651956D03*
X1855121Y660756D03*
Y656356D03*
Y651956D03*
X1850121Y660756D03*
Y656356D03*
Y651956D03*
X1845121Y660756D03*
Y656356D03*
Y651956D03*
X1840121Y660756D03*
Y656356D03*
Y651956D03*
X1927921Y-40764D03*
X1947921Y-45764D03*
X1942921D03*
X1937921D03*
X1932921D03*
X1927921D03*
X1922921D03*
X1917921D03*
X1912921D03*
X1907921D03*
X1902921D03*
X1927921Y-50764D03*
X1932921D03*
Y-40764D03*
X1937921D03*
X1942921D03*
X1947921D03*
X1907921Y-50764D03*
X1902921D03*
X1922921Y-40764D03*
X1917921D03*
X1912921D03*
X1907921D03*
X1902921D03*
X1922921Y-54764D03*
X1917921D03*
X1912921D03*
X1907921D03*
X1902921D03*
X1927921D03*
X1932921D03*
X1937921D03*
X1942921D03*
X1947921D03*
X1952921D03*
X1957921D03*
Y-50764D03*
X1952921D03*
X1947921D03*
X1942921D03*
X1937921D03*
X1922921D03*
X1917921D03*
X1912921D03*
X1957921Y-35764D03*
Y-58764D03*
X1952921Y-35764D03*
Y-58764D03*
X1947921Y-35764D03*
Y-58764D03*
X1942921Y-35764D03*
Y-58764D03*
X1937921Y-35764D03*
Y-58764D03*
X1932921Y-35764D03*
Y-58764D03*
X1927921Y-35764D03*
Y-58764D03*
X1922921Y-35764D03*
Y-58764D03*
X1917921Y-35764D03*
Y-58764D03*
X1912921Y-35764D03*
Y-58764D03*
X1907921Y-35764D03*
Y-58764D03*
X1902921Y-35764D03*
Y-58764D03*
X1938150Y70447D03*
X1937950Y73247D03*
X1940750Y73347D03*
X1929961Y73247D03*
X1935350D03*
X1932730Y73310D03*
X1942390Y76040D03*
X1943550Y73347D03*
X1946350Y73447D03*
X1948951Y73448D03*
X1945020Y76060D03*
X1954271Y80449D03*
X1936706Y75987D03*
X1939470Y76000D03*
X1930150Y70447D03*
X1932950D03*
X1935550D03*
X1940950Y70547D03*
X1943750D03*
X1907385Y93926D03*
X1904678Y93845D03*
X1907428Y91133D03*
X1904742Y96552D03*
X1907448Y96615D03*
X1908400Y101010D03*
X1937100Y146900D03*
X1940847Y227984D03*
X1938127Y228016D03*
X1910153Y226090D03*
X1910219Y223358D03*
X1914037Y243646D03*
X1917298Y466999D03*
X1914173Y467000D03*
X1910999D03*
X1960106Y638753D03*
X1955106D03*
X1950106D03*
X1945121Y647556D03*
Y643156D03*
X1945106Y638753D03*
X1940121Y647556D03*
Y643156D03*
X1940106Y638753D03*
X1935121Y647556D03*
Y643156D03*
X1935106Y638753D03*
X1930106D03*
X1925106D03*
X1920121Y647556D03*
X1910121Y643156D03*
X1910106Y638753D03*
X1905121Y647556D03*
Y643156D03*
X1905106Y638753D03*
X1900121Y647556D03*
X1900106Y638753D03*
X1900121Y643156D03*
X1920106Y638753D03*
X1915121Y647556D03*
X1920121Y643156D03*
X1910121Y647556D03*
X1915106Y638753D03*
X1915121Y643156D03*
X1960121Y656356D03*
Y660756D03*
X1955121Y656356D03*
Y660756D03*
X1950121Y651956D03*
Y656356D03*
Y660756D03*
X1945121Y651956D03*
Y656356D03*
Y660756D03*
X1940121Y651956D03*
Y656356D03*
Y660756D03*
X1935121Y651956D03*
Y656356D03*
Y660756D03*
X1930121Y651956D03*
Y656356D03*
Y660756D03*
X1925121Y651956D03*
Y656356D03*
Y660756D03*
X1920121Y651956D03*
Y656356D03*
X1905121Y651956D03*
Y656356D03*
Y660756D03*
X1900121D03*
Y656356D03*
Y651956D03*
X1915121D03*
Y656356D03*
Y660756D03*
X1920121D03*
X1910121D03*
Y656356D03*
Y651956D03*
X1967921Y-45764D03*
X1962921D03*
Y-40764D03*
X1967921D03*
Y-54764D03*
X1962921D03*
X1967921Y-50764D03*
X1962921D03*
X1967921Y-35764D03*
Y-58764D03*
X1962921Y-35764D03*
Y-58764D03*
X1969500Y229600D03*
X1966300D03*
X1970121Y647556D03*
Y643156D03*
X1970106Y638753D03*
X1965121Y647556D03*
Y643156D03*
X1965106Y638753D03*
X1970121Y651956D03*
Y656356D03*
Y660756D03*
X1965121Y651956D03*
Y656356D03*
Y660756D03*
G54D230*
G01X5440Y21090D02*
X4572D01*
X2871Y22791D01*
G01X74386Y-18439D02*
X73674Y-19151D01*
Y-20121D01*
X74070Y-20517D01*
X331638D01*
X333015Y-19140D01*
X378105D01*
X382840Y-14405D01*
Y36655D01*
X384440Y38255D01*
Y44575D01*
X382880Y46135D01*
Y56965D01*
X383920Y58005D01*
Y63835D01*
X382880Y64875D01*
Y78035D01*
X381770Y79145D01*
Y83430D01*
X382860Y84520D01*
Y94300D01*
X385290Y96730D01*
X388300D01*
X390880Y99310D01*
Y110620D01*
X403230Y122970D01*
X427158D01*
G01X71172Y-18486D02*
X71217D01*
X72674Y-19943D01*
Y-20536D01*
X73655Y-21517D01*
X332053D01*
X333430Y-20140D01*
X378520D01*
X383840Y-14820D01*
Y36240D01*
X385440Y37840D01*
Y44990D01*
X383880Y46550D01*
Y56550D01*
X384920Y57590D01*
Y64250D01*
X383880Y65290D01*
Y78450D01*
X382770Y79560D01*
Y83015D01*
X383860Y84105D01*
Y93885D01*
X385705Y95730D01*
X388715D01*
X391880Y98895D01*
Y110205D01*
X403645Y121970D01*
X441600D01*
X442128Y121442D01*
Y120734D01*
X440878Y119484D01*
Y117880D01*
G01X89360Y620310D02*
Y621993D01*
X90587Y623220D01*
X381365D01*
X382880Y621705D01*
Y509360D01*
X388710Y503530D01*
Y495144D01*
X385686Y492120D01*
X346748D01*
G01X86230Y620250D02*
X87613Y621633D01*
Y621661D01*
X90172Y624220D01*
X381780D01*
X383880Y622120D01*
Y509775D01*
X389710Y503945D01*
Y494729D01*
X386101Y491120D01*
X367615D01*
G01X253000Y255100D02*
X251500Y253600D01*
Y233285D01*
X210115Y191900D01*
X161659D01*
X156659Y196900D01*
X151900D01*
X150000Y195000D01*
Y194850D01*
G01X249000Y255100D02*
X250500Y253600D01*
Y233700D01*
X209700Y192900D01*
X161932D01*
X157032Y197800D01*
X151800D01*
X150000Y199600D01*
Y199850D01*
G01X343802Y496030D02*
X347302D01*
G01X343802D02*
Y495402D01*
X342704Y494304D01*
Y492620D01*
X343204Y492120D01*
X346748D01*
G01X340302Y496030D02*
Y495338D01*
X341552Y494088D01*
Y492229D01*
X342661Y491120D01*
X367615D01*
G01X340302Y496030D02*
X336802D01*
G01X444378Y117880D02*
X447878D01*
G01X427158Y122970D02*
X442015D01*
X443128Y121857D01*
Y120734D01*
X444378Y119484D01*
Y117880D01*
G01X440878D02*
X437378D01*
G01X643100Y253700D02*
X644200Y252600D01*
X649800D01*
G01X663500Y257500D02*
X662995D01*
X658861Y253366D01*
Y251333D01*
X657700Y250172D01*
G01X663500Y254000D02*
X660910D01*
X659982Y253072D01*
Y250918D01*
X660588Y250312D01*
G01X640500Y322000D02*
Y323463D01*
X640034Y323929D01*
X637497D01*
X637143Y323575D01*
Y322000D01*
G01Y327000D02*
Y325579D01*
X637593Y325129D01*
X640050D01*
X640500Y325579D01*
Y327000D01*
G01X640900Y312000D02*
X640500Y312400D01*
Y313407D01*
X640002Y313905D01*
X638059D01*
X637561Y313407D01*
Y312000D01*
G01Y317000D02*
Y315250D01*
X638006Y314805D01*
X639405D01*
X640900Y316300D01*
G01X709175Y221875D02*
X707550Y223500D01*
G01X705500D02*
X705525Y223525D01*
Y225525D01*
X704450Y226600D01*
G01X667500Y257750D02*
X665450D01*
X665200Y257500D01*
X663500D01*
G01X667500Y254250D02*
X665600D01*
X665350Y254000D01*
X663500D01*
G01X671733Y253567D02*
X671050Y254250D01*
X667500D01*
G01X693751Y335500D02*
X695689Y333562D01*
X696902D01*
X697352Y334012D01*
Y335500D01*
G01X693751Y330500D02*
X695613Y332362D01*
X697065D01*
X697352Y332075D01*
Y330500D01*
G01X679000Y345500D02*
X679900D01*
X680943Y346543D01*
Y349457D01*
X679194Y351206D01*
G01X684000Y345500D02*
X682701D01*
X682143Y346058D01*
Y349155D01*
X684194Y351206D01*
G01X903050Y254450D02*
X901750Y253150D01*
Y238935D01*
X867615Y204800D01*
X828715D01*
X821860Y197945D01*
X817448D01*
X816090Y199303D01*
Y199891D01*
X814691Y201290D01*
X810580D01*
X806290Y197000D01*
X800700D01*
X799300Y195600D01*
G01X899450Y254550D02*
X900750Y253250D01*
Y239350D01*
X867200Y205800D01*
X828300D01*
X821445Y198945D01*
X817863D01*
X817090Y199718D01*
Y200306D01*
X815106Y202290D01*
X810165D01*
X805875Y198000D01*
X800400D01*
X799300Y199100D01*
G01X1093800Y115500D02*
Y117080D01*
X1092318Y118562D01*
X1082362D01*
X1074000Y110200D01*
X1045400D01*
X1041300Y106100D01*
Y100700D01*
X1037100Y96500D01*
X1035300D01*
X1031700Y92900D01*
Y75400D01*
X1032400Y74700D01*
Y65000D01*
X1034100Y63300D01*
Y57128D01*
X1032497Y55525D01*
Y46231D01*
X1034400Y44328D01*
Y40400D01*
X1032400Y38400D01*
Y-10483D01*
X1043317Y-21400D01*
X1287674D01*
X1292074Y-17000D01*
X1293600D01*
G01X1077942Y112727D02*
X1074415Y109200D01*
X1045815D01*
X1042300Y105685D01*
Y100285D01*
X1037515Y95500D01*
X1035715D01*
X1032700Y92485D01*
Y75815D01*
X1033400Y75115D01*
Y65415D01*
X1035100Y63715D01*
Y56713D01*
X1033497Y55110D01*
Y46646D01*
X1035400Y44743D01*
Y39985D01*
X1033400Y37985D01*
Y-10068D01*
X1043732Y-20400D01*
X1287259D01*
X1291528Y-16131D01*
Y-15821D01*
X1293816Y-13533D01*
G01X1043300Y490900D02*
Y489600D01*
X1042000Y488300D01*
X1035500D01*
X1031400Y492400D01*
Y525800D01*
X1033400Y527800D01*
Y613700D01*
X1037100Y617400D01*
X1045400D01*
X1051328Y623328D01*
X1387852D01*
X1388352Y622828D01*
Y622120D01*
X1386921Y620689D01*
G01X1037657Y487300D02*
X1035085D01*
X1030400Y491985D01*
Y526215D01*
X1032400Y528215D01*
Y614115D01*
X1036685Y618400D01*
X1044985D01*
X1050913Y624328D01*
X1388267D01*
X1389352Y623243D01*
Y622188D01*
X1390851Y620689D01*
G01X1050984Y54842D02*
X1052622Y53204D01*
X1059371D01*
X1061024Y54857D01*
G01D02*
X1062677Y53204D01*
X1066078D01*
X1067716Y54842D01*
G01X1097300Y115500D02*
X1093800D01*
G01X1086800D02*
X1090300D01*
G01X1077942Y112727D02*
X1082777Y117562D01*
X1089799D01*
X1090300Y117061D01*
Y115500D01*
G01X1043300Y490900D02*
X1039900D01*
G01X1046800D02*
X1050300D01*
G01X1037657Y487300D02*
X1043554D01*
X1046800Y490546D01*
Y490900D01*
G01X1333500Y356500D02*
X1337368Y360368D01*
X1341954D01*
G01X1337469Y354526D02*
X1335474D01*
X1333500Y356500D01*
G01X1353569Y208960D02*
X1352241D01*
X1351570Y208289D01*
Y205405D01*
X1352158Y204817D01*
X1361326D01*
X1364255Y207746D01*
Y214628D01*
X1372919Y223292D01*
X1396133D01*
X1399480Y219945D01*
X1406989D01*
X1409908Y222864D01*
Y226786D01*
X1402467Y234227D01*
Y244034D01*
X1397911Y248590D01*
X1397910D01*
G01X1348569Y208960D02*
X1350001D01*
X1350670Y208291D01*
Y205032D01*
X1351785Y203917D01*
X1361699D01*
X1365155Y207373D01*
Y214255D01*
X1373292Y222392D01*
X1395760D01*
X1399107Y219045D01*
X1407362D01*
X1410808Y222491D01*
Y227159D01*
X1403367Y234600D01*
Y244407D01*
X1389637Y258137D01*
G01X1395512Y339812D02*
Y338488D01*
X1396800Y337200D01*
Y333427D01*
X1405784Y324443D01*
X1414783D01*
X1424000Y315226D01*
Y300500D01*
X1420350Y296850D01*
X1377647D01*
X1370400Y289603D01*
Y279858D01*
X1379758Y270500D01*
X1382228D01*
X1387100Y265628D01*
Y259401D01*
X1397910Y248591D01*
Y248590D01*
G01X1399012Y339812D02*
X1399011Y338511D01*
X1397700Y337200D01*
Y333800D01*
X1406157Y325343D01*
X1415156D01*
X1424900Y315599D01*
Y300127D01*
X1420723Y295950D01*
X1378020D01*
X1371300Y289230D01*
Y280231D01*
X1380131Y271400D01*
X1382601D01*
X1388000Y266001D01*
Y259774D01*
X1389637Y258137D01*
G01X1395512Y339812D02*
Y342260D01*
G01X1399012Y339812D02*
Y342260D01*
G01X1396052Y354220D02*
X1394260Y352428D01*
Y351170D01*
G01D02*
X1394257Y349476D01*
X1394753Y348980D01*
X1396186D01*
X1397700Y347466D01*
Y345672D01*
X1399012Y344360D01*
G01X1391845Y348325D02*
X1392300Y348780D01*
X1393680D01*
X1394380Y348080D01*
X1395813D01*
X1396800Y347093D01*
Y345648D01*
X1395512Y344360D01*
G01X1344731Y359567D02*
Y357678D01*
X1347332Y355077D01*
X1348988D01*
G01X1354650Y351387D02*
X1353650D01*
X1349960Y355077D01*
X1348988D01*
G01X1391845Y348325D02*
X1391212Y348958D01*
Y354260D01*
G01X1356149Y358155D02*
Y359855D01*
X1356466Y360172D01*
Y360680D01*
G01D02*
X1355868Y361278D01*
X1353590D01*
X1352407Y360095D01*
G01X1357213Y353950D02*
Y356509D01*
X1356149Y357573D01*
Y358155D01*
G01X1358788Y353950D02*
Y356234D01*
X1359649Y357095D01*
Y358155D01*
G01D02*
Y360751D01*
X1359600Y360800D01*
G01D02*
X1357637Y362763D01*
X1351575D01*
X1348907Y360095D01*
G01X1462775Y281470D02*
X1459631D01*
X1459628Y281473D01*
G01X1427851Y558435D02*
Y561651D01*
X1428200Y562000D01*
Y563500D01*
G01D02*
X1426483D01*
X1425243Y562260D01*
G01X1419950Y558398D02*
Y561076D01*
X1418402Y562624D01*
G01X1424351Y558435D02*
Y560664D01*
X1421560Y563455D01*
G01X1416450Y558398D02*
Y562036D01*
X1415582Y562904D01*
G01X1553300Y614500D02*
Y616699D01*
X1552575Y617424D01*
Y619000D01*
G01D02*
Y623102D01*
X1552198Y623479D01*
G01X1549075Y619000D02*
X1546930D01*
X1546075Y618145D01*
G01X1544050Y615296D02*
X1547004D01*
X1547800Y614500D01*
G01X1560747Y623576D02*
X1559629Y622458D01*
Y621626D01*
X1560879Y620376D01*
Y618572D01*
G01X1569495Y623365D02*
X1569257Y623127D01*
Y618555D01*
G01D02*
Y614855D01*
G01X1557575Y623559D02*
X1558629Y622505D01*
Y621626D01*
X1557379Y620376D01*
Y618572D01*
G01X1566520Y623382D02*
Y619318D01*
X1565757Y618555D01*
G01X1537700Y607397D02*
X1539296D01*
X1539802Y607903D01*
X1541162D01*
G01X1608762Y108548D02*
Y109552D01*
X1609970Y110760D01*
X1611340D01*
X1612921Y112341D01*
X1613741D01*
G01D02*
X1615290Y110792D01*
Y108089D01*
X1614792Y107591D01*
X1609719D01*
X1608762Y108548D01*
G01X1625485Y494188D02*
Y495304D01*
X1632762Y502581D01*
Y502957D01*
G01D02*
X1632039Y503680D01*
Y509300D01*
X1630300Y511039D01*
Y514327D01*
X1623551Y521076D01*
Y525015D01*
G01X1621783Y498617D02*
X1624493D01*
X1627500Y501624D01*
Y502000D01*
G01D02*
Y508000D01*
X1629106Y509606D01*
Y514106D01*
X1622000Y521212D01*
Y523096D01*
X1620030Y525066D01*
G54D104*
X699050Y226500D03*
X1367239Y8476D03*
X1366860Y40490D03*
X1352457Y360095D03*
X1369307Y399408D03*
X1371060Y587276D03*
X1367450Y616400D03*
X1420000Y558398D03*
X1427901Y558435D03*
X1560929Y618572D03*
X1569307Y618555D03*
G54D203*
X1952756Y-14960D03*
Y58268D03*
G54D122*
X1364300Y344300D03*
G54D11*
X0Y0D03*
G54D140*
X1446392Y472057D03*
X1438283Y472592D03*
G54D113*
X1228715Y362963D03*
G54D20*
X-17392Y478512D03*
X2621Y32939D03*
X2008Y79298D03*
X3474Y48572D03*
X11300Y53240D03*
X41508Y402597D03*
X45450Y348600D03*
X-1458Y462804D03*
X-5602Y498621D03*
X-10669Y516148D03*
X12217Y480254D03*
X-12210Y521200D03*
X37618Y502853D03*
X28246Y491557D03*
X418Y534500D03*
X2700Y564500D03*
X-9500Y539400D03*
X-9200Y574400D03*
X79670Y135828D03*
X60723Y156869D03*
X95777Y129396D03*
X76899Y157895D03*
X76300Y166500D03*
X57700Y169300D03*
X78100Y189400D03*
X68200Y191200D03*
X62400Y166500D03*
X67700Y255100D03*
X70400Y270200D03*
X90300Y224400D03*
X69300Y306000D03*
X76600Y342000D03*
X51498Y295470D03*
X62807Y305396D03*
X107300Y327600D03*
X85500Y341000D03*
X70900Y317400D03*
X80513Y338412D03*
X94850Y320650D03*
X95000Y315300D03*
X56100Y361900D03*
X56600Y356400D03*
X67130Y369550D03*
X55881Y527427D03*
X58597Y498898D03*
X55528Y478782D03*
X68700Y532400D03*
X57684Y647686D03*
Y651626D03*
X115300Y-5600D03*
X118600Y159500D03*
X124980Y241380D03*
X125460Y273080D03*
X110740Y240361D03*
X124400Y305080D03*
X110470Y308170D03*
X121620Y339500D03*
X119018Y369791D03*
X164830Y422339D03*
X157776Y410444D03*
X115750Y412130D03*
X226039Y400962D03*
X206696Y647714D03*
Y651654D03*
X267859Y209109D03*
X271239Y203260D03*
X277999Y218860D03*
X281379Y209109D03*
X288139Y201309D03*
Y209109D03*
X277999Y199360D03*
X274619Y201309D03*
Y209109D03*
Y205210D03*
X264092Y242260D03*
X271239D03*
X267859Y248109D03*
X264179Y261760D03*
X271239D03*
Y253960D03*
X288139Y228610D03*
X277999Y226660D03*
X288139Y220809D03*
X281379Y236409D03*
X284759Y250060D03*
X288139Y240309D03*
X281379Y244209D03*
X277999Y257860D03*
X288139Y267609D03*
Y259809D03*
X277999Y265660D03*
X274619Y271509D03*
X291519Y273460D03*
X277999D03*
X288139Y322209D03*
X281379D03*
X284759Y335860D03*
X277999D03*
X288139Y330009D03*
X281379Y341709D03*
Y330009D03*
X271239Y339760D03*
X252170Y337860D03*
X271239Y394359D03*
X267859Y392410D03*
X271239Y398260D03*
X284759Y355360D03*
X274619Y400209D03*
X281379D03*
X277999Y398260D03*
X274619Y396309D03*
X288139Y388509D03*
X291519Y394359D03*
X281379Y388509D03*
X284759Y394359D03*
X277999Y355360D03*
X284759Y347560D03*
X281379Y361209D03*
X284759Y374860D03*
X271239Y347560D03*
X264179D03*
X277999Y374860D03*
X288139Y369010D03*
X281379Y380709D03*
Y369010D03*
X260000Y371000D03*
X260900Y353123D03*
X267400Y364400D03*
X243705Y354394D03*
X243259Y363354D03*
X262200Y361200D03*
X256300Y349800D03*
Y358800D03*
X246406Y647786D03*
Y651726D03*
X308418Y216909D03*
X294899D03*
X301659D03*
X294899Y205210D03*
Y197409D03*
X352357Y218860D03*
X345598D03*
X338838Y214960D03*
X342218Y216909D03*
X338838Y207158D03*
Y203258D03*
X345598Y211060D03*
X348978Y213009D03*
X342218Y205210D03*
X298279Y222760D03*
X305039D03*
X328698Y236409D03*
Y244209D03*
X321938Y240309D03*
X294899Y232509D03*
X301659Y244209D03*
Y232509D03*
X318558Y222760D03*
X311798Y234460D03*
X305039Y238360D03*
X294899Y240309D03*
X311798Y226660D03*
X318558Y230559D03*
X332078Y222760D03*
X328698Y224709D03*
Y228610D03*
X332078Y230560D03*
X311798Y242260D03*
X315178Y248109D03*
X308418D03*
X305039Y257860D03*
X328698Y255909D03*
X325318Y261760D03*
X294899Y252009D03*
X301659Y263709D03*
Y252009D03*
X294899Y259809D03*
X332078Y261760D03*
X315178Y271509D03*
X311798Y265660D03*
X321938Y271509D03*
X308418D03*
X318558Y265660D03*
X294899Y271509D03*
Y267609D03*
X332078Y273460D03*
X298279D03*
X328698Y275409D03*
X332078Y277360D03*
X325318D03*
X328698Y279310D03*
X321938D03*
X301659Y271509D03*
X328698D03*
X298279Y269560D03*
X342218Y224709D03*
X345598Y230559D03*
X348978Y224709D03*
X355737D03*
X352357Y230559D03*
X335458Y220809D03*
X345598Y222760D03*
X335458Y228610D03*
X338838Y230560D03*
Y273460D03*
Y269560D03*
X335458Y275409D03*
X338838Y277360D03*
X335458Y279310D03*
Y271509D03*
X348978Y236409D03*
X355737D03*
X342218D03*
X319816Y257829D03*
X298279Y320260D03*
X294899Y330009D03*
X352357Y339760D03*
X355737Y341709D03*
X298279Y335860D03*
X321938Y326110D03*
X311798Y331960D03*
X325318D03*
X315178Y326110D03*
X318558Y331960D03*
X335458Y341709D03*
X301659D03*
X294899D03*
X305039Y335860D03*
X338838D03*
X328698Y341709D03*
X342218D03*
X332078Y335860D03*
Y370959D03*
X328698Y369010D03*
X294899Y400209D03*
X315178Y384609D03*
Y380709D03*
X332078Y374860D03*
X328698Y372909D03*
X355737Y345609D03*
X335458Y369010D03*
X338838Y363160D03*
X352357Y343660D03*
X348978Y384609D03*
X335458Y376809D03*
X345598Y374860D03*
X301659Y361209D03*
X332078Y351460D03*
X321938Y357309D03*
X335458D03*
X325318Y351460D03*
X301659Y380709D03*
X328698Y361209D03*
X305039Y374860D03*
X294899Y380709D03*
X308418D03*
X298279Y374860D03*
X345598Y386560D03*
X341892Y396301D03*
X311798Y363160D03*
X318558Y374860D03*
Y363160D03*
X294899Y361209D03*
X305039Y355360D03*
X298279Y367060D03*
X342218Y369010D03*
Y357309D03*
X345598Y363160D03*
Y351460D03*
X348978Y357309D03*
Y369010D03*
X355737Y380709D03*
X352357Y374860D03*
X294899Y388509D03*
X338838Y374860D03*
X348978Y380709D03*
X351192Y402800D03*
X342218Y380709D03*
X355737Y357309D03*
Y369010D03*
X352357Y363160D03*
Y351460D03*
X315178Y369010D03*
X298279Y355360D03*
Y347560D03*
X321938Y369010D03*
X318495Y348600D03*
X371700Y112300D03*
X365877Y218860D03*
X372637D03*
X386157Y211060D03*
X379397Y207159D03*
Y218860D03*
X359117Y211060D03*
Y218860D03*
X386157D03*
X357987Y193507D03*
X378267D03*
X372637Y211060D03*
X399676D03*
X392916D03*
X399676Y218860D03*
X407706Y216909D03*
X392916Y218860D03*
X376017Y224709D03*
X369257D03*
X362497D03*
X389537D03*
X382777D03*
X396296D03*
X407706Y236409D03*
Y244209D03*
X415634Y243496D03*
Y231797D03*
X396296Y236409D03*
X359117Y230559D03*
X379397Y234460D03*
X386157Y230559D03*
X407706Y224709D03*
X392916Y230559D03*
X399676D03*
X389537Y236409D03*
X362497D03*
X369257D03*
X365877Y230559D03*
X372637D03*
X389537Y357309D03*
X365877Y351460D03*
X372637D03*
X362497Y345609D03*
X359117Y343660D03*
X403056Y396309D03*
X411086Y394359D03*
X399676Y386560D03*
X411086D03*
Y382660D03*
Y378760D03*
X398546Y402900D03*
X402892Y400400D03*
X403056Y369010D03*
X399676Y363160D03*
X382777Y369010D03*
X365877Y363160D03*
X372637D03*
X362497Y369010D03*
X369257D03*
X389537Y380709D03*
X392916Y374860D03*
X359117D03*
Y386560D03*
X379397Y374860D03*
X382777Y380709D03*
X369257D03*
X379397Y386560D03*
X399676Y374860D03*
X403056Y380709D03*
X386157Y386560D03*
X396296Y369010D03*
X386157Y374860D03*
X376017Y380709D03*
X365877Y374860D03*
X372637D03*
X362497Y380709D03*
X396296D03*
X392916Y386560D03*
X372637D03*
X376017Y369010D03*
X389537D03*
X392916Y363160D03*
X386157D03*
X359117Y351460D03*
Y363160D03*
X362497Y357309D03*
X379397Y363160D03*
X369257Y357309D03*
X415500Y391900D03*
X371070Y498650D03*
X394280Y647594D03*
Y651534D03*
X419214Y218147D03*
X436113Y235696D03*
Y220096D03*
Y227896D03*
X446253Y222047D03*
Y225947D03*
X432733Y222047D03*
Y225947D03*
X442873Y220096D03*
Y227896D03*
X453013Y225947D03*
X439493Y229847D03*
Y222047D03*
Y225947D03*
X425974Y222047D03*
X419214Y225947D03*
X442873Y235696D03*
X429354Y231797D03*
X449633D03*
Y239596D03*
X452865Y270081D03*
X439764Y263699D03*
X449288Y266435D03*
X444752Y264188D03*
X453013Y253247D03*
X463153Y220096D03*
Y227896D03*
X473292Y222047D03*
Y225947D03*
X459773Y229847D03*
Y222047D03*
X466533Y241547D03*
X463153Y235696D03*
X473292Y241547D03*
X469913Y235696D03*
X456393D03*
Y247396D03*
X463153D03*
X476672D03*
X456393Y220096D03*
X466533Y225947D03*
Y253247D03*
X473292D03*
X459773D03*
X476672Y262996D03*
X469913Y266896D03*
X466300Y277700D03*
X461400Y274600D03*
X447800Y335900D03*
X466066Y292452D03*
X466734Y287074D03*
X466100Y300021D03*
X471033Y339047D03*
X472692Y292385D03*
X462200Y332100D03*
X474057Y299057D03*
X430474Y358547D03*
X433854Y356596D03*
X467653Y379996D03*
X443993Y354647D03*
X460893Y368296D03*
X450753Y374146D03*
X464273D03*
X454133Y368296D03*
X423714Y366347D03*
Y358547D03*
X437233Y366347D03*
X477792Y374146D03*
X427094Y387796D03*
X471033Y374146D03*
X474413Y368296D03*
X430474Y381947D03*
X423714Y378047D03*
X433854Y387796D03*
X423714Y393647D03*
X467653Y387796D03*
X447373Y383896D03*
X460893D03*
X474413D03*
X450753Y389747D03*
X440613Y383896D03*
X454133D03*
X443993Y389747D03*
X467653Y360496D03*
X447373D03*
X457513Y374146D03*
X430474Y362447D03*
Y370247D03*
X471033Y354647D03*
X460893Y360496D03*
X474413D03*
X464273Y354647D03*
X450753D03*
X440613Y360496D03*
X454133D03*
X433874Y647516D03*
Y651456D03*
X483432Y247396D03*
X508212Y243496D03*
X486812Y253247D03*
X480052D03*
X491312Y272747D03*
X494692Y266896D03*
X528491Y259096D03*
X504832Y307847D03*
X487932Y305896D03*
X491312Y303947D03*
X501452Y305896D03*
X494692Y298096D03*
X498072Y307847D03*
X484552Y303947D03*
X487932Y294196D03*
X491312Y296147D03*
X494692Y301996D03*
X487932D03*
X501452Y309797D03*
X487932Y298096D03*
X511592Y311747D03*
Y303947D03*
X481172Y321496D03*
X487932Y313696D03*
X481172Y325396D03*
X491312Y315647D03*
X481172Y317596D03*
X518352Y311747D03*
X528491Y305896D03*
X484552Y311747D03*
X481172Y286396D03*
X484552Y342947D03*
X481172Y364396D03*
Y383896D03*
X566051Y211555D03*
X562861Y205503D03*
X552151Y237647D03*
X548771Y305896D03*
X552151Y300047D03*
X548771Y301996D03*
X552151Y307847D03*
Y303947D03*
X555831Y301996D03*
X548771Y298096D03*
X542011Y317596D03*
X545391Y389747D03*
X542011Y391696D03*
Y395597D03*
Y387796D03*
X545391Y393647D03*
X581747Y647323D03*
Y651263D03*
X660600Y84800D03*
Y170000D03*
X653000Y256500D03*
X639000Y261100D03*
X650856Y292256D03*
X607339Y458540D03*
X657200Y522300D03*
X614870Y492153D03*
X641500Y487400D03*
X636600Y480900D03*
X613700Y474560D03*
X621422Y647247D03*
X658600Y590900D03*
X621422Y651187D03*
X667000Y28400D03*
X710000Y21000D03*
X690515Y27586D03*
X667900Y84100D03*
X682700Y34400D03*
X679800Y53600D03*
X710700Y48400D03*
X691830Y89820D03*
X670600Y144900D03*
Y150000D03*
X713248Y276494D03*
X709175Y221875D03*
X671733Y253567D03*
X673240Y274190D03*
X702503Y296653D03*
X700700Y304300D03*
X687427Y380000D03*
X692000Y345400D03*
X680200Y432100D03*
X682083Y520789D03*
X669150Y489450D03*
X725190Y510910D03*
X725021Y568200D03*
X688300Y532900D03*
X722500Y583800D03*
X682340Y584970D03*
X725600Y594600D03*
X729798Y84503D03*
X726815Y75315D03*
X771750Y242120D03*
X771800Y274850D03*
X774460Y336700D03*
X773580Y305230D03*
X774490Y369520D03*
X758150Y406880D03*
X728141Y579451D03*
X760300Y604300D03*
X848900Y217000D03*
X842500Y396400D03*
X802900Y417615D03*
X869877Y-5735D03*
X906470Y-5775D03*
X910900Y211803D03*
Y203260D03*
X910455Y340644D03*
X902559Y352500D03*
X906622Y348377D03*
X908300Y367500D03*
X903600Y361500D03*
X909450Y395500D03*
X903550Y398260D03*
X908650Y403450D03*
X897391Y647303D03*
Y651243D03*
X930987Y209109D03*
X937747Y201309D03*
Y209109D03*
X927607Y199360D03*
X924227Y201309D03*
Y209109D03*
Y205210D03*
X930987Y216909D03*
X934367Y203260D03*
Y211060D03*
X958026Y216909D03*
X944507D03*
X951267Y213009D03*
Y216909D03*
X944507Y197409D03*
X915457Y207159D03*
X930987Y248109D03*
X937747Y244209D03*
X927607Y246160D03*
X934367Y242260D03*
X930987Y228610D03*
X937747D03*
X927607Y222760D03*
X913700Y242260D03*
X920847D03*
Y250060D03*
X927607Y226660D03*
X917467Y248109D03*
X934367Y222760D03*
X927607Y238360D03*
X934367Y250060D03*
Y238360D03*
X917467Y271509D03*
X927607Y273460D03*
X924227Y271509D03*
X913787Y257860D03*
X920847Y261760D03*
Y253960D03*
X930987Y255909D03*
X934367Y269560D03*
X937747Y267609D03*
X927607Y261760D03*
X937747Y259809D03*
X934367Y261760D03*
X930987Y263709D03*
X947887Y222760D03*
X954647D03*
X951267Y220809D03*
X971546Y240309D03*
Y244209D03*
X961406Y242260D03*
X964786Y244209D03*
X961406Y246160D03*
X964786Y248109D03*
X958026D03*
X968166Y250060D03*
X971546Y279310D03*
X944507Y271509D03*
X964786Y263709D03*
Y275409D03*
X961406Y265660D03*
X971546Y271509D03*
X958026D03*
X968166Y265660D03*
Y273460D03*
X944507Y267609D03*
X947887Y269560D03*
X951267Y271509D03*
X947887Y273460D03*
X941127D03*
X944507Y232509D03*
X971546Y228610D03*
X968166Y222760D03*
X951267Y232509D03*
Y252009D03*
Y244209D03*
X947887Y257860D03*
X968166Y230559D03*
X964786Y228610D03*
X944507Y259809D03*
X954647Y234460D03*
X961406Y226660D03*
X944507Y240309D03*
X954647Y253960D03*
Y238360D03*
Y261760D03*
X951267Y263709D03*
X947887Y250060D03*
X944507Y252009D03*
X964786Y236409D03*
X961406Y234460D03*
X954647Y257860D03*
X968166Y234460D03*
X968218Y254594D03*
X967589Y260093D03*
X913787Y335860D03*
X920847Y331960D03*
Y339760D03*
X930987Y330009D03*
Y341709D03*
X937747Y330009D03*
X927607Y335860D03*
X934367D03*
Y320260D03*
X927607Y324160D03*
X947887Y335860D03*
X954647D03*
X944507Y341709D03*
X951267D03*
X968166Y331960D03*
X964786Y326110D03*
X947887Y320260D03*
X941127D03*
X944507Y330009D03*
X961406Y331960D03*
X971546Y326110D03*
X967830Y340840D03*
X934367Y367060D03*
X913787Y351460D03*
X920847D03*
X927607Y370959D03*
X917467Y345609D03*
X934367Y347560D03*
X927607Y359260D03*
X934367Y355360D03*
X927607Y351460D03*
X937747Y372909D03*
X927607Y378760D03*
X934367D03*
Y386560D03*
X930987Y392410D03*
X937747Y396309D03*
X930987Y400209D03*
X917467Y392410D03*
X924227Y396309D03*
X971546Y357309D03*
X951267Y365109D03*
Y353409D03*
X944507Y365109D03*
X961406Y367060D03*
X964786Y361209D03*
X947887Y347560D03*
X954647Y359260D03*
X971546Y345609D03*
X944507Y357309D03*
X971546Y365109D03*
X958026Y349509D03*
X947887Y382660D03*
X958026Y376809D03*
X944507D03*
X954647Y382660D03*
X951267Y372909D03*
X944507Y392410D03*
X941127Y386560D03*
X971546Y372909D03*
X964786D03*
X944507Y400209D03*
X964786Y384609D03*
Y380709D03*
X967498Y348611D03*
X916700Y403300D03*
X937076Y647236D03*
Y651176D03*
X991826Y213009D03*
X988446Y214960D03*
X991826Y216909D03*
X988446Y207158D03*
Y203258D03*
X995206Y211060D03*
X998586Y213009D03*
X1025625Y216909D03*
X1015485Y218860D03*
X1022245D03*
X1032385Y213009D03*
X1029005Y207159D03*
X1012105Y213009D03*
X1008725Y218860D03*
X1005345Y216909D03*
X1025625Y213009D03*
X991826Y209109D03*
X995206Y207159D03*
X1022245D03*
X1005345Y213009D03*
X1029005Y218860D03*
X1001965D03*
X1018865Y213009D03*
X978306Y236409D03*
Y240309D03*
Y244209D03*
X974926Y246160D03*
X985066Y240309D03*
X981686Y246160D03*
X991826Y224709D03*
X988446Y222760D03*
X998586Y228610D03*
X985066Y220809D03*
X981686Y222760D03*
X978306Y224709D03*
X981686Y226660D03*
X985066Y228610D03*
X978306D03*
X981686Y230559D03*
X985066Y232509D03*
X995206Y250060D03*
X998586Y252009D03*
X995206Y253960D03*
X998586Y255909D03*
X995206Y257860D03*
X998586Y259809D03*
X995206Y261760D03*
X988446Y269560D03*
X985066Y271509D03*
X978306D03*
X988446Y273460D03*
X981686D03*
X985066Y275409D03*
X978306D03*
X988446Y277360D03*
X981686D03*
X974926D03*
X985066Y279310D03*
X978306D03*
X1025625Y224709D03*
X1022245Y222760D03*
X1018865Y224709D03*
X1012105D03*
X1032385D03*
X1029005Y222760D03*
X1005345Y224709D03*
X1001965Y230559D03*
X1012105Y248109D03*
X1008725Y250060D03*
X1001965D03*
X1032385Y240309D03*
X1029005Y242260D03*
X1032385Y244209D03*
X1025625D03*
X1029005Y246160D03*
X1022245D03*
X1015485D03*
X1018865Y248109D03*
X1015485Y250060D03*
X1005345Y252009D03*
X1008725Y253960D03*
X1001965D03*
X1005345Y255909D03*
X1001965Y257860D03*
X1012105Y252009D03*
X985066Y263709D03*
X988446Y257860D03*
X1022245Y242260D03*
X1018865Y228610D03*
X1012105Y236409D03*
X1018865D03*
X1015485Y230559D03*
X1022245D03*
X991826Y236409D03*
Y228610D03*
X995206Y242260D03*
X1015485D03*
X1029005Y230559D03*
X998586Y236409D03*
Y224709D03*
X1008725Y246160D03*
X1001965Y242260D03*
X1005345Y236409D03*
X1008725Y230559D03*
Y242260D03*
X1001965Y246160D03*
X1025625Y236409D03*
X981686Y257860D03*
Y265660D03*
Y253960D03*
X974926Y261760D03*
Y257860D03*
X978306Y263709D03*
X1032385Y236409D03*
X998586Y337809D03*
X991826D03*
X978306D03*
X985066Y333909D03*
X974926Y331960D03*
X1001965Y339760D03*
X1005345Y341709D03*
X978306Y361209D03*
X974926Y351460D03*
X981686D03*
X995206Y367060D03*
X988446Y370959D03*
X981686Y343660D03*
X991826Y349509D03*
X995206Y347560D03*
X981686Y370959D03*
X978306Y369010D03*
X985066D03*
Y365109D03*
X988446Y363160D03*
X995206Y378760D03*
X998586Y372909D03*
X988446Y378760D03*
X998586Y384609D03*
X985066Y376809D03*
X981686Y374860D03*
X995206D03*
X991826Y384609D03*
X991500Y396301D03*
X1032385Y357309D03*
X1022245Y351460D03*
X1029005D03*
X1001965Y347560D03*
X1012105Y345609D03*
X1015485Y347560D03*
X1008725D03*
X1001965Y367060D03*
X1015485Y355360D03*
X1008725Y367060D03*
X1022245Y390460D03*
X1000800Y402800D03*
X1025625Y372909D03*
X1018865Y384609D03*
Y372909D03*
X1012105D03*
X1022245Y378760D03*
X1032385Y384609D03*
X1001965Y378760D03*
X1032385Y372909D03*
X1029005Y378760D03*
X1012105Y384609D03*
X1008725Y378760D03*
X1005345Y372909D03*
Y384609D03*
X1025625D03*
X988446Y343660D03*
X1015485Y378760D03*
Y367060D03*
X1022245D03*
X1012105Y361209D03*
X1018865D03*
X991826D03*
X998586D03*
X1029005Y367060D03*
X995206Y355360D03*
X1001965D03*
X1005345Y361209D03*
X1008725Y355360D03*
X1025625Y361209D03*
X1032385D03*
X985066Y357309D03*
X1001946Y621460D03*
X1049284Y218860D03*
X1057314Y216909D03*
X1035765Y218860D03*
X1049284Y211060D03*
X1089101Y218147D03*
X1065242Y216196D03*
X1039145Y213009D03*
X1042524Y211060D03*
X1049284Y207159D03*
X1045904Y216909D03*
X1042524Y218860D03*
X1045904Y244209D03*
Y240309D03*
X1035765Y222760D03*
X1039145Y224709D03*
X1042524Y222760D03*
X1045904Y224709D03*
X1049284Y242260D03*
X1039145Y240309D03*
X1042524Y242260D03*
X1035765D03*
X1039145Y244209D03*
X1042524Y246160D03*
X1035765D03*
X1092481Y220096D03*
Y227896D03*
X1089101Y229847D03*
X1075582Y222047D03*
X1065242Y227896D03*
Y231797D03*
X1072202Y220096D03*
Y227896D03*
X1068822Y225947D03*
Y222047D03*
X1095861Y241547D03*
X1092481Y235696D03*
Y239596D03*
X1072202Y247396D03*
X1065242Y243496D03*
X1085721Y220096D03*
X1095861Y225947D03*
X1082341D03*
X1095700Y265900D03*
X1078962Y231797D03*
X1082341Y241547D03*
X1085721Y235696D03*
X1075582Y241547D03*
X1045904Y236409D03*
X1035765Y230559D03*
X1072202Y235696D03*
X1057314Y228610D03*
X1042524Y230559D03*
X1049284D03*
X1057314Y236409D03*
X1049284Y355360D03*
X1052664Y361209D03*
X1035765Y367060D03*
X1045904Y384609D03*
X1039145D03*
X1049284Y390460D03*
X1052664Y396309D03*
X1049284Y386560D03*
X1048154Y402900D03*
X1052500Y400400D03*
X1049284Y378760D03*
X1039145Y372909D03*
X1042524Y378760D03*
X1035765D03*
X1045904Y372909D03*
X1083462Y356596D03*
X1086841Y370247D03*
X1073322Y358547D03*
X1083462Y364396D03*
X1093601Y354647D03*
X1090221Y360496D03*
X1080082Y358547D03*
X1093601Y381947D03*
X1090221Y387796D03*
X1073322Y393647D03*
X1083462Y383896D03*
X1073322Y378047D03*
X1080082Y389747D03*
X1060694Y394359D03*
Y386560D03*
Y382660D03*
Y378760D03*
X1086841Y378047D03*
X1090221Y376096D03*
X1093601Y374146D03*
X1061055Y363160D03*
X1060963Y370959D03*
X1064371Y367060D03*
X1076702Y364396D03*
X1073322Y370247D03*
X1080082Y374146D03*
X1045904Y361209D03*
X1052664Y372909D03*
X1042524Y367060D03*
X1049284D03*
X1039145Y361209D03*
X1076702Y383896D03*
X1066300Y396700D03*
X1109381Y218147D03*
X1116141Y206446D03*
X1133040Y216196D03*
X1129660Y218147D03*
X1133040Y212296D03*
X1106001Y220096D03*
X1116141Y225947D03*
X1102621Y222047D03*
Y225947D03*
X1112761Y220096D03*
Y227896D03*
X1109381Y229847D03*
X1116141Y241547D03*
X1112761Y235696D03*
X1119521Y243496D03*
Y235696D03*
X1106001D03*
X1102621Y241547D03*
X1099241Y231797D03*
Y243496D03*
Y235696D03*
X1107600Y271900D03*
X1114340Y280560D03*
X1151060Y251296D03*
X1126280Y220096D03*
X1133040Y231797D03*
X1122900Y222047D03*
Y225947D03*
X1133040Y220096D03*
X1129660Y229847D03*
X1126280Y235696D03*
X1122900Y241547D03*
X1157820Y243496D03*
X1133040Y239596D03*
X1136420Y261047D03*
X1133040Y262996D03*
X1151060Y255196D03*
X1147680Y261047D03*
X1144300Y259096D03*
X1151060Y262996D03*
X1147680Y253247D03*
Y257147D03*
X1134160Y272747D03*
X1109381Y264947D03*
X1129660Y249347D03*
X1109381D03*
X1126280Y247396D03*
X1102621Y249347D03*
X1116141D03*
X1129660Y257147D03*
X1122900Y253247D03*
X1133040Y247396D03*
Y255196D03*
X1136420Y253247D03*
X1121500Y273338D03*
X1113740Y274852D03*
X1116096Y295809D03*
X1099391Y337001D03*
X1105800Y336830D03*
X1114839Y320075D03*
X1157820Y309797D03*
X1134160Y303947D03*
X1130780Y321496D03*
X1137540Y313696D03*
X1130780Y325396D03*
X1140920Y315647D03*
X1134160Y319547D03*
X1130780Y317596D03*
Y333196D03*
X1134160Y331247D03*
X1115230Y289252D03*
X1101100Y332200D03*
X1111900Y334199D03*
X1123769Y290624D03*
X1123256Y282984D03*
X1123747Y298283D03*
X1113881Y370247D03*
X1100361D03*
X1103741Y360496D03*
X1100361Y354647D03*
Y362447D03*
X1113881Y354647D03*
X1110501Y356596D03*
Y360496D03*
X1096981Y356596D03*
X1117261D03*
X1096981Y364396D03*
X1117261D03*
X1107121Y366347D03*
X1103741Y387796D03*
X1100361Y381947D03*
X1113881Y389747D03*
X1110501Y383896D03*
X1117261Y379996D03*
X1096981Y391696D03*
X1117261Y383896D03*
Y387796D03*
X1103741Y376096D03*
X1110501D03*
X1124021Y368296D03*
X1130780Y364396D03*
X1124021Y360496D03*
X1120641Y354647D03*
Y362447D03*
X1140920Y354647D03*
X1137540Y356596D03*
X1124021Y383896D03*
X1120641Y389747D03*
X1144300Y399496D03*
X1130780Y383896D03*
Y387796D03*
X1140920Y393647D03*
X1137540Y379996D03*
Y383896D03*
Y387796D03*
X1134160Y374146D03*
X1120641D03*
X1127400D03*
X1157820Y383896D03*
X1156699Y401447D03*
X1127400Y370247D03*
X1147680D03*
X1157820Y364396D03*
X1216100Y106520D03*
X1208519Y218147D03*
X1178099Y223996D03*
X1174719Y241547D03*
X1178099Y239596D03*
X1174719Y245447D03*
X1178099Y251296D03*
X1171339Y270796D03*
X1178099Y266896D03*
Y262996D03*
X1191619Y223996D03*
X1181479Y253247D03*
X1164580Y243496D03*
X1181479Y331247D03*
X1198379Y321496D03*
X1194999Y323446D03*
X1181479Y315647D03*
X1191619Y337096D03*
X1181479Y323446D03*
X1171339Y337096D03*
X1174719Y331247D03*
X1178099Y321496D03*
X1174719Y327347D03*
X1167960Y335147D03*
X1171339Y329296D03*
X1178099Y333196D03*
Y325396D03*
X1171339Y333196D03*
X1178099Y329296D03*
X1174719Y319547D03*
X1161201Y401447D03*
X1178099Y368296D03*
X1164580Y391696D03*
X1171339Y352696D03*
X1164580Y364396D03*
X1167960Y350747D03*
X1161200Y362447D03*
Y358547D03*
X1201000Y402200D03*
X1210917Y647292D03*
Y651232D03*
X1257500Y142000D03*
X1259371Y129171D03*
X1268401Y137250D03*
X1262900Y140050D03*
X1221300Y106600D03*
X1235165Y129710D03*
X1229600Y128300D03*
X1242000Y125000D03*
X1263300Y172440D03*
X1263401Y240889D03*
X1276337Y243490D03*
X1269500Y235900D03*
X1240640Y495440D03*
X1246300Y495000D03*
X1249500Y483800D03*
X1242100Y484100D03*
X1254000Y477310D03*
X1266900Y469500D03*
X1250574Y647266D03*
Y651206D03*
X1327700Y31200D03*
X1297010Y21510D03*
X1325100Y145000D03*
X1315180Y169950D03*
X1315130Y164870D03*
X1298051Y204392D03*
X1336100Y200300D03*
X1285000Y211000D03*
X1287743Y262956D03*
X1308130Y252600D03*
X1334600Y228400D03*
X1294909Y248409D03*
X1308400Y263300D03*
X1302000Y282300D03*
X1330257Y293443D03*
X1315183Y289917D03*
X1315177Y297177D03*
X1335250Y341350D03*
X1327400Y327195D03*
X1317834Y342234D03*
X1336600Y323400D03*
X1333500Y356500D03*
X1315496Y354100D03*
X1321068Y349234D03*
X1332075Y438600D03*
X1314700Y577400D03*
X1302200Y605300D03*
X1375212Y967D03*
X1371123Y41033D03*
X1369500Y107500D03*
X1380100Y165000D03*
Y160000D03*
X1393500Y213250D03*
X1402918Y278082D03*
X1390800Y279000D03*
X1361558Y325942D03*
X1352285Y321824D03*
X1349700Y341500D03*
X1378900Y336600D03*
X1377966Y332783D03*
X1378900Y341000D03*
X1350200Y332700D03*
X1392657Y288900D03*
X1386400Y362150D03*
X1349700Y347800D03*
X1383806Y372597D03*
X1399960Y391476D03*
X1386792Y378855D03*
X1378071Y386200D03*
X1344253Y354242D03*
X1373830Y398940D03*
X1378880Y352370D03*
X1390100Y432500D03*
X1377028Y458125D03*
X1375100Y447500D03*
X1390100Y452500D03*
X1372028Y458125D03*
X1352266Y503491D03*
X1373426Y516634D03*
X1377700Y587500D03*
X1388600Y577800D03*
X1390389Y585211D03*
X1378930Y612980D03*
X1452017Y16800D03*
X1457674Y16774D03*
X1415400Y23730D03*
X1421400Y16700D03*
X1456790Y87112D03*
X1420337Y48377D03*
X1414091Y46412D03*
X1464800Y132900D03*
X1435500Y145400D03*
X1439451Y140149D03*
X1441600Y146400D03*
X1434581Y117098D03*
X1428000Y124600D03*
X1444500Y126600D03*
X1433500Y151419D03*
X1457572Y134510D03*
X1457694Y96494D03*
X1415712Y213300D03*
X1417963Y206280D03*
X1465610Y214440D03*
X1411950Y198838D03*
X1457043Y161495D03*
X1432600Y161300D03*
X1406050Y200850D03*
X1465650Y209350D03*
X1450250Y161330D03*
X1454079Y157468D03*
X1466400Y195243D03*
X1415800Y188600D03*
X1415819Y181981D03*
X1427100Y159100D03*
X1415985Y174791D03*
X1443715Y253769D03*
X1449919Y252409D03*
X1451858Y257896D03*
X1423475Y269600D03*
X1464340Y247410D03*
X1437923Y269627D03*
X1407200Y269600D03*
X1441600Y258300D03*
X1425304Y234733D03*
X1425469Y239829D03*
X1449497Y264519D03*
X1447345Y260523D03*
X1462950Y267913D03*
X1444948Y264505D03*
X1465830Y271083D03*
X1439700Y300400D03*
X1423407Y281739D03*
X1436812Y285989D03*
X1432344Y289437D03*
X1410990Y334390D03*
X1438958Y329999D03*
X1443150Y315080D03*
X1464476Y315500D03*
X1443400Y285700D03*
X1422553Y326188D03*
X1431194Y327707D03*
X1434624Y294777D03*
X1460154Y382938D03*
X1454814Y379245D03*
X1429100Y361300D03*
X1425828Y347928D03*
X1451850Y392790D03*
X1458800Y426700D03*
X1453400Y423000D03*
X1407200Y521500D03*
X1424116Y518484D03*
X1428200Y563500D03*
X1465950Y612290D03*
X1473550Y14150D03*
X1492700Y12300D03*
X1468000Y17100D03*
X1515000Y-3242D03*
X1525000Y-1587D03*
X1510500Y-300D03*
X1473886Y35185D03*
X1511900Y34100D03*
X1516017Y38841D03*
X1521741Y65151D03*
X1482500Y77500D03*
Y83500D03*
X1520887Y44028D03*
X1479138Y130320D03*
X1468635Y119025D03*
X1489000Y135955D03*
X1489252Y152111D03*
X1508700Y112400D03*
X1481100Y102500D03*
X1481300Y96900D03*
X1472887Y204496D03*
X1481500Y161617D03*
X1484800Y157800D03*
X1516000Y189200D03*
X1523400Y212400D03*
X1475564Y200130D03*
X1513779Y182078D03*
X1523000Y199100D03*
X1498387Y264666D03*
X1522210Y234190D03*
X1516450Y227011D03*
X1511440Y250974D03*
X1519400Y268480D03*
X1505500Y269500D03*
X1469330Y249069D03*
X1522717Y221027D03*
X1517608Y221216D03*
X1472824Y267123D03*
X1506137Y248182D03*
X1467469Y277500D03*
X1487078Y253972D03*
X1490963Y276277D03*
X1499900Y277100D03*
X1511710Y311070D03*
X1521350Y322417D03*
X1504217Y294890D03*
X1467542Y300987D03*
X1477393Y316431D03*
X1482996Y292960D03*
X1467700Y311397D03*
X1489600Y293300D03*
X1482200Y318600D03*
X1507500Y300606D03*
X1467613Y306048D03*
X1469801Y318200D03*
X1517700Y303082D03*
X1489200Y299100D03*
X1485850Y350500D03*
X1501360Y367320D03*
X1499350Y370850D03*
X1495300Y374100D03*
X1476100Y390000D03*
X1485850Y344600D03*
X1476150Y383860D03*
X1491000Y367687D03*
X1493600Y354020D03*
X1518245Y361300D03*
X1521050Y371700D03*
X1523700Y366200D03*
X1515183Y372400D03*
X1477800Y370800D03*
X1512000Y346100D03*
X1483497Y375917D03*
X1527478Y352860D03*
X1474626Y362517D03*
X1509800Y372300D03*
X1504600Y372200D03*
X1507800Y366600D03*
X1481081Y356230D03*
X1468190Y383870D03*
X1484756Y440623D03*
X1515070Y527170D03*
X1520747Y508200D03*
X1524583Y489586D03*
X1471220Y519260D03*
X1520300Y494000D03*
X1472000Y532000D03*
X1524415Y647322D03*
X1516158Y616032D03*
X1481778Y614716D03*
X1524415Y651262D03*
X1547716Y6046D03*
X1530367Y-1587D03*
X1583001Y-10700D03*
X1569553Y32168D03*
X1580398Y2300D03*
X1583256Y29400D03*
X1581409Y48148D03*
X1558285Y54807D03*
X1539299Y73184D03*
X1564100Y59266D03*
X1555623Y41553D03*
X1565637Y52524D03*
X1543200Y42303D03*
X1568950Y99252D03*
X1567820Y115200D03*
X1588600Y150500D03*
X1536000Y135000D03*
X1574665Y106417D03*
X1528346Y147595D03*
X1535061Y109559D03*
X1561693Y136074D03*
X1563506Y142982D03*
X1545500Y138500D03*
X1535338Y141386D03*
X1576870Y127078D03*
X1537249Y118153D03*
X1589700Y169000D03*
X1555800Y167300D03*
X1576679Y171209D03*
X1575600Y166000D03*
X1588847Y175137D03*
X1561000Y168500D03*
X1582627Y198617D03*
X1574600Y185400D03*
X1574500Y206100D03*
X1574700Y201100D03*
X1574900Y196000D03*
X1579700Y206200D03*
X1588799Y162838D03*
X1567500Y158100D03*
X1549000Y160500D03*
X1561400Y263000D03*
X1553532Y231913D03*
X1548996Y265700D03*
X1566260Y256040D03*
X1559350Y255050D03*
X1538443Y265371D03*
X1587500Y236486D03*
X1543400Y277900D03*
X1579600Y235100D03*
X1532526Y227200D03*
X1579900Y223500D03*
X1537150Y229238D03*
X1562900Y243600D03*
X1568230Y287330D03*
X1542972Y296758D03*
X1532080Y310820D03*
X1582659Y334237D03*
X1587300Y338400D03*
X1535813Y326540D03*
X1545000Y336900D03*
X1576168Y313332D03*
X1555100Y356000D03*
X1549303Y358875D03*
X1585298Y383013D03*
X1576305Y371122D03*
X1580029Y356304D03*
X1576129Y377952D03*
X1546350Y363400D03*
X1565188Y351991D03*
X1585600Y375200D03*
X1543651Y368755D03*
X1540300Y371800D03*
X1534000Y371500D03*
X1536800Y367300D03*
X1528339Y372339D03*
X1529400Y367200D03*
X1554150Y371303D03*
X1585650Y389001D03*
X1578750Y391060D03*
X1571598Y355435D03*
X1580253Y383700D03*
X1575310Y444790D03*
X1581000Y465400D03*
X1583060Y449320D03*
X1578840Y473176D03*
X1584500Y579009D03*
X1585830Y592132D03*
X1556630Y610070D03*
X1541610Y593700D03*
X1571080Y591445D03*
X1569257Y614855D03*
X1567300Y601700D03*
X1594821Y31300D03*
X1608500Y-12800D03*
X1631500Y12200D03*
X1601200Y32300D03*
Y20000D03*
X1623400Y17500D03*
X1601502Y3437D03*
X1597244Y43700D03*
X1617688Y79904D03*
X1635841Y47859D03*
X1603000Y63000D03*
X1641000Y35500D03*
X1614000Y63500D03*
X1619750Y63650D03*
X1624500Y50890D03*
X1627330Y44800D03*
X1603900Y41300D03*
X1615400Y39800D03*
X1640000Y60000D03*
X1638580Y76500D03*
X1622000Y84500D03*
X1648700Y82100D03*
X1640732Y106227D03*
X1592510Y140471D03*
X1591700Y146200D03*
X1591366Y108251D03*
X1603804Y146096D03*
X1592700Y154600D03*
X1630300Y101900D03*
X1635384Y105507D03*
X1646200Y103800D03*
X1612103Y131920D03*
X1633994Y200254D03*
X1597302Y162132D03*
X1596730Y189030D03*
X1619958Y206643D03*
X1613002Y169672D03*
X1634170Y168900D03*
X1637825Y171672D03*
X1640910Y192600D03*
X1645395Y169192D03*
X1641375Y170017D03*
X1606538Y173091D03*
X1604326Y203326D03*
X1609116Y170006D03*
X1604275Y164859D03*
X1617078Y169100D03*
X1632000Y173800D03*
X1651064Y171331D03*
X1591606Y198319D03*
X1649621Y236279D03*
X1605200Y263833D03*
X1643750Y267900D03*
X1594500Y277500D03*
X1593250Y245553D03*
X1644700Y260900D03*
X1589954Y229054D03*
X1610550Y222670D03*
X1597000Y265900D03*
X1648911Y326711D03*
X1613000Y337900D03*
X1641055Y324176D03*
X1605090Y336004D03*
X1631419Y319313D03*
X1642022Y318523D03*
X1624900Y377400D03*
X1595076Y353237D03*
X1599300Y350200D03*
X1651163Y384645D03*
X1649530Y375170D03*
X1640000Y348800D03*
X1628843Y411524D03*
X1599539Y436752D03*
X1596800Y430500D03*
X1628439Y439800D03*
X1629913Y463000D03*
X1623300Y458910D03*
X1623527Y453915D03*
X1612500Y414700D03*
X1609138Y505050D03*
X1632762Y502957D03*
X1627500Y502000D03*
X1615307Y466679D03*
X1651486Y500217D03*
X1598013Y557397D03*
X1596200Y576250D03*
X1669500Y28500D03*
X1683210Y-10630D03*
X1700130Y77700D03*
X1662100Y85000D03*
X1666693Y95300D03*
X1679147Y78085D03*
X1670500Y64500D03*
X1694200Y44500D03*
X1694070Y64800D03*
X1703727Y74152D03*
X1667497Y47202D03*
X1663000Y76400D03*
X1667000Y56000D03*
X1678974Y51626D03*
X1682158Y59955D03*
X1680958Y66942D03*
X1692470Y69740D03*
X1688060Y43900D03*
X1665876Y62596D03*
X1673415Y94797D03*
X1662675Y106475D03*
X1672222Y98726D03*
X1667600Y106232D03*
X1654875Y115278D03*
X1713137Y213138D03*
X1653496Y167799D03*
X1660891Y169381D03*
X1708922Y204564D03*
X1701500Y208600D03*
X1656700Y171014D03*
X1708600Y182800D03*
X1656200Y199700D03*
X1677558Y189941D03*
X1681670Y169940D03*
X1710650Y176650D03*
X1671209Y176011D03*
X1665500Y226000D03*
X1656500Y247500D03*
X1674500Y228513D03*
X1689019Y253510D03*
X1665000Y254000D03*
X1668648Y265000D03*
X1669348Y240862D03*
X1655821Y236554D03*
X1666500Y231900D03*
X1661872Y338515D03*
X1654937Y338572D03*
X1661600Y333100D03*
X1668735Y344282D03*
X1653396Y390402D03*
X1680520Y445012D03*
X1665900Y447000D03*
X1681336Y457690D03*
X1658482Y498975D03*
X1656197Y503552D03*
X1701960Y585390D03*
X1705683Y589300D03*
X1762600Y15500D03*
X1774600Y8800D03*
X1769730Y10070D03*
X1728460Y71300D03*
X1735800Y54650D03*
X1741044Y65498D03*
X1759525Y56400D03*
X1743600Y43900D03*
X1736600Y44700D03*
X1735850Y49650D03*
X1731280Y89220D03*
X1757383Y63002D03*
X1745650Y91850D03*
X1764900Y91800D03*
X1727860Y93920D03*
X1753370Y88520D03*
X1744600Y150900D03*
X1760200Y108900D03*
X1765000Y102000D03*
X1764900Y97000D03*
X1721000Y193706D03*
X1718900Y448000D03*
X1718230Y452955D03*
X1768200Y505700D03*
X1715489Y493890D03*
X1771502Y501944D03*
X1738500Y581700D03*
X1738600Y565100D03*
X1728537Y589342D03*
X1716438Y600400D03*
X1748100Y607000D03*
X1744700Y593700D03*
X1782900Y9500D03*
X1833210Y-3910D03*
X1777685Y12830D03*
X1787164Y31113D03*
X1835600Y13000D03*
X1793720Y7387D03*
X1787969Y47993D03*
X1779440Y52250D03*
X1797840Y49720D03*
X1782949Y155900D03*
X1832177Y150500D03*
X1792000Y118100D03*
X1788000Y114500D03*
X1817767Y101100D03*
X1797620Y148240D03*
X1817715Y172398D03*
X1806032Y256368D03*
X1820341Y254616D03*
X1821100Y239200D03*
X1829971Y233712D03*
X1834500Y250000D03*
X1835900Y244600D03*
X1821600Y227200D03*
X1826662Y228000D03*
X1795358Y238669D03*
X1800728Y238920D03*
X1824850Y511050D03*
X1808134Y495734D03*
X1817950Y517500D03*
X1825600Y482100D03*
X1821441Y528960D03*
X1821895Y588200D03*
X1834700Y556500D03*
X1814138Y548444D03*
X1809290Y549668D03*
X1800683Y572968D03*
X1826600Y549500D03*
X1784650Y566000D03*
X1776200Y578650D03*
X1783400Y570900D03*
X1779950Y575300D03*
X1776400Y583900D03*
X1827211Y597431D03*
X1786450Y590040D03*
X1783200Y597400D03*
X1781600Y592600D03*
X1846500Y10500D03*
X1864706Y34766D03*
X1836800Y91000D03*
X1854482Y82583D03*
X1871460Y73390D03*
X1891494Y70584D03*
X1895000Y61600D03*
X1886800Y72500D03*
X1858700Y49700D03*
X1866100Y51600D03*
X1871812Y39088D03*
X1866376Y67105D03*
X1860100Y111500D03*
X1879700Y155700D03*
X1868844Y103130D03*
X1892000Y126500D03*
X1867400Y139050D03*
X1854477Y212365D03*
X1844110Y206600D03*
X1868000Y199100D03*
X1840783Y169326D03*
X1841900Y174200D03*
X1885719Y232386D03*
X1856422Y456400D03*
X1848511Y445558D03*
X1861312Y457446D03*
X1866900Y458400D03*
X1851150Y477640D03*
X1860500Y469800D03*
X1848200Y510500D03*
X1880242Y515942D03*
X1838843Y568874D03*
X1896800Y551900D03*
X1852190Y537760D03*
X1865300Y584950D03*
X1851600Y551400D03*
X1892554Y565000D03*
X1842730Y545224D03*
X1836909Y528586D03*
X1839200Y589619D03*
X1916660Y70070D03*
X1944740Y81810D03*
X1948458Y149021D03*
X1915700Y144200D03*
X1930000Y114608D03*
X1929800Y151900D03*
X1916700Y122700D03*
X1902370Y147000D03*
X1916400Y127900D03*
X1916700Y196700D03*
X1921100Y199269D03*
X1925520Y179160D03*
X1935300Y172600D03*
X1900230Y204500D03*
X1921900Y158100D03*
X1933900Y167600D03*
X1901400Y161200D03*
X1944173Y200444D03*
X1954070Y177088D03*
X1927300Y201000D03*
X1942345Y206525D03*
X1937800Y163000D03*
X1954143Y172000D03*
X1937430Y469860D03*
X1951800Y477900D03*
X1943500Y471000D03*
X1927138Y480071D03*
X1953440Y495050D03*
X1959300Y525500D03*
X1930402Y516640D03*
X1945170Y510870D03*
X1925800Y567500D03*
X1956100Y537500D03*
X1925808Y562498D03*
X1904800Y577700D03*
X1919500Y558900D03*
X1904790Y586240D03*
X1930625Y566185D03*
X1930600Y561000D03*
X1959100Y542500D03*
X1954350Y545350D03*
X1924800Y586400D03*
X1936970Y590600D03*
X1913180Y601923D03*
X1906900Y603200D03*
X1910150Y597900D03*
X1921700Y613500D03*
X1907240Y610410D03*
X1902800Y599200D03*
X1914500Y613600D03*
X1962780Y231794D03*
X1964281Y525057D03*
X1960078Y550793D03*
X1960700Y531600D03*
X1964100Y608000D03*
X1964300Y601900D03*
G54D212*
X1928842Y222302D03*
X1930810D03*
X1934747D03*
X1936716D03*
X1928842Y220003D03*
X1930810D03*
X1934747D03*
X1936716D03*
G54D221*
X1961890Y211043D03*
Y238405D03*
G54D131*
X1457000Y104700D03*
X1474100Y237800D03*
X1585849Y108488D03*
X1582849Y99488D03*
X1825700Y29700D03*
X1938600Y458717D03*
G54D240*
G01X1057314Y244209D02*
X1055742D01*
X1053839Y242306D01*
Y235588D01*
X1050978Y232727D01*
X1048568D01*
X1046631Y230790D01*
X1045157D01*
X1043363Y232584D01*
X1041652D01*
X1039858Y230790D01*
X1038432D01*
X1036638Y232584D01*
X1034926D01*
X1034465Y232123D01*
X1034431D01*
X1033098Y230790D01*
X1031672D01*
X1030339Y232123D01*
X1030305D01*
X1029844Y232584D01*
X1027982D01*
X1026338Y234228D01*
X1024909D01*
X1022722Y236415D01*
X1021723D01*
X1019704Y238434D01*
X1017991D01*
X1016198Y236641D01*
X1014737D01*
X1012944Y238434D01*
X1011266D01*
X1009473Y236641D01*
X1007977D01*
X1006184Y238434D01*
X1004471D01*
X1002678Y236641D01*
X1001218D01*
X999425Y238434D01*
X997564D01*
X995919Y240079D01*
X994488D01*
X992539Y242028D01*
X991110D01*
X989057Y244081D01*
X987819D01*
X985616Y246284D01*
X984426D01*
X982525Y248185D01*
X980662D01*
X978557Y250290D01*
X977128D01*
X975177Y252241D01*
X974107D01*
X972264Y254084D01*
X970553D01*
X970043Y254594D01*
X968218D01*
G01X1049284Y246160D02*
X1051400Y244044D01*
Y237889D01*
X1050111Y236600D01*
X1048962D01*
X1046699Y234337D01*
X1045085D01*
X1043165Y236257D01*
X1041883D01*
X1039947Y234321D01*
X1038409D01*
X1036536Y236194D01*
X1035042D01*
X1033137Y234289D01*
X1031630D01*
X1029616Y236303D01*
X1028605D01*
X1026428Y238480D01*
X1024827D01*
X1023149Y240158D01*
X1021473D01*
X1019545Y242086D01*
X1018208D01*
X1016312Y240190D01*
X1014666D01*
X1012808Y242048D01*
X1011402D01*
X1009473Y240119D01*
X1007990D01*
X1006006Y242103D01*
X1004707D01*
X1002950Y240346D01*
X1002915D01*
X1002804Y240235D01*
X1001126D01*
X998871Y242490D01*
X997873D01*
X995922Y244441D01*
X994493D01*
X992544Y246390D01*
X991113D01*
X989162Y248341D01*
X987733D01*
X985784Y250290D01*
X984353D01*
X982824Y251819D01*
X980963D01*
X978592Y254190D01*
X977593D01*
X975948Y255835D01*
X974087D01*
X972288Y257634D01*
X971289D01*
X968830Y260093D01*
X967589D01*
G54D231*
G01X471463Y269816D02*
Y268682D01*
X472031Y267312D01*
Y266514D01*
X471296Y264740D01*
X468934D01*
X468169Y263975D01*
Y262273D01*
X468290Y262152D01*
Y260200D01*
X467343Y259253D01*
G01X460817Y255398D02*
X458885D01*
X458004Y254517D01*
X457721Y253833D01*
X457290Y253402D01*
X455970D01*
X454927Y252359D01*
X454688Y251783D01*
X454021Y251116D01*
X452244D01*
G01X448634Y253090D02*
X450270D01*
X450917Y253737D01*
X451193Y254403D01*
X452164Y255374D01*
X453778D01*
G01X476048Y304911D02*
Y324348D01*
X476378Y324678D01*
Y326202D01*
X475280Y327300D01*
X473559D01*
X471033Y329826D01*
Y339047D01*
G01X1065242Y239596D02*
X1069504D01*
X1071282Y237818D01*
X1073238D01*
X1073875Y237181D01*
X1074110Y236614D01*
X1074873Y235851D01*
X1076579D01*
X1078530Y237802D01*
X1079759D01*
X1081360Y239403D01*
X1083287D01*
X1084034Y240150D01*
X1084379Y240980D01*
X1085101Y241702D01*
X1086718D01*
X1088357Y243341D01*
X1089788D01*
X1091947Y245500D01*
X1093376D01*
X1095376Y247500D01*
X1096807D01*
X1098497Y249190D01*
X1099919D01*
X1100540Y249811D01*
X1100859Y250579D01*
X1101748Y251468D01*
X1103468D01*
X1105090Y253090D01*
X1106690D01*
X1108641Y255041D01*
X1109774D01*
X1112069Y257336D01*
X1113792D01*
X1115709Y259253D01*
X1116867D01*
X1118816Y261202D01*
X1120361D01*
X1121337Y262178D01*
Y263972D01*
X1121106Y264203D01*
Y265691D01*
X1121316Y265901D01*
Y267893D01*
X1121106Y268103D01*
Y269591D01*
X1121500Y269985D01*
Y273338D01*
G01X1065242Y243496D02*
X1069604D01*
X1071398Y241702D01*
X1072843D01*
X1073499Y241046D01*
X1073836Y240233D01*
X1074660Y239409D01*
X1076414D01*
X1077408Y240403D01*
X1077713Y241140D01*
X1078275Y241702D01*
X1079689D01*
X1080418Y242431D01*
X1080545Y242738D01*
X1081460Y243653D01*
X1083340D01*
X1084977Y245290D01*
X1086406D01*
X1088669Y247553D01*
X1089845D01*
X1091794Y249502D01*
X1093225D01*
X1095176Y251453D01*
X1096605D01*
X1098554Y253402D01*
X1100238D01*
X1101877Y255041D01*
X1103263D01*
X1103927Y255705D01*
X1104228Y256431D01*
X1105119Y257322D01*
X1107018D01*
X1108637Y258941D01*
X1110068D01*
X1112329Y261202D01*
X1113758D01*
X1115709Y263153D01*
X1116913D01*
X1118000Y264240D01*
Y265879D01*
X1117727Y266152D01*
Y267640D01*
X1118029Y267942D01*
Y269801D01*
X1117517Y270313D01*
Y272821D01*
X1116534Y273804D01*
Y283049D01*
X1114583Y285000D01*
X1112397D01*
X1111256Y286141D01*
G01X1068822Y245447D02*
X1069015Y245254D01*
X1073246D01*
X1073788Y244712D01*
Y244703D01*
X1074838Y243653D01*
X1076326D01*
X1078275Y245602D01*
X1079706D01*
X1081657Y247553D01*
X1083085D01*
X1084722Y249190D01*
X1086406D01*
X1088357Y251141D01*
X1089788D01*
X1092049Y253402D01*
X1093478D01*
X1095117Y255041D01*
X1096548D01*
X1098497Y256990D01*
X1099926D01*
X1102189Y259253D01*
X1103365D01*
X1105314Y261202D01*
X1106745D01*
X1108384Y262841D01*
X1110322D01*
X1111005Y263524D01*
X1111829Y264757D01*
X1112227Y265719D01*
Y268073D01*
X1113740Y269586D01*
Y274852D01*
G01X1129194Y314694D02*
Y315889D01*
X1128639Y317229D01*
Y317531D01*
X1128367Y317803D01*
X1126677D01*
X1125500Y318980D01*
Y324408D01*
X1125765Y324673D01*
Y326444D01*
G01X1364260Y331619D02*
Y332203D01*
X1365087Y333030D01*
Y334650D01*
G01X1374500Y328900D02*
X1376900D01*
X1378100Y330100D01*
Y332649D01*
X1377966Y332783D01*
G01X1374500Y328900D02*
X1371000D01*
G01X1377966Y332783D02*
X1376500Y334249D01*
Y336163D01*
X1375450Y337213D01*
X1373950D01*
G01Y341938D02*
X1376400D01*
G54D222*
G01X1507625Y415175D02*
X1509200Y413600D01*
G01X1528100Y410550D02*
X1527050Y411600D01*
X1523550D01*
G01X1812852Y591601D02*
X1813505Y590948D01*
Y587899D01*
G01X1807599Y600103D02*
Y605099D01*
X1808500Y606000D01*
G54D105*
X695450Y226500D03*
X1363639Y8476D03*
X1363260Y40490D03*
X1348857Y360095D03*
X1365707Y399408D03*
X1367460Y587276D03*
X1363850Y616400D03*
X1416400Y558398D03*
X1424301Y558435D03*
X1557329Y618572D03*
X1565707Y618555D03*
G54D30*
X46777Y-16430D03*
Y-8830D03*
X35677Y-16430D03*
Y-8830D03*
X706270Y243945D03*
Y236345D03*
X714900Y244090D03*
Y236490D03*
X723604Y237024D03*
Y229424D03*
X736500Y208700D03*
Y216300D03*
X732344Y237043D03*
Y229443D03*
X741055Y241836D03*
Y234236D03*
X1380000Y414300D03*
Y406700D03*
X1372000Y414300D03*
Y406700D03*
X1364000Y414300D03*
Y406700D03*
X1388000Y414300D03*
Y406700D03*
X1356655Y523455D03*
Y531055D03*
X1398950Y574260D03*
Y581860D03*
X1429261Y568923D03*
Y576523D03*
X1437013Y568923D03*
Y576523D03*
X1409404Y574063D03*
Y581663D03*
X1448526Y593422D03*
Y601022D03*
X1456694Y618570D03*
Y610970D03*
X1448694Y618570D03*
Y610970D03*
X1440694Y618570D03*
Y610970D03*
X1922224Y216107D03*
X1914569Y216096D03*
X1922224Y223707D03*
X1914569Y223696D03*
X1968487Y214193D03*
Y221793D03*
G54D132*
X1456250Y209500D03*
X1432750Y217180D03*
Y209500D03*
Y201820D03*
X1456250D03*
Y217180D03*
Y204380D03*
Y206940D03*
Y212060D03*
Y214620D03*
X1432750Y204380D03*
Y206940D03*
Y212060D03*
Y214620D03*
X1457838Y176527D03*
X1434338Y184207D03*
Y176527D03*
Y168847D03*
X1457838D03*
Y184207D03*
Y171407D03*
Y173967D03*
Y179087D03*
Y181647D03*
X1434338Y171407D03*
Y173967D03*
Y179087D03*
Y181647D03*
X1458250Y232000D03*
X1434750Y239680D03*
Y232000D03*
Y224320D03*
X1458250D03*
Y239680D03*
Y226880D03*
Y229440D03*
Y234560D03*
Y237120D03*
X1434750Y226880D03*
Y229440D03*
Y234560D03*
Y237120D03*
X1484750Y205750D03*
Y198250D03*
X1506250Y200750D03*
Y208250D03*
X1484750Y215750D03*
X1506250D03*
X1484750Y208250D03*
Y210750D03*
Y200750D03*
Y203250D03*
X1506250D03*
Y205750D03*
Y210750D03*
Y213250D03*
Y198250D03*
X1484750Y213250D03*
X1485450Y232250D03*
Y224750D03*
X1506950Y227250D03*
Y234750D03*
X1485450Y242250D03*
X1506950D03*
X1485450Y234750D03*
Y237250D03*
Y227250D03*
Y229750D03*
X1506950D03*
Y232250D03*
Y237250D03*
Y239750D03*
Y224750D03*
X1485450Y239750D03*
X1703250Y62680D03*
Y55000D03*
Y47320D03*
Y49880D03*
Y52440D03*
Y57560D03*
Y60120D03*
X1726750Y55000D03*
Y47320D03*
Y62680D03*
Y49880D03*
Y52440D03*
Y57560D03*
Y60120D03*
G54D204*
X1923379Y78770D03*
X1918379D03*
X1928379D03*
X1933379D03*
Y105370D03*
X1918379D03*
X1923379D03*
X1928379D03*
G54D150*
X1567299Y215920D03*
Y210920D03*
Y205920D03*
Y200920D03*
Y195920D03*
Y190920D03*
Y185920D03*
X1530149D03*
Y190920D03*
Y195920D03*
Y200920D03*
Y205920D03*
Y210920D03*
Y215920D03*
X1567299Y220920D03*
X1530149D03*
G54D213*
X1932779Y221153D03*
G54D141*
X1410808Y472742D03*
G54D114*
X1233239Y366212D03*
G54D12*
G01X20390Y24559D02*
X16585D01*
X16400Y24744D01*
G01X14025Y56211D02*
X13776Y56460D01*
Y59655D01*
G01X38645Y172740D02*
X44291Y178386D01*
G01D02*
X49937Y184032D01*
G01X38645D02*
X44291Y178386D01*
G01D02*
X49937Y172740D01*
G01X-7615D02*
X-1969Y178386D01*
G01D02*
X3677Y184032D01*
G01X-7615D02*
X-1969Y178386D01*
G01D02*
X3677Y172740D01*
G01X30000Y285500D02*
X44600D01*
X46350Y283750D01*
Y279510D01*
X46600Y279260D01*
Y275900D01*
X52300Y270200D01*
X70400D01*
G01X27280Y510420D02*
Y511060D01*
X31600Y515380D01*
Y517600D01*
G01X3500Y534500D02*
X418D01*
G01X58308Y-17864D02*
X61166D01*
X62486Y-19184D01*
G01X89100Y124700D02*
Y126081D01*
X87501Y127680D01*
X85250D01*
G01X93714Y124724D02*
X89124D01*
X89100Y124700D01*
G01X70400Y270200D02*
X73500D01*
X75500Y272200D01*
Y274000D01*
G01X53500Y307300D02*
X55359D01*
X56872Y308813D01*
Y310550D01*
G01X337642Y32100D02*
X334292D01*
G01X324642D02*
X321334D01*
G01X312442Y69900D02*
X311942Y70400D01*
X307992D01*
G01X332078Y328060D02*
Y324160D01*
G01X304329Y528301D02*
Y523134D01*
G01D02*
Y523133D01*
G01X307675Y580623D02*
Y574757D01*
G01X304329Y560933D02*
Y560934D01*
G01X307675Y536957D02*
Y542823D01*
G01X304329Y560934D02*
Y566139D01*
G01X312342Y589800D02*
X310700D01*
X309500Y591000D01*
X307892D01*
G01X430749Y-124922D02*
G02I-12000J0D01*
G01X425599D02*
G02I-6850J0D01*
G01X434749D02*
X402749D01*
G01X404700Y13200D02*
X408184D01*
G01X417150D02*
X421368D01*
G01X408892Y-15000D02*
Y-20130D01*
X409522Y-20760D01*
Y-20794D01*
G01X378792Y6500D02*
X375792D01*
G01X378292Y13078D02*
Y7000D01*
X378792Y6500D01*
G01X390900Y-15300D02*
Y-12992D01*
X394192Y-9700D01*
G01X379592Y-5810D02*
X380200Y-5202D01*
Y-1200D01*
G01X379592Y-5810D02*
X380232Y-6450D01*
Y-10900D01*
G01X401892Y-15000D02*
X399450D01*
X399150Y-15300D01*
X396400D01*
G01X401375Y-7108D02*
Y-10455D01*
G01D02*
X401892Y-10972D01*
Y-15000D01*
G01X371042Y46900D02*
X374534D01*
X378312Y50678D01*
Y51178D01*
G01X378120Y551360D02*
X377980Y551220D01*
Y547454D01*
X376829Y546303D01*
G01X372760Y618220D02*
X367799D01*
X367706Y618127D01*
G01X374039Y611186D02*
Y616941D01*
X372760Y618220D01*
G01X434749Y-140922D02*
Y-220922D01*
G01D02*
X1729349D01*
G01X434749Y-176422D02*
X1729349D01*
G01X418749Y-140922D02*
Y-108922D01*
G01X434749Y-140922D02*
X1729349D01*
G01X430150Y13200D02*
X433508D01*
G01X422892Y-15000D02*
Y-20789D01*
G01X436392Y-15000D02*
Y-20760D01*
G01X429392Y-15000D02*
X428147Y-13755D01*
Y-7108D01*
G01X454919Y528501D02*
Y523134D01*
G01D02*
Y523133D01*
G01X448226Y528073D02*
Y523134D01*
G01D02*
Y523133D01*
G01Y505024D02*
Y496414D01*
X448250Y496390D01*
G01X451573Y505024D02*
Y500024D01*
X452056Y499541D01*
Y497496D01*
X450950Y496390D01*
G01D02*
X448250D01*
G01X452120Y490771D02*
Y495220D01*
X450950Y496390D01*
G01X454919Y560934D02*
Y566722D01*
G01Y560933D02*
Y560934D01*
G01X451573Y574799D02*
Y580623D01*
G01X598817Y566699D02*
Y568703D01*
G01X664267Y292668D02*
X664246D01*
Y292800D01*
X666246Y294800D01*
X667500D01*
G01X687100Y578500D02*
Y584870D01*
X683960Y588010D01*
X677330D01*
X674920Y585600D01*
X663820D01*
G01X687100Y578500D02*
Y576650D01*
X684500Y574050D01*
Y559400D01*
X694500Y549400D01*
Y507500D01*
X683500Y496500D01*
X680500D01*
G01X686375Y527778D02*
X686097Y527500D01*
X680800D01*
X679800Y528500D01*
G01X687100Y578500D02*
X694600D01*
X696600Y580500D01*
Y581400D01*
G01D02*
X703600D01*
X709499Y575501D01*
X712464D01*
X713965Y574000D01*
X716000D01*
G01D02*
X718026Y571974D01*
Y571524D01*
X721350Y568200D01*
X725021D01*
G01D02*
X728200D01*
X730000Y570000D01*
Y574500D01*
G01X684500Y532900D02*
X683400Y534000D01*
X679800D01*
G01X753600Y-4300D02*
X753208Y-4692D01*
Y-8400D01*
G01X747150Y522560D02*
X740784D01*
X734650Y516426D01*
Y503700D01*
X732150Y501200D01*
X729350D01*
G01X730000Y574500D02*
Y576500D01*
X733500Y580000D01*
Y599700D01*
X729200Y604000D01*
X727000D01*
G01X755500Y612000D02*
Y614000D01*
X755000Y614500D01*
G01X941849Y-140922D02*
Y-220922D01*
G01X962050Y69900D02*
X961550Y70400D01*
X957600D01*
G01X953939Y560934D02*
X953937D01*
G01X957283Y574757D02*
Y580623D01*
G01X961950Y552000D02*
X957701D01*
G01X953937Y560933D02*
Y560934D01*
G01D02*
Y565684D01*
G01X957283Y542823D02*
Y536957D01*
G01X1030400Y26150D02*
Y23200D01*
X1030450Y23150D01*
G01X1028400Y6500D02*
X1029400Y7500D01*
Y13078D01*
G01X1030621Y-15762D02*
Y-9152D01*
X1030407Y-8938D01*
G01X1010800Y50500D02*
X1009959Y49659D01*
X1007370D01*
G01X1028600Y51400D02*
Y45900D01*
X1031600Y42900D01*
G01X1079349Y-140922D02*
Y-220922D01*
G01X1072500Y-16000D02*
Y-15000D01*
G01X1065500D02*
Y-12117D01*
X1067716Y-9901D01*
G01X1050983Y-7108D02*
Y-11483D01*
X1051500Y-12000D01*
Y-15000D01*
G01X1079000D02*
Y-11250D01*
X1077755Y-10005D01*
G01D02*
Y-7108D01*
G01X1061258Y51000D02*
X1061024Y51234D01*
Y54857D01*
G01X1050984Y54842D02*
Y53176D01*
X1048808Y51000D01*
G01X1081104Y79623D02*
Y73744D01*
G01X1091143Y79623D02*
Y73744D01*
G01X1057679Y79623D02*
Y73744D01*
G01X1047639Y79623D02*
Y73744D01*
G01X1074409Y73742D02*
Y79623D01*
G01X1067718D02*
X1067716D01*
G01X1081104Y73744D02*
X1081102Y73742D01*
G01X1091143Y73744D02*
X1091141Y73742D01*
G01X1057679Y73744D02*
X1057677Y73742D01*
G01X1047639Y73744D02*
X1047637Y73742D01*
G01X1074409Y79623D02*
X1074411D01*
G01X1067716D02*
Y73742D01*
G01X1097836Y523134D02*
X1097834D01*
G01Y528965D02*
Y523134D01*
G01X1104529D02*
X1104527D01*
G01Y523133D02*
Y523134D01*
G01D02*
Y528557D01*
G01X1097834Y523134D02*
Y523133D01*
G01X1097836Y560934D02*
X1097834D01*
G01Y569200D02*
Y560934D01*
G01X1101181Y542823D02*
Y536999D01*
G01X1097834Y560934D02*
Y560933D01*
G01X1104529Y560934D02*
Y553866D01*
X1104177Y553514D01*
G01X1097834Y542823D02*
Y536929D01*
G01X1104529Y560934D02*
Y568361D01*
G01X1097834Y536929D02*
X1098040Y536723D01*
G01X1104529Y568361D02*
X1104141Y568749D01*
G01X1194349Y-140922D02*
Y-220922D01*
G01X1221682Y113956D02*
X1218254D01*
G01X1224916D02*
X1221682D01*
G01X1224916D02*
X1224924Y113948D01*
G01X1224916Y113956D02*
X1224700Y114172D01*
Y150150D01*
X1221767Y153083D01*
Y175858D01*
G01X1248425Y566699D02*
Y570817D01*
X1248608Y571000D01*
G01X1266108D02*
X1267900Y572792D01*
Y574300D01*
G01X1336850Y76450D02*
X1333600Y73200D01*
Y71510D01*
G01Y68000D02*
Y71510D01*
G01X1338500Y101500D02*
Y96000D01*
G01Y107000D02*
X1339029Y107529D01*
X1345500D01*
G01X1331650Y317250D02*
Y313844D01*
X1329300Y311494D01*
Y300300D01*
X1333467Y296133D01*
X1338091D01*
X1342476Y291748D01*
Y282766D01*
X1345050Y280192D01*
Y272350D01*
G01X1335900Y518300D02*
X1336500Y518900D01*
X1339900D01*
G01X1304500Y619000D02*
X1306500D01*
X1307600Y620100D01*
G01X1361849Y-140922D02*
Y-220922D01*
G01X1366810Y40490D02*
Y38090D01*
X1367100Y37800D01*
G01X1370975Y67225D02*
X1372250Y68500D01*
X1375500D01*
G01X1457000Y101250D02*
X1455441D01*
X1452908Y103783D01*
X1452626D01*
Y103788D01*
X1452648D01*
G01X1531849Y-140922D02*
Y-220922D01*
G01X1577700Y155353D02*
X1577947Y155600D01*
X1580950D01*
G01X1580599Y159838D02*
Y157650D01*
X1580950Y157299D01*
Y155600D01*
G01X1581099Y140038D02*
X1579256D01*
X1579145Y140149D01*
X1577700D01*
G01X1581099Y143038D02*
Y140038D01*
G01X1580950Y146100D02*
Y143187D01*
X1581099Y143038D01*
G01X1577700Y140149D02*
X1576187Y138636D01*
Y136939D01*
G01X1588156Y129138D02*
X1591356D01*
G01X1583500Y132500D02*
X1586862Y129138D01*
X1588156D01*
G01X1576187Y131439D02*
Y131703D01*
X1578188Y133704D01*
X1582296D01*
X1583500Y132500D01*
G01X1576414Y121287D02*
X1579402D01*
X1580164Y122049D01*
G01X1573121Y120649D02*
X1573484Y121012D01*
X1574724D01*
X1574999Y121287D01*
X1576414D01*
G01X1578920Y190920D02*
X1581453D01*
X1582249Y191716D01*
G01X1580599Y159838D02*
Y162838D01*
G01X1585479Y316610D02*
Y314444D01*
X1587971Y311952D01*
G01X1627642Y-14488D02*
X1627654Y-14500D01*
X1667000D01*
X1667012Y-14488D01*
G01X1621500Y25750D02*
Y29250D01*
G01X1637750Y17000D02*
X1640650Y19900D01*
Y23815D01*
X1642585Y25750D01*
X1644000D01*
G01X1603800Y51450D02*
X1601250D01*
X1600300Y52400D01*
Y54450D01*
G01X1619250Y43311D02*
X1611467D01*
X1610812Y42656D01*
X1608044D01*
X1603800Y46900D01*
Y51450D01*
G01X1609144Y55244D02*
X1605350Y51450D01*
X1603800D01*
G01X1619250Y38750D02*
Y43311D01*
G01X1599500Y84500D02*
Y87400D01*
X1597750Y89150D01*
Y90500D01*
G01X1616891Y124939D02*
X1616498Y124546D01*
Y122472D01*
G01X1620040Y128089D02*
X1619998Y128047D01*
Y122472D01*
G01X1654000Y128000D02*
X1651625D01*
X1651536Y128089D01*
G01X1648500Y125250D02*
X1651225D01*
X1651536Y124939D01*
G01X1635000Y122250D02*
X1632650D01*
X1632618Y122218D01*
X1629618D01*
G01X1635750Y115500D02*
Y118602D01*
X1635788Y118640D01*
G01X1635000Y122250D02*
X1637166D01*
X1637416Y122000D01*
X1639250D01*
G01X1635788Y118640D02*
Y119448D01*
X1635000Y120236D01*
Y122250D01*
G01X1591356Y129138D02*
X1593666D01*
X1593756Y129048D01*
G01X1645237Y118640D02*
X1648090D01*
G01X1620092Y156055D02*
X1623666D01*
X1624049Y156438D01*
G01D02*
Y155576D01*
X1626313Y153312D01*
G01X1611750Y102500D02*
X1612550Y103300D01*
X1615611D01*
X1616849Y104538D01*
G01X1618750Y109500D02*
Y108620D01*
X1616849Y106719D01*
Y104538D01*
G01X1619291Y113140D02*
Y111490D01*
X1618750Y110949D01*
Y109500D01*
G01X1619291Y113140D02*
Y114581D01*
X1619388Y114678D01*
Y116340D01*
G01X1642649Y179288D02*
Y180603D01*
X1643887Y181841D01*
G01X1648450Y189600D02*
Y188050D01*
X1650200Y186300D01*
X1650600D01*
G01D02*
X1651000D01*
X1653099Y188399D01*
Y189608D01*
G01X1648349Y179288D02*
Y182276D01*
G01D02*
X1650861D01*
X1653849Y179288D01*
G01X1645700Y214050D02*
X1644968D01*
X1636337Y222681D01*
X1625758D01*
X1622634Y219557D01*
X1619056D01*
X1612743Y225870D01*
X1607040D01*
X1605760Y224590D01*
G01X1645700Y214050D02*
Y213335D01*
X1651174Y207861D01*
X1655595D01*
X1655629Y207827D01*
X1655978D01*
G01X1590495Y214525D02*
X1590664Y214356D01*
Y208374D01*
X1593558Y205480D01*
X1596080D01*
G01X1592750Y385500D02*
Y382500D01*
G01Y388500D02*
Y385500D01*
G01X1595352Y369117D02*
Y366117D01*
G01Y372117D02*
Y369117D01*
G01X1592750Y382500D02*
Y379500D01*
G01X1665000Y19750D02*
Y19500D01*
X1664750Y19250D01*
Y16500D01*
G01X1666500Y10500D02*
X1667844Y11844D01*
Y15656D01*
X1667000Y16500D01*
X1664750D01*
G01X1665000Y19750D02*
X1663250D01*
X1660040Y22960D01*
G01X1657500Y128000D02*
Y125275D01*
X1657835Y124940D01*
G01X1657179Y179278D02*
X1657169Y179288D01*
X1653849D01*
G01X1686000Y165650D02*
X1685416Y166234D01*
Y175974D01*
X1687819Y178377D01*
X1701102D01*
X1702500Y179775D01*
Y187000D01*
G01X1729349Y-140922D02*
Y-220922D01*
G01X1757349Y-124922D02*
G02I-12000J0D01*
G01X1752199D02*
G02I-6850J0D01*
G01X1745349Y-140922D02*
Y-108922D01*
G01X1761349Y-124922D02*
X1729349D01*
G01X1769250Y84570D02*
X1769777D01*
X1771707Y86500D01*
G01X1780700Y104500D02*
X1773750D01*
G01X1834300Y41100D02*
X1837000Y43800D01*
Y48500D01*
G01X1807745Y104500D02*
Y101901D01*
X1805344Y99500D01*
G01D02*
X1802300D01*
G01X1788627Y125981D02*
X1787121D01*
X1786502Y126600D01*
X1783673D01*
X1782150Y125077D01*
Y122850D01*
X1783500Y121500D01*
Y119000D01*
G01X1780700Y104500D02*
Y106492D01*
X1783252Y109044D01*
G01X1780623Y117269D02*
X1781769D01*
X1783500Y119000D01*
G01X1783252Y109044D02*
X1784915Y110707D01*
Y117585D01*
X1783500Y119000D01*
G01X1798250Y535300D02*
X1804551D01*
X1807752Y538501D01*
G01X1808500Y606000D02*
X1805500D01*
X1805000Y606500D01*
G01X1854482Y82583D02*
X1857495Y79570D01*
Y75405D01*
X1858600Y74300D01*
G01X1849426Y95500D02*
Y90700D01*
G01D02*
Y87639D01*
X1854482Y82583D01*
G01X1858600Y74300D02*
X1858736Y74164D01*
X1861565D01*
X1862539Y75138D01*
G01X1869383Y142500D02*
X1867000Y144883D01*
Y151000D01*
G01D02*
Y152435D01*
X1857526Y161909D01*
X1855369D01*
G01X1870900Y179700D02*
Y176200D01*
X1868375Y173675D01*
Y171900D01*
G01X1868440Y171965D02*
X1868375Y171900D01*
G01X1870900Y179700D02*
X1871000Y179800D01*
Y191100D01*
G01X1878600D02*
Y192036D01*
X1882452Y195888D01*
G01X1878500Y179700D02*
Y191000D01*
X1878600Y191100D01*
G01X1878500Y179700D02*
Y178600D01*
X1881100Y176000D01*
G01X1882452Y195888D02*
X1883880Y194460D01*
X1892860D01*
X1895435Y197035D01*
X1898265D01*
X1901100Y194200D01*
G01X1855369Y161909D02*
X1852654Y164624D01*
G01X1898750Y187500D02*
Y185800D01*
X1896250Y183300D01*
G01X1898750Y187500D02*
X1893100D01*
X1889400Y191200D01*
G01X1890750Y183300D02*
X1888850D01*
X1886400Y180850D01*
Y178700D01*
G01X1909661Y-16368D02*
X1906838D01*
X1906438Y-15968D01*
G01X1913161Y-16368D02*
Y-19554D01*
X1913143Y-19572D01*
G01X1913161Y-16368D02*
X1916078D01*
G01X1918379Y78770D02*
Y84788D01*
G01X1925535Y136078D02*
X1928100D01*
G01X1925535Y132578D02*
Y126932D01*
X1919790Y121187D01*
Y119000D01*
G01D02*
X1910500D01*
G01X1936599Y138000D02*
X1935399Y136800D01*
X1932240D01*
X1930600Y135160D01*
Y135041D01*
X1929137Y133578D01*
X1927950D01*
X1926950Y132578D01*
X1925535D01*
G01X1905092Y150170D02*
X1902580D01*
X1901400Y151350D01*
G01X1903150Y217250D02*
X1906500Y220600D01*
Y223650D01*
G01X1905800Y191050D02*
X1907800D01*
X1908000Y191250D01*
X1910500D01*
G01X1901750Y191000D02*
X1901800Y191050D01*
X1905800D01*
G01X1901100Y194200D02*
X1901750Y193550D01*
Y191000D01*
G01X1922013Y179468D02*
X1925212D01*
X1925520Y179160D01*
G01X1922013Y189468D02*
Y184468D01*
G01Y179468D02*
Y184468D01*
G01X1925520Y179160D02*
X1927268D01*
X1928249Y178179D01*
G01X1950981Y191218D02*
X1953082D01*
X1954841Y189459D01*
Y187424D01*
G01X1954818Y181882D02*
X1954841Y181905D01*
Y187424D01*
G01X1958902Y163045D02*
X1956563D01*
X1956244Y163364D01*
X1954041D01*
G01X1958902Y163045D02*
Y168357D01*
X1964360Y173815D01*
X1967473D01*
X1969473Y171815D01*
Y169460D01*
G01X1927300Y201000D02*
Y199737D01*
X1930554Y196483D01*
X1933383D01*
X1935600Y198700D01*
G01X1915031Y208189D02*
Y206635D01*
G01D02*
X1918001Y203665D01*
X1918583D01*
X1918696Y203552D01*
X1922348D01*
X1924900Y201000D01*
X1927300D01*
G01X1932700Y203335D02*
X1934435Y201600D01*
X1940344D01*
X1942345Y203601D01*
Y206525D01*
G01X1922431Y208449D02*
X1926880Y204000D01*
X1928544D01*
X1929209Y203335D01*
X1932700D01*
G01X1942345Y206525D02*
X1942385Y206565D01*
X1944766D01*
X1952717Y198614D01*
G01X1968487Y214193D02*
X1965040D01*
X1961890Y211043D01*
G01X1969473Y169460D02*
Y167514D01*
X1968871Y166912D01*
Y163564D01*
G01D02*
X1970926D01*
X1972598Y165236D01*
X-20700Y31400D03*
Y25200D03*
Y22300D03*
Y28100D03*
X-20600Y41200D03*
X-20526Y44263D03*
X-16602Y81858D03*
Y79358D03*
X-20500Y60300D03*
Y57300D03*
X-20700Y48800D03*
X-20726Y37463D03*
X-20800Y34400D03*
X-20500Y54300D03*
Y51300D03*
X-19210Y162529D03*
X-15768Y161922D03*
X-18000Y247400D03*
X-15000D03*
X-18000Y262700D03*
X-15000D03*
X-17014Y455604D03*
X-14800Y526100D03*
X-16700Y497400D03*
X-17200Y510800D03*
X-17302Y506798D03*
X-19802Y476738D03*
X-19783Y481286D03*
X-18160Y522609D03*
X-16186Y519304D03*
X-14690Y471140D03*
X-16726Y503651D03*
X-14971Y540000D03*
X-17300Y530800D03*
X-17500Y574000D03*
X-17397Y564242D03*
X30600Y-12000D03*
X22499Y-19381D03*
X19924Y-18875D03*
X19964Y18793D03*
X16550Y18300D03*
X25060Y16214D03*
X25838Y-20458D03*
X25827Y-16958D03*
X38227Y-20485D03*
X42520Y-16896D03*
X41677Y-14390D03*
X602Y30502D03*
X2871Y22791D03*
X-10850Y30800D03*
X34719Y19455D03*
X8660Y27274D03*
X16400Y24744D03*
X10600Y25100D03*
X1068Y24831D03*
X27102Y25383D03*
X40530Y20220D03*
X43960Y20572D03*
X39530Y5205D03*
X45670Y5185D03*
X33370D03*
X45429Y-4669D03*
X33628Y131D03*
X40994Y-7148D03*
X45700Y40D03*
X11539Y31427D03*
X27200Y30600D03*
X27239Y28027D03*
X25600Y32500D03*
X11600Y33944D03*
X37739Y19501D03*
X13716Y24861D03*
X26760Y49595D03*
X-8610Y59810D03*
X-1750Y43320D03*
X-1920Y47290D03*
X27800Y86900D03*
X22100Y56400D03*
X6500Y84400D03*
X6600Y87900D03*
X27800Y89900D03*
Y83900D03*
X9425Y88067D03*
X11925D03*
X30400Y89800D03*
Y86800D03*
Y83800D03*
X8700Y49700D03*
X-1470Y63910D03*
X1863Y59426D03*
X1572Y38307D03*
X14025Y56211D03*
X-3560Y34620D03*
X-13610Y64360D03*
X-9987Y50899D03*
X-7050Y50900D03*
X-10470Y64450D03*
X-8370Y62600D03*
X-6010Y61030D03*
X-9390Y67410D03*
X8988Y58267D03*
X3600Y36200D03*
X16625Y56211D03*
X3100Y65900D03*
X10925Y56167D03*
X27904Y56294D03*
X30686Y79943D03*
X23530Y94840D03*
X11030D03*
X13530D03*
X16030D03*
X18530D03*
X22380Y92670D03*
X21030Y94840D03*
X2380Y92670D03*
X4880D03*
X7380D03*
X9880D03*
X12380D03*
X14880D03*
X17380D03*
X19880D03*
X3530Y94840D03*
X6030D03*
X8530D03*
X-1000Y81500D03*
X24880Y92670D03*
X25870Y80880D03*
X28294Y80889D03*
X32500Y81791D03*
X35650Y91150D03*
X34000Y93350D03*
X5500Y77444D03*
X5600Y80444D03*
X11625Y81267D03*
X9125D03*
X-8562Y81858D03*
Y79358D03*
X-14102Y81858D03*
Y79358D03*
X-5912Y84258D03*
X-8812Y84308D03*
X-5930Y79358D03*
X-5860Y81858D03*
X-11452Y79308D03*
Y81808D03*
X9225Y84467D03*
X11725D03*
X25100Y56300D03*
X-1190Y53240D03*
X11200Y49600D03*
X14010Y49570D03*
X11925Y74867D03*
X11864Y71294D03*
X11539Y39927D03*
X11500Y43400D03*
X11539Y47127D03*
X25886Y71467D03*
X25925Y75867D03*
X26185Y67017D03*
X27488Y64671D03*
X11925Y65311D03*
X27625Y73967D03*
X27525Y69367D03*
X11925Y67811D03*
X11864Y62794D03*
X24064Y61894D03*
X15111Y62553D03*
X27564Y61894D03*
X11600Y36444D03*
X25900Y40300D03*
X27564Y59394D03*
X24064D03*
X25700Y36200D03*
X27300Y34300D03*
Y38300D03*
X27208Y42313D03*
X27239Y47027D03*
X25700Y44400D03*
X27525Y77867D03*
X11864Y78494D03*
X1382Y68100D03*
X44200Y139400D03*
X44300Y144800D03*
X44200Y130700D03*
Y116800D03*
X44100Y97800D03*
X44200Y111500D03*
X44300Y102700D03*
Y125600D03*
X39109Y154901D03*
X44600Y154100D03*
X37037Y138425D03*
X46900Y139750D03*
X47309Y154356D03*
X46900Y144750D03*
Y130750D03*
Y116750D03*
Y97750D03*
Y102750D03*
Y111750D03*
Y125750D03*
X-12861Y163165D03*
X5120Y276058D03*
X2269Y273532D03*
X19904Y254162D03*
X41000Y265350D03*
X37000D03*
X41000Y274647D03*
X37000Y275000D03*
X44310Y268160D03*
X33490Y267900D03*
X3806Y302347D03*
X1500Y295000D03*
X7995Y285385D03*
X6806Y302347D03*
X2450Y460000D03*
X32450Y454050D03*
X35100Y453900D03*
X35900Y423500D03*
X37550Y425400D03*
X43550Y431300D03*
X40965Y429434D03*
X20075Y424850D03*
X12025Y427900D03*
Y424850D03*
X17025D03*
X7025Y427900D03*
X2025D03*
Y424850D03*
X7025D03*
X21397Y439354D03*
Y444354D03*
X24447Y439354D03*
Y444354D03*
X10786Y441785D03*
X15786D03*
X18836D03*
X7736D03*
X10365Y461602D03*
X-6100Y464840D03*
X11100Y446200D03*
X-6104Y461190D03*
X46100Y416271D03*
Y413520D03*
X5000Y469000D03*
X2350Y469650D03*
X10443Y490649D03*
X40132Y499800D03*
X-6712Y515731D03*
X2160Y479000D03*
X-6676Y501800D03*
X44050Y504383D03*
X-9900Y486400D03*
X-13500D03*
X17000Y475500D03*
X-6650Y487800D03*
X-14190Y473840D03*
X-5690Y467840D03*
X14500Y475500D03*
X11972Y475417D03*
X5100Y478330D03*
X-11490Y473840D03*
X-2430Y524340D03*
X-4350Y482100D03*
X2589Y481983D03*
X-900Y482300D03*
X22491Y500618D03*
X24400Y519500D03*
X280Y524350D03*
X-9600Y526100D03*
X46507Y523953D03*
X40185Y482918D03*
X37568Y482836D03*
X34300Y482890D03*
X31477Y482788D03*
X26780Y488910D03*
X41993Y523425D03*
X37000Y511200D03*
X39200Y509500D03*
X40111Y520623D03*
X31800Y510600D03*
X38389Y523748D03*
X34300Y511000D03*
X37600Y507400D03*
X35707Y509055D03*
X21000Y495800D03*
X6748Y517021D03*
X3354Y517143D03*
X13300Y509600D03*
X13600Y504300D03*
X4000Y509500D03*
X2485Y498185D03*
X13700Y498500D03*
X24591Y479139D03*
X35896Y557668D03*
X33396D03*
X38696D03*
X-10200Y558200D03*
X3600Y531300D03*
X-10947Y544117D03*
X-4100Y554400D03*
X-9287Y531604D03*
X21700Y532300D03*
X19100D03*
X27000D03*
X1040Y531218D03*
X-8318Y542216D03*
X6200Y531300D03*
X-3100Y533991D03*
X21948Y566700D03*
X19448D03*
X27114Y557563D03*
X24748Y566700D03*
X0Y566800D03*
X-8200Y578600D03*
X6200Y567300D03*
X-2500Y569500D03*
X-12600Y578900D03*
X-4300Y558400D03*
X1400Y556500D03*
X-1200D03*
X3600Y567300D03*
X-9283Y571324D03*
X29400Y532300D03*
X46400Y536290D03*
Y539790D03*
X43505Y538714D03*
X43241Y535965D03*
X41500Y533800D03*
X29914Y557563D03*
X45880Y554710D03*
Y557820D03*
X46560Y581000D03*
Y577500D03*
X1439Y546583D03*
Y553783D03*
X1539Y550183D03*
X1500Y540600D03*
X15787Y551700D03*
X17100Y545400D03*
X13639Y534683D03*
Y537183D03*
X15800Y543300D03*
X15600Y539100D03*
X17139Y534683D03*
Y537183D03*
X17100Y541200D03*
X17035Y549558D03*
X15800Y547500D03*
X17139Y553683D03*
X1500Y543100D03*
X1439Y538083D03*
X15800Y579500D03*
Y575300D03*
X17108Y585513D03*
X17156Y581481D03*
X17100Y577400D03*
X17139Y573183D03*
X1500Y576600D03*
X17139Y570683D03*
X1500Y579100D03*
X1539Y586183D03*
X1439Y582583D03*
Y574083D03*
X15770Y587700D03*
X15800Y583500D03*
X27495Y591409D03*
X-900Y592500D03*
X1600D03*
X-4500Y594000D03*
X-12450Y590965D03*
X30212Y591417D03*
X35085Y591621D03*
X32609Y591538D03*
X46500Y595190D03*
X43190Y598410D03*
X43210Y595180D03*
X43190Y601910D03*
X1439Y589783D03*
X17139Y589683D03*
X77000Y25992D03*
X74000D03*
X62000Y28500D03*
X59500D03*
X65000D03*
X68000D03*
X71000D03*
X74000D03*
X77000D03*
X80000Y29000D03*
Y26000D03*
X62000D03*
X59500D03*
X65000D03*
X71000Y25992D03*
X68000D03*
X65800Y14200D03*
X59061Y476D03*
X61152Y-12752D03*
X71172Y-18486D03*
X52389Y-14258D03*
X52744Y-4368D03*
X74386Y-18439D03*
X67564Y-20745D03*
X65164Y-19456D03*
X59281Y-20641D03*
X104500Y-1850D03*
X64159Y11303D03*
X50586Y-20687D03*
X63683Y-12866D03*
X66061Y-13689D03*
X60035Y7508D03*
X106000Y17260D03*
X87091Y-16391D03*
X88777Y-10586D03*
X82300Y-16600D03*
X93500Y-18000D03*
X82013Y14129D03*
X79372Y14895D03*
X79096Y9886D03*
X79116Y12361D03*
X81669Y11693D03*
X81610Y9159D03*
X64200Y17389D03*
X99102Y-12010D03*
X105892Y8700D03*
X62076Y5575D03*
X76247Y1189D03*
X84202Y-11395D03*
X81702D03*
X79202D03*
X73611Y1158D03*
X71111D03*
X68611D03*
X73574Y-1437D03*
X71074D03*
X68574D03*
X79500Y-16600D03*
X55713Y-5095D03*
X76165Y-1415D03*
X62008Y13249D03*
X106200Y26500D03*
X61446Y18238D03*
X62536Y-2379D03*
X61994Y362D03*
X54307Y-8051D03*
X62486Y-19184D03*
X60500Y79000D03*
X70500Y70500D03*
X73000D03*
X78000D03*
X75500D03*
X81000Y61500D03*
Y58500D03*
X63000Y74000D03*
X60500D03*
X63000Y76500D03*
X60500D03*
X67500Y49500D03*
X70500D03*
X73500D03*
X79500D03*
X61500Y43500D03*
X59000D03*
X64500D03*
X67500D03*
X70500D03*
X60500Y70500D03*
X63000D03*
X61500Y58500D03*
Y49500D03*
X59000Y56000D03*
X61500D03*
X59000Y49500D03*
X76500Y43500D03*
X79500Y82000D03*
Y46500D03*
X76500D03*
X73500D03*
X70500D03*
X67500D03*
X64500D03*
X59000D03*
X61500D03*
X68000Y70500D03*
X65500D03*
X79500Y43500D03*
X63000Y81500D03*
X59000Y58500D03*
X61500Y61000D03*
X59000D03*
X76500Y49500D03*
X73500Y43500D03*
X64500Y49500D03*
X79500Y79000D03*
X63000D03*
X60500Y81500D03*
X79500Y72500D03*
X102100Y73800D03*
X105892Y45290D03*
X52500Y67200D03*
Y63700D03*
Y60700D03*
Y37700D03*
Y34700D03*
Y43700D03*
Y40700D03*
Y57700D03*
X82046Y90043D03*
X100140Y83170D03*
X79725Y75993D03*
X71050Y89600D03*
X48700Y90700D03*
Y95500D03*
X61300Y89800D03*
X81861Y93392D03*
X86600Y94000D03*
X76106Y89337D03*
X108385Y84291D03*
X68725Y90900D03*
X63725D03*
X51381Y90750D03*
X105898Y55194D03*
X63737Y130602D03*
X48900Y132600D03*
X68592D03*
X85250Y127680D03*
X77730Y126860D03*
X63858Y97620D03*
X66600Y102360D03*
X62422Y109413D03*
X68000Y111000D03*
X48900Y123500D03*
X62524Y123395D03*
X68584Y123900D03*
X68654Y118680D03*
X48800Y118900D03*
X48700Y109600D03*
X48600Y104900D03*
X63582Y116409D03*
X62502Y105100D03*
X52500Y152000D03*
X60300Y151500D03*
X70800Y151400D03*
X79670Y132300D03*
X91913Y121318D03*
X77790Y121030D03*
X70980Y97166D03*
X104424Y110833D03*
X98420Y112198D03*
X48800Y137600D03*
X63878Y144800D03*
X68632Y137800D03*
X63888Y140064D03*
X87200Y152374D03*
X107254Y128041D03*
X75660Y152380D03*
X78950Y152810D03*
X51381Y104750D03*
Y109750D03*
X63098Y151473D03*
X68098D03*
X51309Y154356D03*
X51569Y132750D03*
Y118750D03*
X51381Y95750D03*
X51569Y123750D03*
Y137750D03*
X65384Y109750D03*
Y104750D03*
X65405Y118730D03*
X60831Y144750D03*
X65687Y132750D03*
X60831Y130750D03*
X60700Y116750D03*
X60801Y97750D03*
X60831Y139750D03*
X65687Y137750D03*
X60831Y125750D03*
X65405Y123730D03*
X60700Y111750D03*
X60801Y102750D03*
X106698Y215610D03*
X102507Y211047D03*
X107700Y211040D03*
X100500Y188600D03*
X97500Y185700D03*
X104800D03*
X102400D03*
X99900D03*
X77650Y178150D03*
X76143Y183019D03*
X61402Y177773D03*
X97900Y194500D03*
X104820Y198800D03*
X97800Y197600D03*
X104820Y202100D03*
X90831Y184982D03*
X86952Y181721D03*
X87151Y184872D03*
X61800Y191600D03*
X99250Y160370D03*
X107750Y238730D03*
X99500Y223800D03*
X83300Y267400D03*
X84000Y272500D03*
X79300Y272300D03*
X57500Y254100D03*
X62000Y278000D03*
X59500D03*
X108000Y249330D03*
X99758Y240300D03*
X53400Y277582D03*
Y274500D03*
X69125Y310625D03*
X98538Y341139D03*
X94360Y335210D03*
X94938Y323467D03*
X92086Y324258D03*
X48800Y282600D03*
Y285100D03*
X53500Y307300D03*
X48800Y292400D03*
Y289600D03*
X53400Y298100D03*
X61900Y286200D03*
X68300Y281600D03*
X70900D03*
X66300Y285850D03*
X58700Y283000D03*
X58600Y297200D03*
X58700Y299800D03*
X88600Y302997D03*
X75626Y310418D03*
X72100Y321800D03*
X79410Y331636D03*
X84000Y324542D03*
X53100Y327000D03*
X74800Y338850D03*
X69000Y338800D03*
X72000D03*
X81324Y316119D03*
X82500Y341400D03*
X65800Y338900D03*
X54400Y340300D03*
X64000Y313900D03*
Y316500D03*
X56300Y338500D03*
X79400Y325400D03*
X74887Y321780D03*
X79600Y335200D03*
X49200Y340650D03*
X87400Y337200D03*
X77600Y320800D03*
X68418Y336150D03*
X53100Y315000D03*
X59452Y338800D03*
X82150Y335800D03*
X66900Y322000D03*
X85300Y335750D03*
X69500Y322000D03*
X58400Y314600D03*
X77300Y315600D03*
X53000Y323500D03*
X52804Y333247D03*
X61300Y328600D03*
X84000Y316083D03*
X70700Y330349D03*
X103500Y302100D03*
X93500Y289000D03*
X93400Y296000D03*
X103500Y304700D03*
Y308500D03*
X102322Y295478D03*
X104600Y316602D03*
X103200Y335190D03*
X100550Y335140D03*
X103200Y330190D03*
X88840Y324740D03*
X98680Y338080D03*
X99770Y325249D03*
X71500Y298000D03*
X66000Y292700D03*
X76800Y298000D03*
X76900Y292600D03*
X66500Y303400D03*
X76800D03*
X62900Y339000D03*
X67400Y391690D03*
X67230Y397380D03*
X64725Y391645D03*
Y396645D03*
X67710Y402040D03*
X65384Y403258D03*
X93712Y380507D03*
X66350Y347950D03*
X87900Y347500D03*
X88000Y343900D03*
X51900Y351000D03*
X63800Y348600D03*
X58271Y363669D03*
X61041Y351737D03*
X49091Y351509D03*
X49017Y346509D03*
X49117Y349009D03*
X49017Y344009D03*
X55616Y368998D03*
X52000Y354500D03*
X60400Y355750D03*
X90518Y388828D03*
X54900Y389400D03*
X74800Y383114D03*
X85609Y385234D03*
X61000Y383000D03*
X57500Y388100D03*
X77300Y390600D03*
X101880Y346300D03*
X102060Y351759D03*
X101750Y360120D03*
X101965Y368296D03*
X107224Y393848D03*
X50510Y359240D03*
X47970Y359550D03*
X76500Y368300D03*
X76300Y358400D03*
X82037Y358542D03*
X70600Y368400D03*
X82100Y368300D03*
X70900Y358300D03*
X102040Y348960D03*
X54244Y405624D03*
X51500Y406000D03*
X57471Y410749D03*
X56383Y408163D03*
X63024Y405636D03*
X64007Y408276D03*
X61005Y429305D03*
Y424305D03*
X63630Y424280D03*
X63600Y429000D03*
X49265Y423995D03*
Y418995D03*
X51890Y424470D03*
Y418970D03*
X54662Y416478D03*
X51645Y416281D03*
X103100Y411800D03*
X65450Y475610D03*
X67477Y477940D03*
X47800Y487600D03*
X47550Y504367D03*
X66750Y521900D03*
Y519400D03*
X64503Y521054D03*
X64380Y523606D03*
Y526202D03*
X64600Y515600D03*
X66750Y516900D03*
X64600Y518100D03*
X66840Y526800D03*
Y524300D03*
X47369Y527005D03*
X55500Y521800D03*
X53000Y524300D03*
Y521800D03*
X58000D03*
X55500Y519300D03*
X52992Y516846D03*
X58000Y524300D03*
X57936Y519212D03*
X53900Y505450D03*
X57100D03*
X60300D03*
X55500Y524300D03*
X53000Y519300D03*
X53900Y502250D03*
X60300D03*
X57100D03*
X88855Y522359D03*
X86100Y505200D03*
X72603Y474072D03*
X59731Y480066D03*
X66016Y468350D03*
X89497Y479201D03*
X60300Y508650D03*
X51607Y511747D03*
X74480Y504480D03*
X79630Y504580D03*
X60000Y526500D03*
X79400Y502150D03*
X74600Y502064D03*
X77000Y502133D03*
X49800Y524300D03*
X76996Y504587D03*
X60700Y521900D03*
X57936Y516012D03*
X60202Y495342D03*
X57302Y495442D03*
X105958Y518550D03*
X91650Y522000D03*
X94998Y481612D03*
X106392Y527413D03*
X77960Y541468D03*
Y538468D03*
X75461Y541468D03*
Y538468D03*
X73009Y541444D03*
Y538444D03*
X62500Y535500D03*
X71500Y575000D03*
Y578000D03*
Y582000D03*
X81500Y575000D03*
X78500D03*
X81500Y578000D03*
X78500D03*
X74500Y575000D03*
Y578000D03*
Y582000D03*
X81500D03*
X78500D03*
X75500Y557500D03*
X72500Y561500D03*
Y557500D03*
X69500Y561500D03*
Y557500D03*
X75500Y561500D03*
X78500D03*
X81500D03*
Y557500D03*
X78500D03*
X66500Y554500D03*
X70521Y538403D03*
X63500Y554500D03*
X68500Y535500D03*
X65500D03*
X70498Y541394D03*
X75500Y554500D03*
X72500D03*
X69500D03*
X81500D03*
X78500D03*
X80389Y541468D03*
Y538468D03*
X66500Y557500D03*
X63500Y561500D03*
Y557500D03*
X66500Y561500D03*
X106392Y537000D03*
X105392Y574800D03*
X105412Y556580D03*
X105392Y566000D03*
X86230Y620250D03*
X89360Y620310D03*
X105000Y614533D03*
X102236Y614167D03*
X91150Y618250D03*
X93800Y618111D03*
X82459Y618932D03*
X78500Y615500D03*
X81500D03*
X75500D03*
X72500D03*
X69500D03*
X78500Y602000D03*
X72500D03*
X69500Y596000D03*
X81500Y599000D03*
X78500D03*
X81500Y596000D03*
Y612000D03*
X78500D03*
X69500Y599000D03*
Y602000D03*
X75500D03*
X78500Y596000D03*
X72500D03*
X63500Y602000D03*
Y596000D03*
X66500Y599000D03*
Y602000D03*
X63500Y599000D03*
X66500Y596000D03*
X81500Y602000D03*
X75500Y596000D03*
X72500Y599000D03*
X75500D03*
X105352Y594770D03*
X101898Y611483D03*
X91952Y620900D03*
X106192Y604600D03*
X114000Y3500D03*
X114680Y17320D03*
X150391Y14814D03*
X163427Y14714D03*
X157084Y14814D03*
X160431Y-1801D03*
X153738Y9114D03*
X150391Y-7851D03*
X163391D03*
X157084D03*
X153738Y-1751D03*
X160431Y9114D03*
X126616Y14714D03*
X136756Y16900D03*
X120273Y16839D03*
X132959Y14814D03*
X141880Y17114D03*
X147045Y9114D03*
X130163D03*
X141856Y9100D03*
X136780Y9098D03*
X123620Y9114D03*
X126580Y-7851D03*
X132959Y-7700D03*
X120273Y-9901D03*
X141893Y-9864D03*
X136806Y-9650D03*
X136780Y-1801D03*
X123620D03*
X130313Y-1751D03*
X141906Y-2050D03*
X147045Y-1751D03*
X169770Y14814D03*
X167124Y-1751D03*
X169770Y-7700D03*
X166974Y9114D03*
X114100Y6120D03*
X116300Y-9460D03*
X116692Y-1800D03*
X114050Y21320D03*
X169770Y30100D03*
X120273Y27899D03*
X141893Y27936D03*
X136806Y28150D03*
X126580Y29949D03*
X132959Y30100D03*
X157084Y29949D03*
X163391D03*
X150391D03*
X132959Y-4100D03*
X130313Y-9901D03*
X126580Y-4100D03*
X123620Y-9901D03*
X147045D03*
X141880Y-7260D03*
X136806Y-7050D03*
X136780Y-4401D03*
X132959Y33700D03*
X130313Y27899D03*
X126580Y33700D03*
X123620Y27899D03*
X147045D03*
X141880Y30540D03*
X136806Y30750D03*
X141880Y33149D03*
X136780Y33399D03*
X130313Y17157D03*
X132959Y12114D03*
X123620Y17157D03*
X126666Y12114D03*
X147045Y17157D03*
X141880Y14514D03*
X136780Y14300D03*
X141880Y11914D03*
X136780Y11700D03*
X163391Y-4100D03*
X160431Y-9901D03*
X157084Y-3700D03*
X153738Y-9901D03*
X150391Y-3700D03*
X169770Y-4100D03*
X167124Y-9901D03*
X163391Y33700D03*
X160431Y27899D03*
X153738D03*
X169770Y33700D03*
X167124Y27899D03*
X160431Y17157D03*
X163477Y12114D03*
X153738Y17157D03*
X157084Y12114D03*
X150391D03*
X167124Y17157D03*
X169770Y12114D03*
X120273Y9157D03*
X141880Y-4651D03*
X169770Y90364D03*
X166974Y84714D03*
Y73849D03*
Y46914D03*
X169770Y52614D03*
X167124Y36049D03*
X169770Y67900D03*
X157084Y67749D03*
X163391D03*
X130313Y73849D03*
X123620Y73799D03*
X141906Y73550D03*
X136780Y73799D03*
X126580Y67749D03*
X132959Y67900D03*
X141880Y54914D03*
X123620Y35983D03*
X141856Y46900D03*
X141906Y35750D03*
X136806Y65950D03*
X141893Y65736D03*
X136756Y54700D03*
X136780Y35999D03*
X130313Y35983D03*
X123620Y46914D03*
X132959Y52614D03*
X126616Y52514D03*
X147045Y46914D03*
Y36049D03*
X120273Y54839D03*
X119892Y84700D03*
X120273Y92500D03*
X126616Y90314D03*
X132959Y90414D03*
X141880Y92714D03*
X163427Y90314D03*
X157084Y90414D03*
X150391D03*
X160431Y84714D03*
X153738D03*
X136756Y92500D03*
X141856Y84700D03*
X136780Y84698D03*
X123620Y84714D03*
X147045D03*
X130163D03*
X109057Y92774D03*
X112007Y93139D03*
X116070Y35780D03*
X113100Y57770D03*
X115980Y73680D03*
X116200Y70387D03*
X114082Y55100D03*
X130163Y46914D03*
X136780Y46898D03*
X120273Y66000D03*
X147045Y73849D03*
X153738Y36049D03*
Y73849D03*
X160431Y73799D03*
X157084Y52614D03*
X160431Y35999D03*
X150391Y67749D03*
Y52614D03*
X163427Y52514D03*
X160431Y46914D03*
X153738D03*
X130313Y65699D03*
X123620D03*
X147045D03*
X136806Y68550D03*
X141880Y68340D03*
X130313Y54957D03*
X132959Y49914D03*
X123620Y54957D03*
X126666Y49914D03*
X147045Y54957D03*
X141880Y52314D03*
X136780Y52100D03*
X141880Y49714D03*
X136780Y49500D03*
X132959Y87714D03*
X126580Y71500D03*
X123620Y92757D03*
X126666Y87714D03*
X147045Y92757D03*
X141880Y70949D03*
Y87514D03*
X136780Y89900D03*
X141880Y90114D03*
X136780Y71199D03*
Y87300D03*
X132959Y71500D03*
X130313Y92757D03*
X160431Y65699D03*
X153738D03*
X167124D03*
X160431Y54957D03*
X163477Y49914D03*
X157084Y34100D03*
X153738Y54957D03*
X157084Y49914D03*
X150391Y34100D03*
Y49914D03*
X167124Y54957D03*
X169770Y49914D03*
X157084Y71900D03*
X153738Y92757D03*
X157084Y87714D03*
X150391Y71900D03*
Y87714D03*
X169770Y71500D03*
X167124Y92757D03*
X169770Y87714D03*
X163391Y71500D03*
X160431Y92757D03*
X163477Y87714D03*
X120273Y46957D03*
X117652Y132792D03*
X120117Y132865D03*
X120138Y130408D03*
X117682Y130387D03*
X112664Y128795D03*
X120533Y109535D03*
X120197Y106587D03*
X109622Y128879D03*
X156954Y192872D03*
X154454Y193021D03*
X151810Y192670D03*
X124895Y212033D03*
X127754Y211853D03*
X122542Y214019D03*
X130324Y212033D03*
X115508Y216512D03*
X153788Y187309D03*
X156928Y190053D03*
X148900Y180400D03*
X148800Y185300D03*
Y182900D03*
X148900Y190100D03*
X148800Y187700D03*
X113800Y180500D03*
X116900D03*
X124340Y197750D03*
X117600Y193805D03*
X151359Y187700D03*
X156294Y187625D03*
X151300Y190200D03*
X141263Y215216D03*
X125563Y218616D03*
X137763Y217716D03*
X128500Y218700D03*
X141263Y217716D03*
X137763Y215216D03*
X117080Y225330D03*
X169150Y223600D03*
Y227600D03*
X112904Y237218D03*
X118008Y220991D03*
X116310Y222940D03*
X122820Y244133D03*
X115497Y248376D03*
X130324Y244033D03*
X122203Y246675D03*
X127500Y243500D03*
X123074Y275948D03*
X113100Y269163D03*
X115508Y280512D03*
X130324Y276033D03*
X116000Y254643D03*
X127500Y275500D03*
X117063Y257016D03*
X118008Y252991D03*
X122400Y278671D03*
X125624Y223633D03*
Y221133D03*
X141263Y234216D03*
X141200Y229600D03*
X141211Y225615D03*
X141300Y221700D03*
X139763Y231700D03*
Y227600D03*
Y223700D03*
X139582Y219800D03*
X125563Y234316D03*
X125663Y230716D03*
X125563Y227116D03*
X128200Y250700D03*
X125563Y250616D03*
X141263Y249716D03*
Y247216D03*
X137763D03*
Y249716D03*
X125624Y255633D03*
X125563Y259116D03*
X125663Y262716D03*
X125563Y266316D03*
X141300Y253700D03*
X139631Y251900D03*
X125624Y253133D03*
X137763Y279216D03*
X141263Y266216D03*
X139763Y255700D03*
Y259600D03*
X139800Y263700D03*
X141313Y257533D03*
X141263Y279216D03*
X141200Y261600D03*
X137300Y337200D03*
X118800Y298400D03*
X123301Y308044D03*
X110180Y280920D03*
X130324Y308033D03*
X127500Y307500D03*
X115508Y312512D03*
X129700Y340152D03*
X127000Y339000D03*
X109960Y313190D03*
X119050Y341625D03*
X116000Y286643D03*
X113000Y304000D03*
X117063Y289016D03*
X118008Y284991D03*
X122493Y310633D03*
X116000Y318643D03*
X118008Y316991D03*
X117063Y321016D03*
X113100Y333106D03*
X125624Y287633D03*
X125663Y294716D03*
X125563Y298316D03*
Y291116D03*
X128200Y282600D03*
X141263Y311216D03*
X137763D03*
X141263Y281716D03*
X139730Y284200D03*
X139763Y288200D03*
Y292000D03*
Y296000D03*
X125624Y285133D03*
X141200Y286100D03*
X141261Y290076D03*
X141300Y294000D03*
X141263Y298216D03*
X137763Y281716D03*
X125563Y282616D03*
X141211Y325515D03*
X128200Y314800D03*
X141263Y330216D03*
X139763Y327800D03*
X141300Y317500D03*
Y321500D03*
X139582Y315800D03*
X139763Y319400D03*
X125563Y323116D03*
X125663Y326716D03*
X125563Y330316D03*
Y314616D03*
X141263Y313716D03*
X137763D03*
X139763Y323600D03*
X125624Y317133D03*
Y319633D03*
X109640Y376070D03*
X113500Y369000D03*
X115508Y344512D03*
X130585Y372085D03*
X127420Y371590D03*
X110670Y344500D03*
X112600Y366300D03*
X122300Y372100D03*
X119300Y400900D03*
X110397Y402603D03*
X109924Y393848D03*
X116000Y382643D03*
X122473Y374716D03*
X117063Y385016D03*
X153392Y404000D03*
X122361Y342649D03*
X116000Y350643D03*
X118008Y348991D03*
X117063Y353016D03*
X141289Y349488D03*
X128100Y346700D03*
X141300Y353300D03*
X141200Y357200D03*
X137763Y345716D03*
X141263D03*
Y343216D03*
X125624Y349133D03*
X137763Y343216D03*
X125563Y362316D03*
Y355116D03*
X125663Y358716D03*
X141263Y362216D03*
X139582Y347800D03*
X139763Y351400D03*
Y355200D03*
Y359500D03*
X125624Y351633D03*
X125563Y346616D03*
X141300Y381800D03*
X139763Y384000D03*
X125624Y381133D03*
X141263Y394216D03*
Y390416D03*
X141261Y385876D03*
X139736Y392300D03*
X125563Y378616D03*
X125663Y390716D03*
X125563Y387116D03*
Y394316D03*
X137763Y375216D03*
X141263D03*
Y377716D03*
X137763D03*
X139631Y379900D03*
X128500Y378700D03*
X139900Y388000D03*
X125624Y383633D03*
X118220Y360500D03*
X118629Y381193D03*
X157862Y416012D03*
X117363Y417416D03*
X121981Y405573D03*
X110452Y407092D03*
X148666Y417397D03*
X148300Y414600D03*
X148409Y422239D03*
X119100Y411600D03*
X119016Y414201D03*
X119398Y406348D03*
X122242Y419199D03*
X123441Y421795D03*
X151909Y413267D03*
X153392Y407500D03*
X167680Y408440D03*
X167640Y404842D03*
X150650Y409860D03*
X111961Y499877D03*
X130163Y510114D03*
X147045D03*
X132959Y515814D03*
X126616Y515714D03*
X120273Y517900D03*
X136780Y510098D03*
X136756Y517900D03*
X141856Y510100D03*
X141880Y518114D03*
X123620Y510114D03*
X119892Y510100D03*
X114322Y525980D03*
X114442Y510300D03*
Y507800D03*
X116927Y517900D03*
X150391Y515814D03*
X169770Y515764D03*
X163427Y515714D03*
X166974Y510114D03*
X160431D03*
X157084Y515814D03*
X153738Y510114D03*
X112427Y497225D03*
X132959Y513114D03*
X163477D03*
X160431Y518157D03*
X130313D03*
X136780Y512700D03*
X141880Y515514D03*
X136780Y515300D03*
X141880Y512914D03*
X169770Y513114D03*
X167124Y518157D03*
X150391Y513114D03*
X147045Y518157D03*
X126666Y513114D03*
X123620Y518157D03*
X157084Y513114D03*
X153738Y518157D03*
X141893Y528936D03*
X136806Y529150D03*
X141906Y536750D03*
X132959Y553614D03*
X126616Y553514D03*
X130163Y547914D03*
X123620D03*
X136780Y547898D03*
X141856Y547900D03*
X147045Y537049D03*
Y547914D03*
X120210Y529200D03*
X130313Y537049D03*
X132959Y531100D03*
X126580Y530949D03*
X123620Y536999D03*
X136780D03*
X114792Y528600D03*
X119892Y536983D03*
Y547900D03*
X115883Y548024D03*
X123620Y574799D03*
X130313Y574849D03*
X132959Y568900D03*
X126580Y568749D03*
X141856Y585700D03*
X141906Y574550D03*
X136780Y574799D03*
Y585698D03*
X120092Y566900D03*
X136806Y566950D03*
X147045Y585714D03*
Y574849D03*
X113692Y566000D03*
X119892Y574700D03*
Y585700D03*
X114509Y575658D03*
X114150Y585850D03*
X116927Y555700D03*
X141880Y555914D03*
X120273Y555700D03*
X136756D03*
X141893Y566736D03*
X130163Y585714D03*
X123620D03*
X150391Y530949D03*
Y553614D03*
X166974Y537049D03*
X163391Y530949D03*
X160431Y536999D03*
X169770Y553564D03*
X163427Y553514D03*
X166974Y547914D03*
X160431D03*
X157084Y530949D03*
X153738Y537049D03*
X157084Y553614D03*
X153738Y547914D03*
X169770Y531100D03*
X150391Y568749D03*
X163391D03*
X160431Y585714D03*
X166974D03*
Y574849D03*
X160431Y574799D03*
X169770Y568900D03*
X157084Y568749D03*
X153738Y585714D03*
Y574849D03*
X130313Y528899D03*
X132959Y588714D03*
X160431Y528899D03*
X163391Y534700D03*
X132959D03*
X136780Y550500D03*
X141880Y553314D03*
X136780Y553100D03*
X141880Y550714D03*
X169770Y550914D03*
X167124Y555957D03*
X150391Y550914D03*
X147045Y555957D03*
X126666Y550914D03*
X123620Y555957D03*
X157084Y550914D03*
X153738Y555957D03*
X132959Y550914D03*
X163477D03*
X160431Y555957D03*
X130313D03*
X136780Y534399D03*
X141880Y531540D03*
X136806Y531750D03*
X141880Y534149D03*
X167124Y528899D03*
X169770Y534700D03*
X147045Y528899D03*
X150391Y535100D03*
X123620Y528899D03*
X126580Y534700D03*
X153738Y528899D03*
X157084Y535100D03*
X136780Y588300D03*
X141880Y588514D03*
X169770Y588714D03*
X150391D03*
X126666D03*
X157084D03*
X163477D03*
X136780Y572199D03*
X136806Y569550D03*
X141880Y571949D03*
X167124Y566699D03*
X169770Y572500D03*
X147045Y566699D03*
X150391Y572900D03*
X123620Y566699D03*
X126580Y572500D03*
X153738Y566699D03*
X157084Y572900D03*
X130313Y566699D03*
X160431D03*
X163391Y572500D03*
X132959D03*
X141880Y569340D03*
X147045Y612649D03*
X123620Y612599D03*
X136780D03*
X130313Y612649D03*
X119892Y612583D03*
X160431Y612599D03*
X166974Y612649D03*
X153738D03*
X126616Y591314D03*
X116992Y590700D03*
X132959Y591414D03*
X136756Y593500D03*
X141880Y593714D03*
X132959Y606700D03*
X126580Y606549D03*
X120092Y604900D03*
X141906Y612350D03*
X136806Y604750D03*
X141893Y604536D03*
X114792Y604600D03*
X116927Y593500D03*
X150391Y591414D03*
Y606549D03*
X163427Y591314D03*
X163391Y606549D03*
X169770Y606700D03*
Y591364D03*
X157084Y591414D03*
Y606549D03*
X130313Y604499D03*
X136780Y609999D03*
X141880Y607140D03*
Y591114D03*
X136806Y607350D03*
X136780Y590900D03*
X167124Y604499D03*
Y593757D03*
X169770Y610300D03*
X147045Y604499D03*
X150391Y610700D03*
X147045Y593757D03*
X123620Y604499D03*
X126580Y610300D03*
X123620Y593757D03*
X153738Y604499D03*
X157084Y610700D03*
X153738Y593757D03*
X160431Y604499D03*
X163391Y610300D03*
X160431Y593757D03*
X132959Y610300D03*
X130313Y593757D03*
X141880Y609749D03*
X173591Y-1801D03*
X178691Y17114D03*
X173567Y16900D03*
X178717Y-2050D03*
X183856Y-1751D03*
X173617Y-9650D03*
X178704Y-9864D03*
X178667Y9100D03*
X173591Y9098D03*
X183856Y9114D03*
X178704Y27936D03*
X173617Y28150D03*
X190549Y9114D03*
X197242D03*
X210402Y9098D03*
X210428Y-9650D03*
X193895Y-3700D03*
X190549Y-9901D03*
X187202Y-3700D03*
X183856Y-9901D03*
X206581Y-4100D03*
X203935Y-9901D03*
X200202Y-4100D03*
X197242Y-9901D03*
X173617Y-7050D03*
X210428D03*
X173591Y-4401D03*
X210402D03*
X178691Y-4651D03*
X193895Y-7851D03*
X187202D03*
X200202D03*
X210402Y-1801D03*
X190549Y-1751D03*
X197242Y-1801D03*
X203935Y-1751D03*
X206581Y-7700D03*
X203785Y9114D03*
X210378Y16900D03*
X210428Y28150D03*
X200202Y29949D03*
X187202D03*
X193895Y14814D03*
Y29949D03*
X200238Y14714D03*
X187202Y14814D03*
X206581D03*
X190549Y27899D03*
X183856D03*
X206581Y33700D03*
X203935Y27899D03*
X200202Y33700D03*
X197242Y27899D03*
X173617Y30750D03*
X210428D03*
X178691Y30540D03*
X173591Y33399D03*
X210402D03*
X178691Y33149D03*
X190549Y17157D03*
X193895Y12114D03*
X183856Y17157D03*
X187202Y12114D03*
X203935Y17157D03*
X206581Y12114D03*
X197242Y17157D03*
X200288Y12114D03*
X173591Y14300D03*
X210402D03*
X178691Y14514D03*
X173591Y11700D03*
X210402D03*
X178691Y11914D03*
X206581Y30100D03*
X224013Y-3700D03*
X220667Y-9901D03*
X215502Y-7260D03*
Y-4651D03*
X220667Y-1751D03*
X215528Y-2050D03*
X215515Y-9864D03*
X227360Y-1751D03*
X230706Y-7851D03*
X224013D03*
X215478Y9100D03*
X220667Y9114D03*
X227360D03*
X230706Y-3700D03*
X227360Y-9901D03*
X224013Y29949D03*
X230706D03*
Y14814D03*
X227360Y27899D03*
X220667D03*
X215502Y30540D03*
Y33149D03*
X227360Y17157D03*
X230706Y12114D03*
X220667Y17157D03*
X224013Y12114D03*
X215502Y14514D03*
Y11914D03*
X224013Y14814D03*
X215502Y17114D03*
X215515Y27936D03*
X178691Y-7260D03*
Y92714D03*
X173591Y84698D03*
X178667Y84700D03*
X183856Y84714D03*
X173567Y92500D03*
X183856Y36049D03*
X173591Y46898D03*
X183856Y73849D03*
X178717Y73550D03*
X173591Y73799D03*
X178691Y54914D03*
X173591Y35999D03*
X183856Y46914D03*
X178717Y35750D03*
X178667Y46900D03*
X173567Y54700D03*
X173617Y65950D03*
X178704Y65736D03*
X206581Y52614D03*
X210378Y54700D03*
X210402Y46898D03*
X193895Y67749D03*
X200202D03*
X187202D03*
X203785Y46914D03*
X190549D03*
X197242D03*
X200238Y52514D03*
X193895Y52614D03*
X187202D03*
X190549Y36049D03*
X203935D03*
X190549Y65699D03*
X183856D03*
X203935D03*
X197242D03*
X173617Y68550D03*
X210428D03*
X178691Y68340D03*
X190549Y54957D03*
X193895Y34100D03*
Y49914D03*
X183856Y54957D03*
X187202Y34100D03*
Y49914D03*
X203935Y54957D03*
X206581Y49914D03*
X197242Y54957D03*
X200288Y49914D03*
X173591Y52100D03*
X210402D03*
X178691Y52314D03*
X173591Y49500D03*
X210402D03*
X178691Y49714D03*
X197242Y35999D03*
X206581Y67900D03*
X210428Y65950D03*
X210402Y35999D03*
X173591Y89900D03*
X210402D03*
X178691Y70949D03*
Y87514D03*
X173591Y71199D03*
Y87300D03*
X210402Y71199D03*
Y87300D03*
X178691Y90114D03*
X197242Y73799D03*
X203935Y73849D03*
X210402Y73799D03*
Y84698D03*
X210378Y92500D03*
X190549Y73849D03*
Y84714D03*
X197242D03*
X203785D03*
X193895Y90414D03*
X206581D03*
X200238Y90314D03*
X187202Y90414D03*
X193895Y71900D03*
X190549Y92757D03*
X193895Y87714D03*
X187202Y71900D03*
X183856Y92757D03*
X187202Y87714D03*
X206581Y71500D03*
X203935Y92757D03*
X206581Y87714D03*
X200202Y71500D03*
X197242Y92757D03*
X200288Y87714D03*
X215478Y46900D03*
X215502Y54914D03*
X215515Y65736D03*
X224013Y52614D03*
X220667Y46914D03*
X230706Y52614D03*
X224013Y67749D03*
X230706D03*
X227360Y46914D03*
Y65699D03*
X220667D03*
X215502Y68340D03*
X227360Y54957D03*
X230706Y34100D03*
Y49914D03*
X220667Y54957D03*
X224013Y34100D03*
Y49914D03*
X215502Y52314D03*
Y49714D03*
X227360Y36049D03*
X220667D03*
X215528Y35750D03*
X215502Y92714D03*
X230706Y71900D03*
X227360Y92757D03*
X230706Y87714D03*
X224013Y71900D03*
X220667Y92761D03*
X224013Y87714D03*
X215502Y70949D03*
Y87514D03*
Y90114D03*
X220667Y73849D03*
Y84714D03*
X227360D03*
X230706Y90414D03*
X215478Y84700D03*
X215528Y73550D03*
X227360Y73849D03*
X224013Y90414D03*
X197617Y243089D03*
X191537Y242989D03*
Y240489D03*
X197617Y240589D03*
X191537Y237989D03*
X197617Y238089D03*
X192037Y270750D03*
X194537D03*
X197037D03*
X194537Y299750D03*
X197037D03*
X192037D03*
X194537Y332480D03*
X197037D03*
X192037D03*
X194500Y360200D03*
X197137Y360350D03*
X191900Y360173D03*
X195200Y377800D03*
Y380300D03*
X177689Y404109D03*
X180799Y404049D03*
X174609Y404009D03*
X172697Y407196D03*
X197242Y510114D03*
X200238Y515714D03*
X203785Y510114D03*
X190549D03*
X187202Y515814D03*
X193895D03*
X183856Y510114D03*
X173591Y510098D03*
X173567Y517900D03*
X178691Y518114D03*
X206581Y515814D03*
X210402Y510098D03*
X210378Y517900D03*
X215502Y518114D03*
X215478Y510100D03*
X224013Y515814D03*
X220667Y510114D03*
X227360D03*
X230706Y515814D03*
X173591Y515300D03*
X200288Y513114D03*
X197242Y518157D03*
X230706Y513114D03*
X227360Y518157D03*
X206581Y513114D03*
X203935Y518157D03*
X187202Y513114D03*
X183856Y518157D03*
X193895Y513114D03*
X190549Y518157D03*
X215502Y515514D03*
X178691D03*
X210402Y512700D03*
X173591D03*
X215502Y512914D03*
X178691D03*
X210402Y515300D03*
X224013Y513114D03*
X220667Y518161D03*
X193895Y553614D03*
X200238Y553514D03*
X183856Y547914D03*
X190549D03*
X203785D03*
X197242D03*
X190549Y537049D03*
X183856D03*
X187202Y530949D03*
X193895D03*
X197242Y536999D03*
X203935Y537049D03*
X200202Y530949D03*
X206581Y553614D03*
X210402Y547898D03*
X178717Y536750D03*
X173617Y529150D03*
X173591Y536999D03*
X178704Y528936D03*
X178667Y547900D03*
X173591Y547898D03*
X206581Y531100D03*
X210402Y536999D03*
X210428Y529150D03*
X187202Y553614D03*
X173591Y553100D03*
X178691Y555914D03*
X173567Y555700D03*
X210378D03*
X203935Y574849D03*
X200202Y568749D03*
X197242Y574799D03*
X190549Y585714D03*
X183856D03*
X187202Y568749D03*
X193895D03*
X190549Y574849D03*
X183856D03*
X210402Y585698D03*
X206581Y568900D03*
X210428Y566950D03*
X210402Y574799D03*
X178667Y585700D03*
X178717Y574550D03*
X173591Y574799D03*
Y585698D03*
X173617Y566950D03*
X178704Y566736D03*
X197242Y585714D03*
X203785D03*
X173617Y569550D03*
X215515Y528936D03*
X215528Y536750D03*
X215478Y547900D03*
X224013Y530949D03*
X220667Y537049D03*
X230706Y530949D03*
X227360Y537049D03*
X230706Y553614D03*
X220667Y547914D03*
X227360D03*
X224013Y553614D03*
X215502Y555914D03*
X220667Y585714D03*
X215528Y574550D03*
X215478Y585700D03*
X215515Y566736D03*
X224013Y568749D03*
X220667Y574849D03*
X230706Y568749D03*
X227360Y574849D03*
Y585714D03*
X173617Y531750D03*
X224013Y535100D03*
X197242Y528899D03*
X200202Y534700D03*
X227360Y528899D03*
X230706Y535100D03*
X203935Y528899D03*
X206581Y534700D03*
X183856Y528899D03*
X187202Y535100D03*
X190549Y528899D03*
X193895Y535100D03*
X173591Y550500D03*
X215502Y550714D03*
X178691D03*
X210402Y553100D03*
X224013Y550914D03*
X220667Y555961D03*
X200288Y550914D03*
X197242Y555957D03*
X230706Y550914D03*
X227360Y555957D03*
X206581Y550914D03*
X203935Y555957D03*
X187202Y550914D03*
X183856Y555957D03*
X193895Y550914D03*
X190549Y555957D03*
X210402Y534399D03*
X215502Y534149D03*
X178691D03*
X210428Y531750D03*
X220667Y528899D03*
X215502Y553314D03*
X178691D03*
X210402Y550500D03*
X220667Y566699D03*
X224013Y572900D03*
X197242Y566699D03*
X200202Y572500D03*
X227360Y566699D03*
X230706Y572900D03*
X203935Y566699D03*
X206581Y572500D03*
X183856Y566699D03*
X187202Y572900D03*
X190549Y566699D03*
X193895Y572900D03*
X210402Y588300D03*
X173591D03*
X215502Y588514D03*
X178691D03*
X224013Y588714D03*
X200288D03*
X230706D03*
X206581D03*
X187202D03*
X193895D03*
X215502Y569340D03*
X178691D03*
X210402Y572199D03*
X173591D03*
X210428Y569550D03*
X215502Y531540D03*
X178691D03*
X173591Y534399D03*
X215502Y571949D03*
X178691D03*
X227360Y612649D03*
X220667D03*
X203935D03*
X197242Y612599D03*
X190549Y612649D03*
X183856D03*
X210402Y612599D03*
X173591D03*
X187202Y591414D03*
X193895D03*
X187202Y606549D03*
X193895D03*
X200202D03*
X210428Y604750D03*
X206581Y606700D03*
X210378Y593500D03*
X206581Y591414D03*
X178717Y612350D03*
X173617Y604750D03*
X178704Y604536D03*
X173567Y593500D03*
X178691Y593714D03*
X200238Y591314D03*
X224013Y606549D03*
X230706D03*
Y591414D03*
X215515Y604536D03*
X215528Y612350D03*
X215502Y593714D03*
X224013Y591414D03*
X173617Y607350D03*
X173591Y590900D03*
X215502Y607140D03*
Y591114D03*
X178691D03*
X173591Y609999D03*
X215502Y609749D03*
X178691D03*
X210402Y590900D03*
X210428Y607350D03*
X220667Y604499D03*
X224013Y610700D03*
X220667Y593761D03*
X197242Y604499D03*
Y593757D03*
X200202Y610300D03*
X227360Y604499D03*
X230706Y610700D03*
X227360Y593757D03*
X203935Y604499D03*
X206581Y610300D03*
X203935Y593757D03*
X183856Y604499D03*
Y593757D03*
X187202Y610700D03*
X190549Y604499D03*
Y593757D03*
X193895Y610700D03*
X178691Y607140D03*
X210402Y609999D03*
X243392Y-4100D03*
X240746Y-9901D03*
X267517Y-3700D03*
X264171Y-9901D03*
X237013Y-4100D03*
X234053Y-9901D03*
X260824Y-3700D03*
X257478Y-9901D03*
X252313Y-7260D03*
X247213Y-4401D03*
X252313Y-4651D03*
X270864Y-9901D03*
Y-1801D03*
X247213D03*
X240746Y-1751D03*
X264171D03*
X252339Y-2050D03*
X234053Y-1801D03*
X257478Y-1751D03*
X243392Y-7700D03*
X260824Y-7851D03*
X252326Y-9864D03*
X237013Y-7851D03*
X247239Y-9650D03*
X267517Y-7851D03*
X252289Y9100D03*
X264171Y9114D03*
X240596D03*
X247213Y9098D03*
X270864Y9114D03*
X234053D03*
X257478D03*
X267517Y14814D03*
Y29949D03*
X247189Y16900D03*
X252326Y27936D03*
X243392Y30100D03*
X247239Y28150D03*
X260824Y29949D03*
X237013D03*
X243392Y33700D03*
X240746Y27899D03*
X264171D03*
X237013Y33700D03*
X234053Y27899D03*
X257478D03*
X247239Y30750D03*
X252313Y33149D03*
X247213Y33399D03*
X252313Y30540D03*
X270864Y27899D03*
X240746Y17157D03*
X243392Y12114D03*
X264171Y17157D03*
X267517Y12114D03*
X234053Y17157D03*
X237099Y12114D03*
X257478Y17157D03*
X260824Y12114D03*
X247213Y14300D03*
X252313Y14514D03*
X247213Y11700D03*
X252313Y11914D03*
X270864Y17157D03*
X252313Y17114D03*
X243392Y14814D03*
X260824D03*
X237049Y14714D03*
X284050Y-9650D03*
X289137Y-9864D03*
X284050Y-7050D03*
X289124Y-7260D03*
Y-4651D03*
X280203Y-4100D03*
X277557Y-9901D03*
X273824Y-4100D03*
Y-7851D03*
X280203Y-7700D03*
X289100Y9100D03*
X284024Y9098D03*
X277407Y9114D03*
X277557Y-1751D03*
X289150Y-2050D03*
X284024Y-1801D03*
X273824Y29949D03*
X273860Y14714D03*
X284000Y16900D03*
X280203Y14814D03*
Y30100D03*
X289124Y17114D03*
X284050Y28150D03*
X289137Y27936D03*
X289124Y33149D03*
X284024Y33399D03*
X280203Y33700D03*
X277557Y27899D03*
X273824Y33700D03*
X284024Y14300D03*
X289124Y14514D03*
X284024Y11700D03*
X289124Y11914D03*
X277557Y17157D03*
X280203Y12114D03*
X273910D03*
X247239Y-7050D03*
X284024Y-4401D03*
X284050Y30750D03*
X289124Y30540D03*
X247213Y46898D03*
X257478Y46914D03*
X240596D03*
X243392Y67900D03*
X267517Y67749D03*
Y52614D03*
X270864Y46914D03*
X252326Y65736D03*
X237013Y67749D03*
X260824D03*
X247239Y65950D03*
X243392Y52614D03*
X264171Y46914D03*
X247213Y35999D03*
X257478Y36049D03*
X252339Y35750D03*
X234053Y35999D03*
X240746Y36049D03*
X264171D03*
X237049Y52514D03*
X252289Y46900D03*
X240746Y65699D03*
X264171D03*
X234053D03*
X257478D03*
X247239Y68550D03*
X270864Y65699D03*
X240746Y54957D03*
X243392Y49914D03*
X264171Y54957D03*
X267517Y34100D03*
Y49914D03*
X234053Y54957D03*
X237099Y49914D03*
X257478Y54957D03*
X260824Y34100D03*
Y49914D03*
X247213Y52100D03*
X252313Y49714D03*
X247213Y49500D03*
X252313Y52314D03*
X270864Y54957D03*
X247189Y54700D03*
X252313Y54914D03*
X260824Y52614D03*
X270864Y35999D03*
X234053Y46914D03*
X247213Y73799D03*
X243392Y71500D03*
X240746Y92757D03*
X243392Y87714D03*
X267517Y71900D03*
X264171Y92757D03*
X267517Y87714D03*
X237013Y71500D03*
X234053Y92757D03*
X237099Y87714D03*
X260824Y71900D03*
X257478Y92757D03*
X260824Y87714D03*
X247213Y89900D03*
X252313Y70949D03*
Y87514D03*
X247213Y71199D03*
Y87300D03*
X252313Y90114D03*
X270864Y92757D03*
X247213Y84698D03*
X264171Y84714D03*
X252339Y73550D03*
X257478Y84714D03*
X240746Y73849D03*
X257478D03*
X234053Y73799D03*
X264171Y73849D03*
X243392Y90414D03*
X252313Y92714D03*
X237049Y90314D03*
X270864Y84714D03*
X247189Y92500D03*
X240596Y84714D03*
X234053D03*
X252289Y84700D03*
X260824Y90414D03*
X267517D03*
X270864Y73799D03*
X273824Y67749D03*
X280203Y67900D03*
X284024Y35999D03*
X277557Y36049D03*
X277407Y46914D03*
X289137Y65736D03*
X284050Y65950D03*
X284024Y46898D03*
X284000Y54700D03*
X289100Y46900D03*
X289150Y35750D03*
X289124Y54914D03*
X280203Y52614D03*
X284050Y68550D03*
X289124Y68340D03*
X277557Y65699D03*
X284024Y52100D03*
X289124Y49714D03*
X284024Y49500D03*
X289124Y52314D03*
X277557Y54957D03*
X280203Y49914D03*
X273910D03*
X284024Y89900D03*
X289124Y70949D03*
Y87514D03*
X284024Y71199D03*
Y87300D03*
X289124Y90114D03*
X280203Y71500D03*
X277557Y92757D03*
X280203Y87714D03*
X273824Y71500D03*
X273910Y87714D03*
X273860Y90314D03*
X277407Y84714D03*
X289100Y84700D03*
X284024Y84698D03*
X284000Y92500D03*
X289150Y73550D03*
X284024Y73799D03*
X289124Y92714D03*
X280203Y90414D03*
X277407Y73849D03*
X252313Y68340D03*
X240746Y112327D03*
X243392Y106934D03*
X264171Y112327D03*
X267517Y107284D03*
X234053Y112327D03*
X237099Y107284D03*
X257478Y112327D03*
X260824Y107284D03*
X247213Y110514D03*
X252313Y107655D03*
X247239Y107865D03*
X252339Y110264D03*
X270864Y112327D03*
X264171Y104284D03*
X267517Y109984D03*
X270864Y104284D03*
X257478D03*
X260824Y109984D03*
X243392Y109534D03*
X252339Y112865D03*
X247213Y113114D03*
X237049Y109884D03*
X240596Y104284D03*
X247239Y105265D03*
X252326Y105051D03*
X234053Y104284D03*
X284024Y110514D03*
X289124Y107655D03*
X284050Y107865D03*
X289150Y110264D03*
X277557Y112327D03*
X280203Y106934D03*
X273910Y107284D03*
X273860Y109884D03*
X284050Y105265D03*
X289137Y105051D03*
X289150Y112865D03*
X284024Y113114D03*
X280203Y109534D03*
X277407Y104284D03*
X271239Y207159D03*
Y211060D03*
X284759Y207159D03*
X291519D03*
X274619Y213009D03*
Y216909D03*
X277999Y211060D03*
Y214960D03*
Y203260D03*
Y207159D03*
X281379Y213009D03*
X288139Y216909D03*
X284759Y214960D03*
X281379Y216909D03*
X284759Y218860D03*
Y203260D03*
Y211060D03*
X281379Y205210D03*
X291519Y203260D03*
Y211060D03*
X288139Y213009D03*
Y205210D03*
X291519Y214960D03*
Y218860D03*
X281379Y201309D03*
X284759Y199360D03*
X291519D03*
X267859Y244209D03*
Y240309D03*
X271239Y238360D03*
X264179D03*
Y250060D03*
X264092Y222710D03*
X264179Y226660D03*
Y246160D03*
X271239D03*
Y250060D03*
Y269560D03*
Y273460D03*
Y265660D03*
X267859Y263709D03*
Y259809D03*
X264179Y265660D03*
X267859Y252009D03*
X264179Y253960D03*
Y257860D03*
X271239D03*
X267859Y255909D03*
X271239Y277360D03*
X267392Y276000D03*
X267359Y279310D03*
X267859Y271509D03*
X264179Y273460D03*
X291519Y238360D03*
X284759Y234460D03*
X288139Y232509D03*
X281379D03*
X277999Y234460D03*
X274619Y232509D03*
Y220809D03*
Y224709D03*
Y228610D03*
X277999Y230559D03*
X274619Y244209D03*
X277999Y250060D03*
X274619Y240309D03*
Y248109D03*
Y236409D03*
X291519Y246160D03*
Y250060D03*
X284759Y246160D03*
X291519Y242260D03*
X281379Y220809D03*
X284759Y226660D03*
Y230559D03*
X277999Y222760D03*
X281379Y224709D03*
X284759Y222760D03*
X277999Y238360D03*
X288139Y248109D03*
X277999Y242260D03*
X284759Y238360D03*
X281379Y248109D03*
X288139Y244209D03*
X277999Y246160D03*
X284759Y242260D03*
X288139Y236409D03*
X291519Y234460D03*
Y222760D03*
Y230559D03*
Y226660D03*
X281379Y240309D03*
Y228610D03*
X288139Y224709D03*
X281379Y252009D03*
X274619D03*
X277999Y253960D03*
X284759D03*
X291519D03*
X284759Y265660D03*
X291519D03*
Y277360D03*
X281379Y275409D03*
Y271509D03*
X284759Y277360D03*
Y273460D03*
X288139Y275409D03*
Y271509D03*
X277999Y277360D03*
X274619Y255909D03*
Y259809D03*
X277999Y269560D03*
X274619Y275409D03*
Y267609D03*
Y263709D03*
X288139Y255909D03*
X291519Y269560D03*
Y257860D03*
Y261760D03*
X281379Y259809D03*
Y267609D03*
Y255909D03*
X284759Y269560D03*
X277999Y261760D03*
X284759Y257860D03*
Y261760D03*
X281379Y263709D03*
X288139Y279310D03*
X274619D03*
X288139Y252009D03*
X281379Y279310D03*
X288139Y263709D03*
X291519Y320260D03*
X284759D03*
X291519Y324160D03*
X277999D03*
X264179Y331960D03*
X271239D03*
Y328060D03*
X267859Y333909D03*
Y341709D03*
Y330009D03*
X264179Y328060D03*
Y339760D03*
X271239Y320260D03*
Y324160D03*
X270939Y316160D03*
X267359Y318309D03*
X267859Y326110D03*
X267392Y322000D03*
X270892Y304660D03*
Y311960D03*
Y300760D03*
Y308560D03*
Y292959D03*
Y289060D03*
X271239Y281260D03*
X270892Y285500D03*
Y296860D03*
X267359Y283209D03*
X291519Y285160D03*
Y292959D03*
X284759Y285160D03*
X277999Y308560D03*
Y300760D03*
Y292959D03*
Y285160D03*
X291519Y308560D03*
X284759D03*
Y300760D03*
X291519D03*
X284759Y292959D03*
X281379Y302709D03*
X288139D03*
X291519Y304660D03*
X281379Y306609D03*
Y310509D03*
X288139Y306609D03*
Y310509D03*
X284759Y304660D03*
X281379Y287109D03*
X288139Y291009D03*
X284759Y289060D03*
Y281260D03*
X291519Y289060D03*
Y281260D03*
Y296860D03*
X288139Y298809D03*
X274619Y306609D03*
Y310509D03*
X277999Y304660D03*
X274619Y302709D03*
Y298809D03*
Y294909D03*
X277999Y289060D03*
Y281260D03*
X274619Y283209D03*
Y287109D03*
Y291009D03*
X277999Y296860D03*
X288139Y283209D03*
Y287109D03*
X281379Y298809D03*
Y294909D03*
X288139D03*
X284759Y296860D03*
X281379Y291009D03*
Y283209D03*
X291519Y316360D03*
X281379Y318309D03*
X291519Y328060D03*
X288139Y341709D03*
X274619Y330009D03*
Y326110D03*
Y322209D03*
X277999Y328060D03*
X274619Y341709D03*
X277999Y320260D03*
Y316360D03*
X274619Y333909D03*
Y337809D03*
X284759Y324160D03*
X288139Y318309D03*
X284759Y316360D03*
X281379Y337809D03*
X291519Y339760D03*
Y335860D03*
X284759Y331960D03*
X291519D03*
X281379Y326110D03*
X288139D03*
X291519Y312460D03*
X284759D03*
X277999D03*
X274619Y314409D03*
X281379D03*
X288139D03*
X274619Y318309D03*
X264179Y335860D03*
X288139Y337809D03*
X281379Y333909D03*
X277999Y331960D03*
X284759Y339760D03*
Y328060D03*
X277999Y339760D03*
X288139Y333909D03*
X267859Y337809D03*
X271239Y335860D03*
X267859Y345609D03*
X267559Y369010D03*
X271239Y355360D03*
X267859Y349509D03*
Y353409D03*
X267559Y361209D03*
X264179Y343660D03*
Y355360D03*
X267492Y380709D03*
X271239Y390460D03*
X267859Y388509D03*
X271239Y382660D03*
X284759Y351460D03*
X281379Y345609D03*
X291519Y359260D03*
Y355360D03*
Y351460D03*
X284759Y343660D03*
X274619Y365109D03*
X277999Y363160D03*
Y367060D03*
X274619Y369010D03*
Y361209D03*
Y345609D03*
X277999Y347560D03*
X274619Y353409D03*
Y357309D03*
Y349509D03*
X277999Y343660D03*
X291519Y347560D03*
Y343660D03*
X288139Y365109D03*
X281379D03*
X284759Y363160D03*
X291519D03*
X284759Y370959D03*
X291519Y367060D03*
Y370959D03*
X288139Y361209D03*
X281379Y357309D03*
X288139Y345609D03*
Y380709D03*
Y400209D03*
X274619Y380709D03*
X277999Y394359D03*
X274619Y392410D03*
X277999Y390460D03*
Y386560D03*
X274619Y376809D03*
Y372909D03*
X291519Y374860D03*
X277999Y382660D03*
X284759Y398260D03*
X281379Y396309D03*
X291519Y398260D03*
X284759Y390460D03*
X291519D03*
X281379Y376809D03*
Y384609D03*
X284759Y382660D03*
X291519D03*
Y378760D03*
X288139Y392410D03*
X281379Y353409D03*
X288139Y384609D03*
Y357309D03*
Y396309D03*
X277999Y351460D03*
X281379Y349509D03*
X288139Y353409D03*
X291519Y386560D03*
X281379Y392410D03*
X284759Y386560D03*
X277999Y359260D03*
X288139Y349509D03*
X284759Y359260D03*
X281379Y372909D03*
X288139Y376809D03*
X277999Y370959D03*
X271239Y343660D03*
Y351460D03*
X264179D03*
X284759Y378760D03*
Y367060D03*
X277999Y378760D03*
X288139Y372909D03*
X264171Y510114D03*
X257478D03*
X260824Y515814D03*
X247213Y515300D03*
X260824Y491044D03*
X247177Y490514D03*
X252313D03*
X236892Y493400D03*
X243392Y493094D03*
X267584Y491219D03*
X271092Y495944D03*
X257392Y495800D03*
X264192D03*
X233292Y495900D03*
X239492Y498500D03*
X247177Y498514D03*
X252313D03*
X252289Y510100D03*
X267517Y515814D03*
X270864Y510114D03*
X247189Y517900D03*
X252313Y518114D03*
X247213Y510098D03*
X240596Y510114D03*
X243392Y515814D03*
X234053Y510114D03*
X237049Y515714D03*
X284024Y490644D03*
X289124D03*
X273860Y515714D03*
X277557Y495944D03*
X277407Y510114D03*
X289100Y510100D03*
X289124Y518114D03*
X284024Y510098D03*
X280203Y515814D03*
X273992Y491144D03*
X280203Y490644D03*
X284024Y498644D03*
X289124D03*
X284000Y517900D03*
X247228Y495909D03*
X289124Y493344D03*
X252313Y493214D03*
X284039Y495944D03*
X260824Y493744D03*
X257478Y498487D03*
X236892Y490800D03*
X233292Y498500D03*
X267584Y493919D03*
X264171Y498487D03*
X243392Y495694D03*
X239592Y495900D03*
X273910Y513114D03*
X270864Y518157D03*
X280203Y513114D03*
X277557Y518157D03*
X289124Y515514D03*
X252313D03*
X284024Y512700D03*
X247213D03*
X289124Y512914D03*
X252313D03*
X284024Y515300D03*
X260824Y513114D03*
X257478Y518157D03*
X237099Y513114D03*
X234053Y518157D03*
X267517Y513114D03*
X264171Y518157D03*
X243392Y513114D03*
X240746Y518157D03*
X273992Y493744D03*
X271092Y498644D03*
X280203Y493244D03*
X277557Y498644D03*
X289124Y495944D03*
X252313Y495814D03*
X284039Y493344D03*
X247228Y493209D03*
X257478Y537049D03*
X237013Y530949D03*
X252339Y536750D03*
X243392Y531100D03*
X247213Y536999D03*
X252326Y528936D03*
X240746Y537049D03*
X234053Y536999D03*
X267517Y553614D03*
X270864Y547914D03*
X267517Y530949D03*
X270864Y536999D03*
X260824Y553614D03*
X237049Y553514D03*
X243392Y553614D03*
X264171Y547914D03*
X257478D03*
X252289Y547900D03*
X240596Y547914D03*
X247213Y547898D03*
X234053Y547914D03*
X264171Y537049D03*
X260824Y530949D03*
X247189Y555700D03*
X252313Y555914D03*
X270864Y574799D03*
Y585714D03*
X267517Y568749D03*
X247239Y566950D03*
X252326Y566736D03*
X234053Y574799D03*
X240746Y574849D03*
X247213Y574799D03*
X234053Y585714D03*
X237013Y568749D03*
X264171Y585714D03*
X257478D03*
X264171Y574849D03*
X257478D03*
X260824Y568749D03*
X252339Y574550D03*
X252289Y585700D03*
X240596Y585714D03*
X247213Y585698D03*
X243392Y568900D03*
X277407Y537049D03*
X273824Y530949D03*
X273860Y553514D03*
X284024Y547898D03*
X289100Y547900D03*
X280203Y553614D03*
Y531100D03*
X284024Y536999D03*
X289137Y528936D03*
X284050Y529150D03*
X289150Y536750D03*
X277407Y547914D03*
X273824Y568749D03*
X284000Y555700D03*
X289124Y555914D03*
X280203Y568900D03*
X277407Y574849D03*
Y585714D03*
X289100Y585700D03*
X289150Y574550D03*
X284024Y574799D03*
Y585698D03*
X284050Y566950D03*
X289137Y566736D03*
X284024Y588300D03*
X247213Y553100D03*
X247239Y569550D03*
X289124Y550714D03*
X252313D03*
X284024Y553100D03*
X260824Y550914D03*
X257478Y555957D03*
X237099Y550914D03*
X234053Y555957D03*
X267517Y550914D03*
X264171Y555957D03*
X243392Y550914D03*
X240746Y555957D03*
X270864Y528899D03*
X273824Y534700D03*
X277557Y528899D03*
X280203Y534700D03*
X289124Y531540D03*
X252313D03*
X247213Y534399D03*
X289124Y534149D03*
X252313D03*
X284050Y531750D03*
X257478Y528899D03*
X260824Y535100D03*
X234053Y528899D03*
X237013Y534700D03*
X264171Y528899D03*
X267517Y535100D03*
X240746Y528899D03*
X243392Y534700D03*
X273910Y550914D03*
X270864Y555957D03*
X280203Y550914D03*
X277557Y555957D03*
X289124Y553314D03*
X252313D03*
X284024Y550500D03*
X247213D03*
X264171Y566699D03*
X267517Y572900D03*
X240746Y566699D03*
X243392Y572500D03*
X280203Y588714D03*
X247213Y588300D03*
X289124Y588514D03*
X252313D03*
X260824Y588714D03*
X237099D03*
X267517D03*
X243392D03*
X270864Y566699D03*
X273824Y572500D03*
X277557Y566699D03*
X280203Y572500D03*
X289124Y569340D03*
X284024Y572199D03*
X252313Y571949D03*
X257478Y566699D03*
X260824Y572900D03*
X234053Y566699D03*
X237013Y572500D03*
X273910Y588714D03*
X247239Y531750D03*
X284024Y534399D03*
X252313Y569340D03*
X247213Y572199D03*
X289124Y571949D03*
X284050Y569550D03*
X284024Y612599D03*
X240746Y612649D03*
X247213Y612599D03*
X234053D03*
X257478Y612649D03*
X247239Y604750D03*
X252326Y604536D03*
X260824Y606549D03*
X237013D03*
X243392Y606700D03*
X264171Y612449D03*
X252339Y612350D03*
X267517Y591414D03*
X260824D03*
X237049Y591314D03*
X247189Y593500D03*
X252313Y593714D03*
X243392Y591414D03*
X267517Y606549D03*
X270864Y612399D03*
X273824Y606549D03*
X273860Y591314D03*
X284050Y604750D03*
X289150Y612350D03*
X280203Y606700D03*
Y591414D03*
X277407Y612449D03*
X289124Y593714D03*
X284000Y593500D03*
X289137Y604536D03*
X247213Y590900D03*
X247239Y607350D03*
X277557Y604499D03*
X280203Y610300D03*
X277557Y593757D03*
X289124Y607140D03*
Y591114D03*
X252313Y607140D03*
Y591114D03*
X289124Y609749D03*
X252313D03*
X284050Y607350D03*
X284024Y590900D03*
X257478Y604499D03*
Y593757D03*
X260824Y610700D03*
X234053Y604499D03*
Y593757D03*
X237013Y610300D03*
X264171Y604499D03*
X267517Y610700D03*
X264171Y593757D03*
X240746Y604499D03*
Y593757D03*
X243392Y610300D03*
X270864Y604499D03*
X273824Y610300D03*
X270864Y593757D03*
X284024Y609999D03*
X247213D03*
X297635Y-7851D03*
X304328D03*
X300982Y-1751D03*
X294289D03*
X308157Y-7180D03*
X324407Y-4536D03*
X304328Y-3700D03*
X300982Y-9901D03*
X297635Y-3700D03*
X294289Y-9901D03*
X321061Y-1743D03*
X314368Y-1843D03*
X331100Y-4536D03*
X327754Y-7108D03*
X317714Y-9786D03*
X311021D03*
X314368Y9114D03*
X321061D03*
X331100D03*
X317714Y-4536D03*
X294289Y9114D03*
X300982D03*
X307675Y-1843D03*
X311021Y28014D03*
X307675Y9300D03*
X304328Y29949D03*
X307992Y13200D03*
X297635Y14814D03*
X321192Y13200D03*
X321334Y32100D03*
X308092D03*
X297635Y29949D03*
X304328Y14814D03*
X300982Y27899D03*
X294289D03*
X300982Y17157D03*
X304328Y12114D03*
X294289Y17157D03*
X297635Y12114D03*
X317714Y28014D03*
X311021Y17057D03*
X317714D03*
X327754D03*
Y28014D03*
X334447Y-1743D03*
Y-7108D03*
X347833D03*
X351179Y9122D03*
Y-4536D03*
X341140Y-1743D03*
X337793Y-9901D03*
X341140Y9122D03*
X334292Y13200D03*
Y32100D03*
X347833Y17057D03*
Y28022D03*
X337793Y17057D03*
Y28014D03*
X314368Y-7108D03*
X324407Y-9901D03*
X327754Y-1743D03*
X321061Y-7108D03*
X341140D03*
X337793Y-4536D03*
X344486Y-9786D03*
Y-4536D03*
X351179Y-9901D03*
X354525Y-1742D03*
X354526Y-7108D03*
X331100Y-9786D03*
X311021Y-4536D03*
X347833Y-1743D03*
X311021Y65814D03*
X317714D03*
X321061Y35957D03*
X307950Y50729D03*
X300982Y36049D03*
X294289Y46914D03*
X304328Y52614D03*
X321192Y51000D03*
X307675Y35957D03*
X304328Y67749D03*
X297635D03*
X294289Y36049D03*
X300982Y46914D03*
X297635Y52614D03*
X300982Y65699D03*
X294289D03*
X300982Y54957D03*
X304328Y34100D03*
Y49914D03*
X294289Y54957D03*
X297635Y34100D03*
Y49914D03*
X314368Y35957D03*
Y46914D03*
X311021Y54857D03*
X317714D03*
X321061Y46914D03*
X331100D03*
X327754Y65814D03*
X331100Y35957D03*
X327754Y54857D03*
X304328Y71900D03*
X300982Y92757D03*
X304328Y87714D03*
X297635Y71900D03*
X294289Y92757D03*
X297635Y87714D03*
X331100Y89964D03*
X327754Y92757D03*
X331100Y84714D03*
Y73757D03*
X314368D03*
Y87392D03*
X311021Y89964D03*
X317714D03*
X321061Y87392D03*
Y73757D03*
X317714Y84714D03*
X307992Y70400D03*
X321334Y69900D03*
X304278Y90414D03*
X307592Y73800D03*
X300982Y84714D03*
X294289D03*
X300982Y73849D03*
X294289D03*
X308166Y87394D03*
X297635Y90414D03*
X307675Y92657D03*
X321061Y92757D03*
X327754Y87392D03*
X324407Y89964D03*
Y84599D03*
X314368Y92657D03*
X311021Y84714D03*
X334292Y51000D03*
X341140Y35957D03*
X337793Y65814D03*
Y54857D03*
X351179Y46922D03*
X347833Y54857D03*
X341140Y46922D03*
X347833Y65822D03*
X351179Y35957D03*
X354415Y87392D03*
X351179Y89964D03*
X347833Y87392D03*
X344486Y84714D03*
Y89964D03*
X337793Y84599D03*
X341140Y92757D03*
X334447D03*
X347833D03*
X351179Y84599D03*
Y73757D03*
X337793Y89964D03*
X341140Y87392D03*
Y73757D03*
X334292Y69900D03*
X334447Y87392D03*
X354415Y92757D03*
X311021Y35957D03*
X334446Y65814D03*
X334447Y35957D03*
X347833D03*
X300982Y109700D03*
X304178Y107684D03*
X294889Y110927D03*
X297635Y105084D03*
X326592Y105600D03*
X313637Y105725D03*
X300992Y112300D03*
X297642Y107700D03*
X304192Y105000D03*
X324492Y103500D03*
X327092Y103021D03*
X294899Y213009D03*
X308418Y201309D03*
X317428Y193507D03*
X301648Y194841D03*
X332078Y218860D03*
X329818Y214958D03*
X298279Y214960D03*
X305039D03*
X301659Y213009D03*
X294899Y209109D03*
X298279Y218860D03*
X311798Y211060D03*
Y218860D03*
Y214960D03*
X308418Y213009D03*
X305039Y211060D03*
Y218860D03*
X324200Y201308D03*
X298279Y199360D03*
X294899Y201309D03*
X312918Y205210D03*
X315178Y209109D03*
X298279Y207159D03*
Y203260D03*
Y211060D03*
X318558Y218860D03*
X315178Y216909D03*
Y213009D03*
X301659Y209109D03*
X325318Y211060D03*
X348978Y205210D03*
Y216909D03*
X342218Y213009D03*
X355737Y216909D03*
Y213009D03*
X338838Y218860D03*
X345598Y214960D03*
X352357D03*
X334328Y199108D03*
X348978Y209109D03*
X352357Y211060D03*
X345598Y203260D03*
X355737Y205210D03*
X338838Y211058D03*
X335458Y216909D03*
X355737Y209109D03*
X345598Y207159D03*
X342218Y209109D03*
X332078Y226660D03*
X315178Y244209D03*
X311798Y246160D03*
X321938Y252009D03*
X345598Y242260D03*
X335458Y232510D03*
X352357Y250060D03*
X345598D03*
X342218Y248109D03*
X335458Y240309D03*
X338838Y261760D03*
X335458Y255909D03*
X355737Y252009D03*
X348978D03*
X352357Y253960D03*
X345598D03*
X355737Y255909D03*
X348978D03*
X345598Y261760D03*
X348978Y259809D03*
X345598Y257860D03*
X352357D03*
X342218Y252009D03*
X338838Y250060D03*
X345598Y234460D03*
X352357Y242260D03*
X294899Y224709D03*
X332078Y242260D03*
Y250060D03*
X328698Y232509D03*
Y220809D03*
X332078Y234460D03*
X298279Y246160D03*
X325318Y250060D03*
X321938Y248109D03*
X305039Y246160D03*
X308418Y244209D03*
X294899D03*
Y248109D03*
X325318Y242260D03*
Y226660D03*
X308418Y220809D03*
X294899D03*
X301659Y224709D03*
X328698Y248109D03*
Y240309D03*
X301659Y220809D03*
X325318Y238360D03*
Y246160D03*
X321938Y244209D03*
X332078Y238360D03*
Y246160D03*
X298279Y230559D03*
X305039Y242260D03*
X294899Y236409D03*
X311798Y230559D03*
X318558Y234460D03*
X321938Y224709D03*
X315178Y236409D03*
Y224709D03*
X298279Y234460D03*
X308418Y228610D03*
Y224709D03*
X305039Y230559D03*
X311798Y222760D03*
X308418Y232509D03*
X294899Y228610D03*
X325318Y234460D03*
Y230559D03*
Y222760D03*
X321938Y228610D03*
X298279Y250060D03*
Y242260D03*
X305039Y234460D03*
X321938Y232509D03*
X298279Y238360D03*
X315178Y228610D03*
X301659Y236409D03*
X318558Y250060D03*
X305039D03*
X318558Y246160D03*
X301659Y248109D03*
X308418Y240309D03*
X315178D03*
X301659D03*
X318558Y242260D03*
X298279Y226660D03*
X318558D03*
X315178Y220809D03*
X321938D03*
X315178Y232509D03*
X301659Y228610D03*
X308418Y236409D03*
X321938D03*
X311798Y238360D03*
X318558D03*
X305039Y226660D03*
X308418Y252009D03*
X298279Y253960D03*
X325318D03*
X308418Y275409D03*
X301659D03*
X308418Y255909D03*
X321938Y275409D03*
X315178Y279310D03*
X318558Y277360D03*
X311798Y261760D03*
X321938Y259809D03*
X301659D03*
X308418Y263709D03*
X325318Y269560D03*
X305039D03*
X318558D03*
X328698Y267609D03*
Y259809D03*
X332078Y269560D03*
X321938Y255909D03*
X308418Y259809D03*
X325318Y273460D03*
Y265660D03*
X301659Y267609D03*
X321938Y263709D03*
X294899Y275409D03*
Y263709D03*
X298279Y265660D03*
X305039Y273460D03*
Y277360D03*
X311798D03*
Y269560D03*
X305039Y265660D03*
X298279Y277360D03*
X328698Y252009D03*
X298279Y261760D03*
X328698Y263709D03*
X325318Y257860D03*
X305039Y261760D03*
X294899Y255909D03*
X305039Y253960D03*
X332078D03*
X315178Y263709D03*
X332078Y265660D03*
X315178Y275409D03*
X301659Y255909D03*
X332078Y257860D03*
X315178Y267609D03*
X298279Y257860D03*
X311798Y273460D03*
X321938Y267609D03*
X308418D03*
X318558Y273460D03*
X301659Y279310D03*
X308418D03*
X294899D03*
X338838Y222760D03*
X352357D03*
X348978Y228610D03*
X352357Y246160D03*
X345598D03*
X342218Y244209D03*
Y232509D03*
X355737Y244209D03*
X348978D03*
X345598Y226660D03*
X352357D03*
X348978Y232509D03*
Y220809D03*
X352357Y238360D03*
X345598D03*
X342218Y220809D03*
X355737Y232509D03*
X338838Y246160D03*
X335458Y248109D03*
X338838Y242260D03*
Y234460D03*
X335458Y236409D03*
X338838Y238360D03*
X335458Y224709D03*
X355737Y248109D03*
X348978D03*
X355737Y220809D03*
X335458Y244209D03*
X338838Y253960D03*
X335458Y252009D03*
X338838Y265660D03*
X335458Y259809D03*
Y267609D03*
X345598Y265660D03*
X348978Y263709D03*
X355737Y259809D03*
X352357Y261760D03*
X345598Y273460D03*
Y269560D03*
X342218Y263709D03*
Y271509D03*
Y259809D03*
Y255909D03*
Y267609D03*
Y279310D03*
Y275409D03*
X338838Y257860D03*
X335458Y263709D03*
X348978Y267609D03*
X345598Y277360D03*
X348978Y279310D03*
Y275409D03*
Y271509D03*
X352357Y265660D03*
X355737Y263709D03*
X342218Y240309D03*
X352357Y234460D03*
X348978Y240309D03*
X355737D03*
Y228610D03*
X342218D03*
X298279Y324160D03*
X294899Y326109D03*
X321938Y341709D03*
X335458Y322209D03*
X311798Y292959D03*
X305039D03*
X321938Y283209D03*
X315178D03*
X318558Y281260D03*
Y292959D03*
X311798Y285160D03*
X328698Y310509D03*
X332078Y300760D03*
X328698Y283209D03*
X332078Y292959D03*
Y281260D03*
X298279Y308560D03*
X321938Y310509D03*
X315178D03*
X305039Y308560D03*
X311798D03*
X305039Y300760D03*
X325318D03*
X311798D03*
X298279D03*
X318558D03*
X325318Y292959D03*
Y281260D03*
X305039Y285160D03*
X298279D03*
Y292959D03*
X308418Y306609D03*
X301659Y310509D03*
Y306609D03*
X311798Y304660D03*
X305039D03*
X321938Y306609D03*
X325318Y304660D03*
Y308560D03*
X298279Y304660D03*
X294899Y302709D03*
X308418D03*
X301659D03*
X315178D03*
X321938D03*
X294899Y310509D03*
Y306609D03*
X318558Y304660D03*
Y308560D03*
X321938Y291009D03*
X318558Y296860D03*
X315178Y294909D03*
X321938D03*
X301659D03*
X325318Y285160D03*
Y289060D03*
Y296860D03*
X298279D03*
Y289060D03*
Y281260D03*
X308418Y298809D03*
X301659D03*
X308418Y283209D03*
X305039Y281260D03*
Y289060D03*
X308418Y291009D03*
Y287109D03*
X311798Y281260D03*
Y289060D03*
X308418Y294909D03*
X311798Y296860D03*
X305039D03*
X315178Y287109D03*
X318558Y285160D03*
X321938Y287109D03*
X301659Y283209D03*
Y287109D03*
Y291009D03*
X294899Y298809D03*
Y294909D03*
Y291009D03*
Y283209D03*
Y287109D03*
X315178Y298809D03*
X321938D03*
X318558Y289060D03*
X315178Y291009D03*
X332078Y308560D03*
Y304660D03*
X328698Y302709D03*
Y306609D03*
Y287109D03*
Y291009D03*
Y294909D03*
Y298809D03*
X332078Y296860D03*
Y285160D03*
Y289060D03*
X315178Y306609D03*
X308418Y310509D03*
X318558Y312460D03*
X325318D03*
X308418Y333909D03*
Y341709D03*
X325318Y339760D03*
Y335860D03*
X301659Y337809D03*
X315178Y330009D03*
X301659D03*
X308418Y337809D03*
X305039Y331960D03*
X298279Y328060D03*
Y331960D03*
X311798Y324160D03*
X308418Y330009D03*
X315178Y322209D03*
X321938D03*
X294899Y333909D03*
X305039Y328060D03*
X321938Y330009D03*
Y337809D03*
X328698Y330009D03*
Y326110D03*
Y333909D03*
X325318Y324160D03*
X318558Y320260D03*
X301659Y318309D03*
X308418D03*
X305039Y316360D03*
X332078Y331960D03*
Y339760D03*
X298279Y316360D03*
X294899Y322209D03*
Y318309D03*
X311798Y316360D03*
X308418Y326110D03*
X318558Y324160D03*
X311798Y312460D03*
X305039D03*
X298279D03*
X294899Y314409D03*
X308418D03*
X301659D03*
X328698D03*
X321938D03*
X332078Y328060D03*
X328698Y322209D03*
Y318309D03*
X332078Y324160D03*
Y320260D03*
Y316360D03*
X325318Y320260D03*
X305039D03*
X321938Y318309D03*
X315178D03*
X318558Y316360D03*
X301659Y322209D03*
X315178Y314409D03*
X332078Y312460D03*
X325318Y316360D03*
X305039Y324160D03*
X311798Y320260D03*
X308418Y322209D03*
X301659Y326110D03*
X335458Y310509D03*
X338838Y300760D03*
Y292959D03*
Y281260D03*
X335458Y283209D03*
X342218Y310509D03*
Y283209D03*
X335458Y298809D03*
X348978Y287109D03*
X345598Y285160D03*
Y281260D03*
X348978Y283209D03*
Y298809D03*
Y291009D03*
X345598Y289060D03*
Y292959D03*
Y296860D03*
X348978Y294909D03*
X345598Y300760D03*
X348978Y302709D03*
Y306609D03*
X345598Y304660D03*
Y308560D03*
X348978Y310509D03*
X342218Y302709D03*
Y306609D03*
Y291009D03*
Y287109D03*
Y294909D03*
Y298809D03*
X338838Y308560D03*
X335458Y302709D03*
X338838Y304660D03*
X335458Y306609D03*
Y287109D03*
X338838Y289060D03*
Y285160D03*
X335458Y291009D03*
X338838Y296860D03*
X335458Y294909D03*
X345598Y335860D03*
Y331960D03*
X348978Y314409D03*
X345598Y312460D03*
X348978Y322209D03*
X355737Y333909D03*
X345598Y316360D03*
X348978Y318309D03*
Y330009D03*
X352357Y331960D03*
X348978Y326110D03*
X335458Y314409D03*
Y326110D03*
Y318309D03*
X338838Y320260D03*
Y324160D03*
Y328060D03*
X342218Y314409D03*
X338838Y312460D03*
Y316360D03*
X335458Y330009D03*
X338838Y331960D03*
Y339760D03*
X345598Y328060D03*
Y339760D03*
X352357Y335860D03*
X348978Y333909D03*
X342218Y322209D03*
Y318309D03*
Y330009D03*
Y326110D03*
Y333909D03*
X355737Y337809D03*
X345598Y320260D03*
Y324160D03*
X335458Y337809D03*
X348978Y341709D03*
Y337809D03*
X305039Y339760D03*
X321938Y333909D03*
X311798Y328060D03*
X325318D03*
X315178Y333909D03*
X335458D03*
X298279Y339760D03*
X318558Y335860D03*
Y328060D03*
X294899Y337809D03*
X301659Y333909D03*
X328698Y337809D03*
X342218D03*
X308418Y349509D03*
X332078Y367060D03*
X321938Y345609D03*
X342218Y349509D03*
X345598Y347560D03*
X335458Y365109D03*
X352357Y347560D03*
X308418Y357309D03*
X311798Y359260D03*
X298279Y351460D03*
X294899Y349509D03*
Y353409D03*
X321938Y349509D03*
X318558Y359260D03*
X321938Y361209D03*
X298279Y343660D03*
X315178Y357309D03*
X301659D03*
Y349509D03*
X308418Y361209D03*
Y353409D03*
Y345609D03*
X305039Y347560D03*
X325318Y343660D03*
Y347560D03*
X328698Y365109D03*
X332078Y363160D03*
X328698Y345609D03*
X325318Y355360D03*
X332078Y347560D03*
Y355360D03*
X294899Y369010D03*
X325318Y367060D03*
Y370959D03*
X318558D03*
X308418Y365109D03*
X315178D03*
X325318Y363160D03*
X298279D03*
X305039Y370959D03*
X308418Y369010D03*
X305039Y367060D03*
X301659Y369010D03*
X298279Y370959D03*
X318558Y351460D03*
Y355360D03*
X315178Y349509D03*
Y353409D03*
X311798Y355360D03*
Y347560D03*
Y351460D03*
X305039D03*
X301659Y388509D03*
X308418D03*
X318558Y394359D03*
X324458Y399911D03*
X332078Y378760D03*
X318558Y386560D03*
X325318D03*
X301659Y376809D03*
X311798Y374860D03*
X325318D03*
X294899Y372909D03*
X308418D03*
X321938Y376809D03*
X318558Y382660D03*
Y378760D03*
X298279D03*
X305039D03*
X308418Y384609D03*
X311798Y382660D03*
Y378760D03*
X315178Y376809D03*
X328698D03*
X294899Y384609D03*
X318558Y390460D03*
X320808Y401941D03*
X298279Y386560D03*
Y390460D03*
X315178Y392410D03*
Y388509D03*
X311798Y386560D03*
X298279Y398260D03*
Y394359D03*
X294899Y396309D03*
X325318Y378760D03*
X321938Y380709D03*
X305039Y394359D03*
X302608Y402421D03*
X352357Y359260D03*
X345598Y370959D03*
X355737Y353409D03*
X348978D03*
X342218Y365109D03*
X338838Y347560D03*
X335458Y361209D03*
X338838Y359260D03*
Y355360D03*
Y351460D03*
X335458Y349509D03*
X345598Y359260D03*
X348978Y349509D03*
X345598Y343660D03*
X342218Y345609D03*
X355737Y349509D03*
X342218Y353409D03*
X338838Y367060D03*
X348978Y365109D03*
X355737D03*
X352357Y370959D03*
X355737Y376809D03*
Y388509D03*
X348978Y376809D03*
X342218Y388509D03*
Y376809D03*
Y384609D03*
X338838Y382660D03*
X345598D03*
X352357D03*
X348978Y392410D03*
X355737D03*
X335458Y372909D03*
Y384609D03*
Y380709D03*
X345598Y390460D03*
X352357Y386560D03*
X348978Y361209D03*
X355737D03*
X332078Y359260D03*
X321938Y353409D03*
X335458D03*
X325318Y359260D03*
X328698Y357309D03*
Y349509D03*
X301659Y372909D03*
Y384609D03*
X328698Y353409D03*
X305039Y382660D03*
X294899Y376809D03*
X308418D03*
X298279Y382660D03*
X315178Y361209D03*
X321938Y372909D03*
X311798Y367060D03*
X294899Y365109D03*
X301659Y353409D03*
Y365109D03*
X342218Y361209D03*
X345598Y355360D03*
X355737Y384609D03*
X352357Y367060D03*
X355737Y372909D03*
X352357Y378760D03*
X294899Y392410D03*
X338838Y378760D03*
Y370959D03*
X342218Y372909D03*
X348978D03*
X345598Y367060D03*
Y378760D03*
X348978Y388509D03*
X352357Y355360D03*
X305039Y343660D03*
X298279Y359260D03*
X321938Y365109D03*
X305039Y363160D03*
X335458Y345609D03*
X311798Y370959D03*
X294899Y357309D03*
X318558Y367060D03*
X305039Y359260D03*
X301659Y345609D03*
X294899D03*
X338838Y343660D03*
X332078D03*
X315178Y372909D03*
X348978Y345609D03*
X294289Y490444D03*
X301092Y490700D03*
X307675Y518057D03*
X326797Y499767D03*
X317714Y515364D03*
X321061Y512792D03*
X311701Y499136D03*
X331100Y510114D03*
X327754Y518157D03*
X314368Y512792D03*
X311021Y515364D03*
X317714Y510114D03*
X297835Y497644D03*
X308166Y512794D03*
X300982Y510114D03*
X304278Y515814D03*
X297635D03*
X294289Y510114D03*
X304392Y497300D03*
X324187Y499793D03*
X337793Y515364D03*
X350882Y509999D03*
X347833Y518157D03*
X341140Y512792D03*
X327754D03*
X321061Y518157D03*
X297835Y494944D03*
X294392Y493100D03*
X304392Y494700D03*
X301092Y493300D03*
X334447Y518157D03*
X341140D03*
X337793Y509999D03*
X344486Y515364D03*
Y510114D03*
X347833Y512792D03*
X351179Y515364D03*
X354307Y512792D03*
X354526Y518157D03*
X331100Y515364D03*
X334447Y512792D03*
X297635Y513114D03*
X294289Y518157D03*
X304328Y513114D03*
X300982Y518157D03*
X311021Y510114D03*
X314368Y518057D03*
X324407Y509999D03*
Y515364D03*
X326922Y497170D03*
X321061Y536957D03*
X317714Y529014D03*
X331100Y547914D03*
Y536957D03*
X327754Y529014D03*
X321061Y547914D03*
X314368D03*
Y536957D03*
X311021Y529014D03*
X307675Y548200D03*
X304278Y553614D03*
X297635D03*
X300982Y547914D03*
X294289D03*
X307675Y536957D03*
X304328Y530949D03*
X300982Y537049D03*
X297635Y530949D03*
X294289Y537049D03*
X307992Y533100D03*
X321334D03*
X321123Y552000D03*
X308100D03*
X307992Y570900D03*
X321334D03*
X294289Y574849D03*
Y585714D03*
X304328Y568749D03*
X307675Y574757D03*
X300982Y574849D03*
X307848Y588334D03*
X300982Y585714D03*
X297635Y568749D03*
X327754Y555857D03*
X317714D03*
X311021D03*
X327754Y566814D03*
X331100Y574757D03*
Y585714D03*
X314368D03*
Y574757D03*
X317714Y566814D03*
X311021D03*
X321061Y585714D03*
Y574757D03*
X334292Y533100D03*
Y552000D03*
X337793Y529014D03*
X351179Y547922D03*
Y536957D03*
X347833Y529022D03*
X341140Y547922D03*
Y536957D03*
X334292Y570900D03*
X337793Y555857D03*
X347833D03*
X337793Y566814D03*
X341140Y574757D03*
Y585722D03*
X351179Y574757D03*
Y585722D03*
X347833Y566822D03*
X297635Y550914D03*
X294289Y555957D03*
X304328Y550914D03*
X300982Y555957D03*
X294289Y528899D03*
X297635Y535100D03*
X300982Y528899D03*
X304328Y535100D03*
X297635Y588714D03*
X304328D03*
X294289Y566699D03*
X297635Y572900D03*
X300982Y566699D03*
X304328Y572900D03*
X344486Y529022D03*
Y536957D03*
X354525Y529022D03*
X334447Y536957D03*
X324407Y529014D03*
X314368Y566814D03*
X321061D03*
X344486Y566822D03*
X317714Y609864D03*
X304328Y606549D03*
X297635D03*
X294289Y612249D03*
X300982D03*
X307675Y611600D03*
X307892Y591000D03*
X321192Y589800D03*
X304278Y591414D03*
X297635D03*
X308157Y607220D03*
X327754Y607292D03*
X331100Y609864D03*
X327754Y593657D03*
X317714D03*
X311021D03*
X317714Y604614D03*
X311021D03*
X314368Y612457D03*
X321061D03*
X334292Y589800D03*
X337793Y593657D03*
Y604499D03*
X352109Y609918D03*
X347833Y607292D03*
X341140Y612457D03*
X347833Y593657D03*
X324407Y609864D03*
X334447Y607292D03*
X341140D03*
X337793Y609864D03*
X344486Y604614D03*
X347833Y612357D03*
X351179Y604499D03*
X354525Y612358D03*
X354526Y607292D03*
X331100Y604614D03*
X334447Y612457D03*
X294289Y604499D03*
X297635Y610700D03*
X294289Y593757D03*
X300982Y604499D03*
X304328Y610700D03*
X300982Y593757D03*
X311021Y609864D03*
X314368Y607292D03*
X324407Y604499D03*
X327754Y612457D03*
X321061Y607292D03*
X344486Y609864D03*
X375792Y6500D03*
X377592Y-10880D03*
X380232Y-10900D03*
X380200Y-1200D03*
X378792Y6500D03*
X357872Y-9786D03*
X367911D03*
Y-1858D03*
X357872D03*
X367911Y9114D03*
X357672D03*
X371258Y-1858D03*
Y-9800D03*
X376700Y-1300D03*
X374401Y-11346D03*
X373670Y17580D03*
X374773Y19819D03*
X358592Y30736D03*
X380792Y27812D03*
X357492Y14314D03*
X380792Y24933D03*
X357492Y11714D03*
X358619Y33342D03*
X357872Y28014D03*
X367911D03*
Y17042D03*
X357872Y17014D03*
X404722Y-4536D03*
X398029D03*
X401375Y-7108D03*
X408068Y-1743D03*
X411415Y-9786D03*
X398029Y9107D03*
X408069D03*
X411415Y-4536D03*
X394192Y-9700D03*
X409522Y-20794D03*
X401375Y-1743D03*
X411416Y17057D03*
X401376Y17042D03*
X394682Y17157D03*
X408184Y32100D03*
Y13200D03*
X398029Y28007D03*
X408069D03*
X365311Y17042D03*
X404722Y-9901D03*
X394682Y11792D03*
X394683Y-2200D03*
X408068Y-7108D03*
X414761Y-1743D03*
X398029Y-9901D03*
X361218Y9114D03*
X362662Y17014D03*
X361218Y-9786D03*
X364565Y9114D03*
Y-1858D03*
Y-9786D03*
X414761Y-7108D03*
X361218Y-1858D03*
X364565Y28014D03*
X414762Y28021D03*
X380600Y37400D03*
X380980Y60210D03*
X380892Y63200D03*
X357762Y49659D03*
X357772Y68335D03*
X371042Y46900D03*
X380792Y56500D03*
X357762Y52333D03*
X364565Y54842D03*
X361218D03*
Y35942D03*
X367911Y46914D03*
Y54842D03*
Y35942D03*
X358619Y36031D03*
X358618Y54842D03*
X357872Y65736D03*
X366992Y65950D03*
X357872Y46914D03*
X357965Y92500D03*
X367911Y87500D03*
X368311Y92500D03*
X367742Y73450D03*
X357872Y87500D03*
X358491Y73479D03*
X384992Y81600D03*
X375337Y86377D03*
Y83877D03*
X357772Y70935D03*
X374292Y77200D03*
Y74100D03*
X365607Y92500D03*
X365234Y87500D03*
X362792Y92500D03*
X362435Y87500D03*
X408069Y35942D03*
X401376Y54842D03*
X408069Y46907D03*
X394682Y68492D03*
X408184Y51000D03*
X394492Y54700D03*
X398029Y65807D03*
X408069D03*
X394682Y49592D03*
X398029Y35942D03*
Y46907D03*
X411416Y54857D03*
X394682Y87392D03*
X401375Y92757D03*
X398029Y84800D03*
Y73742D03*
X408068Y87392D03*
X411415Y89964D03*
X408069Y73742D03*
X411415Y84714D03*
X408184Y69900D03*
X404722Y89964D03*
X401375Y87392D03*
X414761Y92757D03*
X398029Y89964D03*
X404722Y84599D03*
X414761Y87392D03*
X408068Y92757D03*
X364565Y35942D03*
X404723Y35957D03*
X386292Y98800D03*
X408126Y103116D03*
Y105750D03*
X414820Y105800D03*
X401375D03*
Y103116D03*
X414819D03*
X369257Y213009D03*
X376017Y216909D03*
X362497D03*
X382777Y213009D03*
X369257Y216909D03*
X382777D03*
X362497Y213009D03*
X389537Y216909D03*
X376017Y213009D03*
X386157Y207159D03*
X362497Y209109D03*
X382777D03*
X376017D03*
X382777Y201309D03*
X365877Y214960D03*
X372637D03*
X379397D03*
X359117D03*
X365877Y203260D03*
X376017Y205211D03*
X362497Y205210D03*
X386157Y214960D03*
X389537Y209109D03*
X372637Y207159D03*
X389537Y213009D03*
X415634Y204496D03*
Y212296D03*
X396296Y209109D03*
X404392Y199100D03*
X415634Y208397D03*
X407706Y209109D03*
X399676Y207159D03*
X396296Y213009D03*
Y216909D03*
X415634Y216196D03*
X392898Y195041D03*
X392916Y214960D03*
Y203260D03*
X396296Y197359D03*
X399676Y203260D03*
Y214960D03*
X365877Y242260D03*
X372637D03*
X362497Y248109D03*
X359117Y250060D03*
X389537Y240309D03*
X382777D03*
X386157Y242260D03*
X379397D03*
X389537Y244209D03*
X382777D03*
X376017D03*
X386157Y246160D03*
X379397D03*
X372637D03*
X365877D03*
X369257Y248109D03*
X365877Y250060D03*
X359117Y253960D03*
X362497Y252009D03*
X399676Y242260D03*
X392916D03*
Y246160D03*
X396296Y244209D03*
Y240309D03*
X359117Y242260D03*
X372637Y222760D03*
X365877D03*
X386157D03*
X379397D03*
X359117D03*
X369257Y240309D03*
X376017D03*
X359117Y246160D03*
X386157Y226660D03*
X389537Y232509D03*
X369257Y244209D03*
X362497D03*
X379397Y238360D03*
X362497Y220809D03*
X379397Y250060D03*
X369257Y220809D03*
X382777D03*
X376017D03*
X386157Y238360D03*
X372637Y226660D03*
X365877D03*
X369257Y232509D03*
X362497D03*
X379397Y226660D03*
X382777Y232509D03*
X376017D03*
X359117Y226660D03*
X372637Y250060D03*
X389537Y248109D03*
Y220809D03*
X376017Y248109D03*
X382777D03*
X386157Y250060D03*
X359117Y238360D03*
X365877D03*
X372637D03*
X365877Y253960D03*
X362497Y255909D03*
X359117Y257860D03*
X372637Y253960D03*
X376017Y252009D03*
X357057Y277360D03*
X368127Y264300D03*
X364747Y266300D03*
X361492Y268100D03*
X362497Y259809D03*
X365877Y257860D03*
X369257Y255909D03*
X357092Y270700D03*
X391787Y254259D03*
X388407Y256500D03*
X359648Y269777D03*
X374887Y260300D03*
X385027Y254259D03*
X359117Y261760D03*
X371507Y262300D03*
X381647Y256400D03*
X378267Y258400D03*
X357057Y273460D03*
X390894Y264899D03*
X369257Y252009D03*
X392916Y222760D03*
Y250060D03*
Y238360D03*
X396296Y248109D03*
Y220809D03*
X399676Y250060D03*
X407706Y248109D03*
Y240309D03*
Y232509D03*
X399676Y246160D03*
X415634Y247396D03*
Y235696D03*
Y223996D03*
X407706Y220809D03*
X415634Y239596D03*
X396296Y228610D03*
X399676Y222760D03*
X415634Y220096D03*
Y227896D03*
X399676Y238360D03*
X392916Y226660D03*
X396296Y232509D03*
X399676Y226660D03*
X395166Y256400D03*
X398546Y254259D03*
X405306Y254500D03*
X401926Y256500D03*
X397394Y264899D03*
X400394D03*
X393894D03*
X379397Y230559D03*
X389537Y228610D03*
X392916Y234460D03*
X386157D03*
X359117D03*
X362497Y240309D03*
X376017Y236409D03*
X407706Y228610D03*
X382777Y236409D03*
X399676Y234460D03*
X382777Y228610D03*
X362497D03*
X369257D03*
X365877Y234460D03*
X372637D03*
X376017Y228610D03*
X407448Y338641D03*
X416448D03*
X413948D03*
X410948D03*
X357057Y281260D03*
Y296860D03*
Y285160D03*
Y292959D03*
Y300760D03*
Y308560D03*
Y304660D03*
Y289060D03*
Y312460D03*
X364747Y331509D03*
X361367Y329560D03*
X357987Y327609D03*
X371507Y335409D03*
X362497Y337809D03*
X369257Y341709D03*
X368127Y333460D03*
X365877Y339760D03*
X374887Y337360D03*
X381647Y341260D03*
X378267Y339309D03*
X359117Y335860D03*
X357057Y320260D03*
Y324160D03*
X370650Y312441D03*
X378156D03*
X375674D03*
X373162Y312400D03*
X368165Y312504D03*
X359117Y339760D03*
X362497Y341709D03*
X357057Y316360D03*
X414294Y292904D03*
X411294D03*
Y309904D03*
X414294D03*
X403648Y338341D03*
X401148D03*
X398148D03*
X394648D03*
X379397Y351460D03*
X362497Y349509D03*
X376017D03*
X382777Y353409D03*
Y357309D03*
X379397Y355360D03*
X359117Y347560D03*
X396296Y357309D03*
X399676Y355360D03*
X369257Y361209D03*
X376017Y357309D03*
X379397Y359260D03*
X382777Y349509D03*
X379397Y347560D03*
X391787Y347109D03*
X388407Y345160D03*
X372637Y343660D03*
X385027Y343209D03*
X379397Y370959D03*
X372637D03*
X365877D03*
X359117D03*
X386157D03*
X362497Y353409D03*
X376017D03*
X369257D03*
Y349509D03*
X386157Y355360D03*
X365877Y347560D03*
X369257Y345609D03*
X376017D03*
X386157Y351460D03*
Y359260D03*
X372637Y347560D03*
X389537Y353409D03*
X372637Y359260D03*
X365877D03*
X359117D03*
X365877Y343660D03*
X389537Y365109D03*
X382777D03*
X369257D03*
X362497D03*
X376017D03*
Y376809D03*
X369257D03*
X382777Y388509D03*
X369257D03*
X362497D03*
X376017D03*
X390657Y394359D03*
X391787Y402800D03*
X357987D03*
X369257Y392410D03*
X362497D03*
X379397Y382660D03*
X372637D03*
X365877D03*
X359117D03*
X379397Y390460D03*
X378267Y402800D03*
X376017Y392410D03*
X386157Y382660D03*
X389537Y388509D03*
Y376809D03*
X382777D03*
X362497D03*
X396296Y353409D03*
X411086Y351460D03*
X405306Y347109D03*
X399676Y351460D03*
X392916Y355360D03*
X395166Y345160D03*
X398546Y347109D03*
X401926Y345160D03*
X392916Y370959D03*
X399676D03*
X396296Y365109D03*
X403056D03*
Y357309D03*
X392916Y351460D03*
Y359260D03*
X396296Y388509D03*
Y376809D03*
X392916Y382660D03*
Y390460D03*
X399676Y382660D03*
X406568Y402471D03*
X403056Y392410D03*
X411086Y390460D03*
Y374860D03*
X403056Y376809D03*
Y388509D03*
X411547Y368260D03*
Y365660D03*
X403056Y353409D03*
X411447Y363160D03*
X411431Y359351D03*
X411086Y355360D03*
X386157Y367060D03*
X396296Y384609D03*
X372637Y390460D03*
X403056Y372909D03*
X392916Y367060D03*
X382777Y361209D03*
X399676Y367060D03*
X389537Y361209D03*
X365877Y367060D03*
X372637D03*
X362497Y361209D03*
X403056D03*
X365877Y355360D03*
X379397Y367060D03*
X376017Y384609D03*
X396296Y372909D03*
X386157Y378760D03*
X359117D03*
X362497Y384609D03*
X392916Y378760D03*
X379397D03*
X382777Y372909D03*
X389537D03*
X399676Y378760D03*
X382777Y384609D03*
X365877Y378760D03*
X372637D03*
X362497Y372909D03*
X369257D03*
Y384609D03*
X376017Y372909D03*
X399676Y390460D03*
X389537Y384609D03*
X396296Y361209D03*
X359117Y367060D03*
Y355360D03*
X399676Y359260D03*
X372637Y355360D03*
X376017Y361209D03*
X385244Y504027D03*
X386630Y521860D03*
X359042Y515200D03*
X358918Y510114D03*
X366865D03*
Y515152D03*
X375192Y516356D03*
Y518856D03*
X401375Y518157D03*
X398029Y509999D03*
X411415Y515364D03*
X408068Y512792D03*
X411415Y510114D03*
X364265Y515152D03*
X401375Y512792D03*
X404722Y515364D03*
X394682Y512792D03*
X408068Y518157D03*
X414761Y512792D03*
X404722Y509999D03*
X398029Y515364D03*
X414761Y518157D03*
X364265Y510114D03*
X361642Y515200D03*
X361518Y510114D03*
X370596Y585614D03*
X370080Y555700D03*
X366890Y586000D03*
X376892Y581127D03*
X357539Y550511D03*
X357661Y534000D03*
X376829Y546303D03*
X357661Y531546D03*
X357539Y553111D03*
X376785Y538305D03*
X363760Y529293D03*
X367692Y547914D03*
X357672D03*
X357872Y528942D03*
X367911Y529057D03*
X367692Y536200D03*
X357910Y536727D03*
X376792Y543700D03*
X357724Y569474D03*
X376892Y577500D03*
X356798Y588366D03*
X357724Y571973D03*
X367211Y555842D03*
X357910D03*
X367192Y566814D03*
X357910D03*
X367192Y574742D03*
X357872D03*
X357025Y585714D03*
X398029Y536942D03*
X408069Y547907D03*
Y536942D03*
X394587Y529026D03*
X408184Y533100D03*
Y552000D03*
X398029Y547907D03*
X394682Y569492D03*
X408184Y570900D03*
X401376Y555842D03*
X411416Y555857D03*
X398029Y574742D03*
Y585707D03*
X408069D03*
Y574742D03*
X394682Y550592D03*
X361518Y547914D03*
X361320Y555842D03*
X364265Y547914D03*
X364565Y555842D03*
X394595Y537058D03*
X398029Y529007D03*
X361218Y566814D03*
X394682Y588392D03*
X361518Y585714D03*
X364265D03*
X408069Y566807D03*
X398029D03*
X361218Y574742D03*
X408069Y529007D03*
X364565Y574742D03*
Y566814D03*
X401377Y536957D03*
X414763D03*
Y566822D03*
X386970Y623539D03*
X378600Y606200D03*
X408068Y612657D03*
X413324Y623559D03*
X399824D03*
X356798Y590939D03*
X373400Y593800D03*
X376204Y593650D03*
X374039Y611186D03*
X357872Y604614D03*
X367170Y611759D03*
X357872Y612242D03*
X367911Y593642D03*
X357026D03*
X367911Y604614D03*
X371134Y612453D03*
X370659Y593691D03*
X371312Y604709D03*
X411415Y609864D03*
X394682Y607292D03*
X408184Y589800D03*
X398029Y609864D03*
X401376Y593642D03*
X401375Y607292D03*
X411416Y593657D03*
X411415Y604614D03*
X414761Y612657D03*
X394682D03*
X408068Y607292D03*
X404722Y609864D03*
X414761Y607292D03*
X361218Y612242D03*
X361964Y593642D03*
X364565Y612242D03*
X365311Y593642D03*
X364565Y604614D03*
X401376Y612658D03*
X404722Y604499D03*
X398029D03*
X361218Y604614D03*
X414763Y593657D03*
X438187Y-4536D03*
X451573Y-9901D03*
X428147Y-1743D03*
X421454Y-7108D03*
X434840Y-1743D03*
X418108Y-4536D03*
X431494D03*
X424801D03*
X428147Y-7108D03*
X434840D03*
X431494Y9107D03*
X424801D03*
X418108D03*
Y-9701D03*
X441533Y-1843D03*
Y9107D03*
X447744Y-7180D03*
X451573Y-1801D03*
Y9114D03*
X436392Y-20760D03*
X422892Y-20789D03*
X421454Y-1817D03*
X434842Y17057D03*
X441533Y17042D03*
X418108D03*
X428149Y17057D03*
X448226Y11100D03*
Y28100D03*
X433508Y32100D03*
X448292Y31900D03*
X421368Y32100D03*
X433508Y13200D03*
X448292Y13700D03*
X421368Y13200D03*
X448892Y17000D03*
X451573Y27899D03*
X424801Y28007D03*
X451573Y17157D03*
X418108Y28007D03*
X441533D03*
X458266Y-1751D03*
X460912Y-7700D03*
Y-4100D03*
X458266Y-9901D03*
X454533Y-4100D03*
X478344Y-3700D03*
X474998Y-9901D03*
X464758Y-7050D03*
X469832Y-7260D03*
X464732Y-4401D03*
X469832Y-4651D03*
X454533Y-7851D03*
X458116Y9114D03*
X469832Y-2051D03*
X464732Y-1801D03*
X474998Y-1751D03*
X469845Y-9864D03*
X478344Y-7851D03*
X464758Y-9652D03*
X474998Y9114D03*
X464732Y9098D03*
X478344Y29949D03*
X460912Y30100D03*
Y14814D03*
X469832Y17114D03*
X454569Y14714D03*
X460912Y33700D03*
X458266Y27899D03*
X454533Y33700D03*
X474998Y27899D03*
X464758Y30750D03*
X469832Y33149D03*
X464732Y33399D03*
X454533Y29949D03*
X469792Y9300D03*
X469832Y30540D03*
X458266Y17157D03*
X460912Y12114D03*
X454619D03*
X474998Y17157D03*
X478344Y12114D03*
X464732Y14300D03*
X469832Y14514D03*
X464732Y11700D03*
X469832Y11914D03*
X478344Y14814D03*
X469845Y27936D03*
X464792Y28100D03*
X464692Y16900D03*
X444880Y-9786D03*
X431494Y-9901D03*
Y28007D03*
X438187Y-9786D03*
X424801D03*
X444880Y-4536D03*
X438189Y28022D03*
X434842Y54857D03*
X441533Y54842D03*
X424801Y46907D03*
X431494D03*
X428149Y54857D03*
X441533Y46907D03*
X448414Y35761D03*
X448973Y54883D03*
X451573Y35999D03*
X448627Y68090D03*
X448517Y46975D03*
X448492Y51000D03*
X421368D03*
X433508D03*
X451573Y46900D03*
X431494Y65807D03*
X451573Y65699D03*
X424801Y65807D03*
X451573Y54957D03*
X418108Y65807D03*
Y54842D03*
X441533Y65807D03*
X431494Y35942D03*
X441533D03*
X424801D03*
X418108D03*
Y46907D03*
X424801Y89964D03*
X438187D03*
X428147Y92500D03*
X424801Y84800D03*
X431400D03*
X431494Y73742D03*
X441533Y87392D03*
Y92500D03*
Y73742D03*
X418108Y89964D03*
Y84599D03*
Y73742D03*
X424801D03*
X434840Y92500D03*
X448651Y70896D03*
X433508Y69900D03*
X421368D03*
X451573Y84714D03*
Y73799D03*
X448610Y85296D03*
X448599Y73589D03*
X448692Y89900D03*
X438187Y84714D03*
X431494Y89964D03*
X444880D03*
Y84714D03*
X451573Y92757D03*
X428147Y87392D03*
X421454Y92757D03*
X434840Y87392D03*
X474998Y36049D03*
X464732Y46898D03*
X460912Y52614D03*
X458266Y36049D03*
X458116Y46914D03*
X464758Y65950D03*
X474998Y46914D03*
X458266Y65699D03*
X474998D03*
X464758Y68550D03*
X469832Y68340D03*
X458266Y54957D03*
X460912Y49914D03*
X454619Y49564D03*
X474998Y54957D03*
X478344Y34100D03*
Y49914D03*
X464732Y52100D03*
X469832Y49714D03*
X464732Y49500D03*
X454533Y67749D03*
X454569Y52514D03*
X469832Y52314D03*
Y54914D03*
X469792Y47100D03*
Y35800D03*
X464692Y54700D03*
X464732Y35999D03*
X478344Y52614D03*
X460912Y67900D03*
X478344Y67749D03*
X469845Y65736D03*
X478344Y87714D03*
X464732Y89900D03*
X469832Y70949D03*
Y87514D03*
X464732Y71199D03*
Y87300D03*
X469832Y90114D03*
X458116Y84714D03*
X464708Y92500D03*
X464732Y84698D03*
X469808Y84700D03*
X474998Y73849D03*
X469858Y73550D03*
X474998Y84714D03*
X478344Y90414D03*
X469832Y92714D03*
X460912Y90314D03*
X464732Y73799D03*
X458266Y73849D03*
X454569Y90314D03*
X460912Y71500D03*
X458266Y92757D03*
X460912Y87714D03*
X454533Y71500D03*
X454619Y87714D03*
X478344Y71900D03*
X474998Y92757D03*
X444882Y35957D03*
X434842Y73757D03*
X421512Y103116D03*
X427696Y105800D03*
X421503D03*
X427696Y103100D03*
X441743Y199841D03*
X421464Y199583D03*
X446253Y206446D03*
X425974D03*
X453013Y218147D03*
X449633Y212296D03*
Y216196D03*
X422594D03*
X419214Y214247D03*
X436113Y212296D03*
X432733Y214247D03*
X429354Y216196D03*
X432733Y218147D03*
X425974D03*
X429353Y212296D03*
X446253Y218147D03*
X442873Y216196D03*
X439493Y214247D03*
X436113Y216196D03*
X453013Y214247D03*
X439493Y210346D03*
X434983Y198931D03*
X439493Y218147D03*
X459773D03*
X455263Y198050D03*
X473292Y218147D03*
X469913Y216196D03*
X469912Y212296D03*
X475692Y199900D03*
X466533Y218147D03*
X473292Y214247D03*
X476672Y212296D03*
Y216196D03*
X459773Y214247D03*
X466533Y206446D03*
X456393Y216196D03*
X462023Y198327D03*
X456393Y212296D03*
X463153Y216196D03*
X422594Y235696D03*
Y247396D03*
X429354Y239596D03*
X425974Y233746D03*
Y241547D03*
X436113Y239596D03*
X422594D03*
X432733Y233746D03*
X429354Y251296D03*
X453013Y245447D03*
Y229847D03*
Y237647D03*
X449633Y251296D03*
Y247396D03*
Y227896D03*
Y223996D03*
X436113Y243496D03*
X442873D03*
X422594D03*
X425974Y245447D03*
Y249347D03*
X432733D03*
X436113Y251296D03*
X429354Y247396D03*
X422594Y251296D03*
X446253Y245447D03*
X419214Y249347D03*
X432733Y245447D03*
X439493Y237647D03*
X446253D03*
X422594Y223996D03*
Y231797D03*
X419214Y233746D03*
Y237647D03*
X436113Y231797D03*
X439493Y241547D03*
X419214D03*
X436113Y223996D03*
X429354D03*
Y220096D03*
Y227896D03*
X446253Y229847D03*
X432733D03*
X425974D03*
X439493Y233746D03*
X442873Y231797D03*
Y223996D03*
X425974Y237647D03*
X432733D03*
X449633Y220096D03*
X419214Y245447D03*
X453013Y222047D03*
X425974Y225947D03*
X422594Y220096D03*
Y227896D03*
X419214Y222047D03*
Y229847D03*
X432733Y241547D03*
X446253Y233746D03*
Y241547D03*
X442873Y239596D03*
X453013Y233746D03*
Y241547D03*
Y249347D03*
X429354Y243496D03*
X449633D03*
X429354Y235696D03*
X449633D03*
X436113Y247396D03*
X446253Y249347D03*
X442873Y251296D03*
X439493Y249347D03*
X442873Y247396D03*
X439493Y245447D03*
X444408Y267305D03*
X440500Y266500D03*
X418084Y253546D03*
X451883Y265246D03*
X434983Y255497D03*
X438363Y257446D03*
X421464Y255497D03*
X431604Y257446D03*
X448503Y263297D03*
X445123Y261346D03*
X441743Y259397D03*
X446253Y253247D03*
X447148Y278841D03*
X449848D03*
X450800Y275600D03*
X429781Y264793D03*
X439493Y253247D03*
X449633Y255196D03*
Y259096D03*
X446253Y257147D03*
X442873Y255196D03*
X453013Y257147D03*
Y261047D03*
X448900Y269600D03*
X476672Y227896D03*
X459773Y225947D03*
X466533Y233746D03*
X476672Y239596D03*
X463153D03*
X473292Y233746D03*
X469913Y231797D03*
Y243496D03*
Y239596D03*
X456393D03*
X469913Y251296D03*
X466533Y245447D03*
X473292D03*
X466533Y249347D03*
X473292D03*
X459773Y245447D03*
Y249347D03*
X476672Y223996D03*
Y243496D03*
Y251296D03*
X469913Y247396D03*
Y223996D03*
X473292Y229847D03*
X469913Y227896D03*
X466533Y229847D03*
X473292Y237647D03*
X466533D03*
X469913Y220096D03*
X456393Y243496D03*
Y251296D03*
X459773Y233746D03*
Y241547D03*
Y237647D03*
X456393Y223996D03*
Y231797D03*
X476672D03*
X463153Y243496D03*
Y251296D03*
Y231797D03*
Y223996D03*
X456393Y227896D03*
X466533Y222047D03*
X476672Y259096D03*
X463153D03*
X458408Y278940D03*
X477792Y272747D03*
X462023Y271097D03*
X458643Y269146D03*
X456393Y262996D03*
Y259096D03*
X459773Y261047D03*
X469913Y255196D03*
X473292Y257147D03*
X466533D03*
X468783Y274997D03*
X469913Y270796D03*
X466533Y264947D03*
X456393Y255196D03*
X463153D03*
X476672D03*
X459773Y257147D03*
X465100Y280300D03*
X455263Y267197D03*
X466533Y261047D03*
X463153Y262996D03*
X477792Y276646D03*
Y280547D03*
X453400Y275600D03*
X473292Y261047D03*
X469913Y259096D03*
X476672Y266896D03*
X473292Y268847D03*
Y264947D03*
X474413Y274696D03*
X469913Y278596D03*
X466533Y268847D03*
X469913Y262996D03*
X458400Y276400D03*
X459773Y264947D03*
X426494Y338361D03*
X430089Y338428D03*
X442020Y339220D03*
X419400Y338600D03*
X438240Y339380D03*
X449500Y309800D03*
X451648Y308341D03*
X447000Y309800D03*
X421494Y292904D03*
X435894D03*
X432894D03*
X440094D03*
X443094D03*
X425694D03*
X418494D03*
X428694D03*
X418494Y309904D03*
X421494D03*
X425694D03*
X428694D03*
X432894D03*
X435894D03*
X440094Y309841D03*
X443148D03*
X450700Y335550D03*
X453200D03*
X469913Y305896D03*
X477792Y307851D03*
X469913Y286396D03*
X477792Y303947D03*
Y288347D03*
X464000Y294500D03*
X454148Y310341D03*
Y307841D03*
X469913Y298096D03*
Y301996D03*
X477792Y284447D03*
Y296147D03*
Y300047D03*
Y292247D03*
Y311747D03*
X469913Y309797D03*
X453400Y293686D03*
X469913Y282496D03*
Y294196D03*
Y290296D03*
X477792Y315647D03*
Y319547D03*
X458643Y338746D03*
X477792Y327347D03*
X462948Y315251D03*
X463671Y319386D03*
X474413Y329296D03*
X468783Y332897D03*
X474413Y333196D03*
Y325396D03*
X477792Y323446D03*
X456900Y333000D03*
X469913Y313696D03*
Y317596D03*
X455263Y340697D03*
X462848Y312741D03*
X467653Y340996D03*
X474413D03*
Y337096D03*
X469913Y321496D03*
X477792Y331247D03*
Y335147D03*
Y339047D03*
X463800Y289500D03*
X443993Y370247D03*
X437233Y378047D03*
X440613Y376096D03*
X443993Y374147D03*
X464273Y342947D03*
X457513Y350747D03*
X460893Y344896D03*
X474413D03*
X443993Y358547D03*
X441743Y348497D03*
X440613Y352696D03*
X437233Y358547D03*
X450753Y366347D03*
Y350747D03*
Y358547D03*
X437233Y362447D03*
X423714D03*
X433854Y368296D03*
X427094D03*
X440613Y364396D03*
X427094Y372197D03*
X447373D03*
Y368296D03*
X440613Y372197D03*
Y368296D03*
X443993Y366347D03*
X427094Y356596D03*
X433854Y352696D03*
X437233Y354647D03*
X423714D03*
X430474D03*
X427094Y360496D03*
X433854D03*
X445123Y346546D03*
X427094Y352696D03*
X447373Y356596D03*
X451883Y342646D03*
X448503Y344597D03*
X421464Y348497D03*
X438363Y346546D03*
X424844D03*
X434983Y348497D03*
X428224D03*
X431604Y346546D03*
X430474Y385847D03*
X450753Y397547D03*
X440613Y395595D03*
X429354Y399496D03*
X433854Y379996D03*
X423714Y381947D03*
X430474Y374146D03*
X423714D03*
X437233D03*
X430474Y378047D03*
X433854Y376096D03*
X443993Y397546D03*
Y401447D03*
Y393647D03*
X440613Y391696D03*
X443993Y385847D03*
X427094Y376096D03*
X437233Y381947D03*
X447373Y376096D03*
X440613Y379996D03*
X443993Y378047D03*
X423715Y397548D03*
X430474Y393647D03*
X433854Y391696D03*
X423715Y401449D03*
X450753Y385847D03*
Y393647D03*
Y378047D03*
X437233Y389747D03*
Y385847D03*
X423714D03*
X477792Y342947D03*
Y362447D03*
Y354647D03*
Y358547D03*
X457513Y362447D03*
X464273Y346847D03*
X471033Y342947D03*
X454133Y372197D03*
Y364396D03*
Y348796D03*
Y352696D03*
X464273Y366347D03*
X474413Y372197D03*
X471033Y366347D03*
X467653Y372197D03*
X474413Y364396D03*
X464273Y350747D03*
X474413Y348796D03*
X471033Y350747D03*
X474413Y352696D03*
X471033Y358547D03*
X464273D03*
X467653Y368296D03*
Y348796D03*
X460893Y372197D03*
Y364396D03*
Y352696D03*
X457513Y354647D03*
Y358547D03*
Y346847D03*
X477792Y389747D03*
X457513D03*
X471033Y393647D03*
X460893Y395595D03*
X464273Y401447D03*
X471033D03*
X460893Y391696D03*
X457513Y385847D03*
Y381947D03*
X460893Y379996D03*
X477792Y381947D03*
X474413Y391696D03*
X464273Y385847D03*
X454133Y391696D03*
Y379996D03*
X471033Y385847D03*
X464273Y393647D03*
X474413Y379996D03*
X471033Y378047D03*
X467653Y376096D03*
X464273Y378047D03*
Y397546D03*
X477792Y385847D03*
Y346847D03*
Y350747D03*
X471033Y346847D03*
X454133Y356596D03*
X443993Y362447D03*
X460893Y376096D03*
X450753Y370247D03*
X464273D03*
X454133Y376096D03*
X433854Y372197D03*
Y364396D03*
X437233Y370247D03*
X423714D03*
X427094Y364396D03*
X477792Y366347D03*
X427094Y379996D03*
X477792Y378047D03*
X427094Y391696D03*
X477792Y370247D03*
X427094Y383896D03*
X471033Y370247D03*
X474413Y376096D03*
X430474Y389747D03*
X433854Y383896D03*
X423714Y389747D03*
X447373Y387796D03*
X467653Y383896D03*
X447373Y379996D03*
X467653Y391696D03*
X447373D03*
X471033Y389747D03*
Y381947D03*
X460893Y387796D03*
X474413D03*
X464273Y389747D03*
Y381947D03*
X450753D03*
X440613Y387796D03*
X454133D03*
X443993Y381947D03*
X467653Y352696D03*
X447373D03*
X457513Y366347D03*
X467653Y364396D03*
X447373D03*
X457513Y378047D03*
X467653Y356596D03*
X457513Y370247D03*
X430474Y366347D03*
X471033Y362447D03*
X460893Y356596D03*
X474413D03*
X464273Y362447D03*
X450753D03*
X440613Y356596D03*
X447091Y407782D03*
X428224Y407800D03*
X443993Y405347D03*
X467653Y407296D03*
X464273Y405347D03*
X441533Y512792D03*
Y518057D03*
X433192Y497650D03*
X434840Y518157D03*
X431494Y509999D03*
X424801Y510114D03*
X418108Y515364D03*
Y509999D03*
X428147Y518157D03*
X451573Y510114D03*
X448692Y515300D03*
X447735Y512794D03*
X474998Y510114D03*
X464732Y510098D03*
X460912Y515714D03*
X458116Y510114D03*
X454569Y515714D03*
X478344Y515814D03*
X464708Y517900D03*
X469832Y518114D03*
X464732Y512700D03*
X469832Y512914D03*
X464732Y515300D03*
X478344Y513114D03*
X474998Y518157D03*
X454619Y513114D03*
X451573Y518157D03*
X460912Y513114D03*
X458266Y518157D03*
X444880Y510114D03*
Y515364D03*
X431494D03*
X435192Y499400D03*
X438187Y510114D03*
Y515364D03*
X424801D03*
X434840Y512792D03*
X421454Y518157D03*
X428147Y512792D03*
X469832Y515514D03*
X418108Y536942D03*
Y547907D03*
X431494D03*
X424801D03*
X441533D03*
X418108Y529007D03*
X431494Y536942D03*
X424801D03*
X441533Y536957D03*
Y529007D03*
X451573Y547914D03*
Y536999D03*
X448510Y549843D03*
X448410Y531156D03*
X448432Y536723D03*
X448692Y553100D03*
X448557Y534061D03*
X421368Y533100D03*
X434395Y532904D03*
X433508Y552000D03*
X421368D03*
X447735Y588394D03*
X433508Y570900D03*
X421368D03*
X451573Y585714D03*
Y574799D03*
X448226Y569200D03*
X448291Y574773D03*
X451573Y566699D03*
X418108Y555842D03*
X428149Y555857D03*
X434842D03*
X441533Y555842D03*
Y585707D03*
Y574742D03*
X418108Y566807D03*
X441533D03*
X424801Y574742D03*
X418108Y585599D03*
Y574742D03*
X431494D03*
Y585707D03*
X424801D03*
X464732Y536999D03*
X460912Y553514D03*
X458116Y547914D03*
X454619Y550914D03*
X454569Y553514D03*
X454533Y530949D03*
X460912Y531100D03*
X458266Y537049D03*
X469845Y528936D03*
X474998Y537049D03*
X464758Y529150D03*
X469858Y536750D03*
X478344Y553614D03*
X464732Y547898D03*
X474998Y547914D03*
X469808Y547900D03*
X478344Y530949D03*
Y568749D03*
X464732Y574799D03*
X469808Y585700D03*
X469858Y574550D03*
X474998Y574849D03*
Y585714D03*
X464732Y585698D03*
X464758Y566950D03*
X469845Y566736D03*
X458266Y574849D03*
X460912Y568900D03*
X458116Y585714D03*
X454533Y568749D03*
X464708Y555700D03*
X469832Y555914D03*
Y534149D03*
X464758Y531750D03*
X474998Y528899D03*
X478344Y535100D03*
X451573Y528899D03*
X454533Y534700D03*
X458266Y528899D03*
X460912Y534700D03*
X469832Y553314D03*
X464732Y550500D03*
X469832Y550714D03*
X464732Y553100D03*
X478344Y550914D03*
X474998Y555957D03*
X451573D03*
X460912Y550914D03*
X458266Y555957D03*
X478344Y588714D03*
X454619D03*
X460912D03*
X469832Y569340D03*
Y571949D03*
X464758Y569550D03*
X474998Y566699D03*
X478344Y572900D03*
X454533Y572500D03*
X458266Y566699D03*
X460912Y572500D03*
X431494Y566807D03*
X464732Y588300D03*
X469832Y588514D03*
X464732Y534399D03*
X469832Y531540D03*
X424801Y566807D03*
X464732Y572199D03*
X444882Y536957D03*
X434842D03*
X421456Y529022D03*
X444880Y566822D03*
X421454Y612560D03*
X441533Y612557D03*
X447766Y612659D03*
X453250Y623320D03*
X474998Y612649D03*
X464732Y612599D03*
X458266Y612649D03*
X456910Y623320D03*
X427324Y623541D03*
X451573Y612599D03*
X441533Y607292D03*
X434840D03*
X428147D03*
X418108Y609864D03*
X424801D03*
X447744Y607220D03*
X448692Y590900D03*
X420634Y589800D03*
X433500D03*
X431494Y609864D03*
X418108Y593642D03*
X434842Y593657D03*
X428149D03*
X441533Y593642D03*
X418108Y604499D03*
X478344Y591414D03*
X464708Y593500D03*
X469832Y593714D03*
X464758Y604750D03*
X469845Y604536D03*
X478344Y606549D03*
X469858Y612350D03*
X460912Y591314D03*
Y606700D03*
X469832Y591114D03*
X469833Y607140D03*
X454533Y606549D03*
X454569Y591314D03*
X478344Y610700D03*
X474998Y593757D03*
X451573Y604499D03*
X454533Y610300D03*
X451573Y593757D03*
X458266Y604499D03*
Y593757D03*
X460912Y610300D03*
X444880Y609864D03*
X438187Y604614D03*
X424801D03*
X434840Y612657D03*
X421454Y607292D03*
X428147Y612657D03*
X464732Y609999D03*
X469832Y609749D03*
X464732Y590900D03*
X474998Y604499D03*
X444880Y604614D03*
X431494Y604499D03*
X464758Y607350D03*
X438187Y593659D03*
X511809Y-1751D03*
X485037Y-3700D03*
X481691Y-9901D03*
X497723Y-4100D03*
X495077Y-9901D03*
X491344Y-4100D03*
X488384Y-9901D03*
X511809D03*
X501570Y-7050D03*
X506644Y-7260D03*
X501544Y-4401D03*
X506644Y-4651D03*
X511809Y9114D03*
X495077Y-1751D03*
X501544Y-1801D03*
X506692Y-2000D03*
X488384Y-1801D03*
X481691Y-1751D03*
X485037Y-7851D03*
X491344D03*
X506657Y-9864D03*
X497723Y-7700D03*
X501592Y-9700D03*
X481691Y9114D03*
X494927D03*
X488384D03*
X501544Y9098D03*
X497723Y14814D03*
X506644Y17114D03*
X506657Y27936D03*
X497723Y30100D03*
X491380Y14714D03*
X481691Y27899D03*
X497723Y33700D03*
X495077Y27899D03*
X491344Y33700D03*
X488384Y27899D03*
X511809D03*
X501569Y30750D03*
X506643Y33149D03*
X506604Y9300D03*
X481691Y17157D03*
X485037Y12114D03*
X495077Y17157D03*
X497723Y12114D03*
X488384Y17157D03*
X491430Y12114D03*
X511809Y17157D03*
X501544Y14300D03*
X506644Y14514D03*
X501544Y11700D03*
X506644Y11914D03*
X485037Y14814D03*
X501504Y16900D03*
X485037Y29949D03*
X491344D03*
X501603Y28100D03*
X515155Y-7851D03*
X538355Y9098D03*
X518502Y-1751D03*
X521848Y-7851D03*
X538355Y-1801D03*
X531888Y-1751D03*
X525195Y-1801D03*
X538403Y-9700D03*
X528155Y-7851D03*
X534534Y-7700D03*
X518502Y9114D03*
X531738D03*
X525195D03*
X521848Y-3700D03*
X518502Y-9901D03*
X515155Y-3700D03*
X534534Y-4100D03*
X531888Y-9901D03*
X528155Y-4100D03*
X525195Y-9901D03*
X538381Y-7050D03*
X521848Y14814D03*
Y29949D03*
X528191Y14714D03*
X538315Y16900D03*
X534534Y30100D03*
X518502Y27899D03*
X534534Y33700D03*
X531888Y27899D03*
X528155Y33700D03*
X525195Y27899D03*
X538381Y30750D03*
X538355Y33399D03*
X518502Y17157D03*
X521848Y12114D03*
X515155D03*
X531888Y17157D03*
X534534Y12114D03*
X525195Y17157D03*
X528241Y12114D03*
X538355Y14300D03*
Y11700D03*
X515155Y29949D03*
Y14814D03*
X534534D03*
X528155Y29949D03*
X538415Y28100D03*
X501543Y33399D03*
X506643Y30540D03*
X538355Y-4401D03*
X488384Y35999D03*
X501492Y54700D03*
X497723Y52614D03*
Y67900D03*
X501544Y46898D03*
X511809Y46914D03*
X491344Y67749D03*
X506657Y65736D03*
X501570Y65950D03*
X481691Y36049D03*
Y65699D03*
X495077D03*
X488384D03*
X511809D03*
X501570Y68550D03*
X506644Y68340D03*
X485037Y34100D03*
X481691Y54957D03*
X485037Y49914D03*
X495077Y54957D03*
X497723Y49914D03*
X488384Y54957D03*
X491430Y49914D03*
X511809Y54957D03*
X501543Y52100D03*
X506643Y49714D03*
X501543Y49500D03*
X495077Y36049D03*
X506643Y52314D03*
X506644Y54914D03*
X494927Y46914D03*
X485037Y52614D03*
X481691Y46914D03*
X511809Y36049D03*
X485037Y67749D03*
X488384Y46914D03*
X506603Y35800D03*
X506592Y47000D03*
X501544Y35999D03*
X497723Y71500D03*
X495077Y92757D03*
X497723Y87714D03*
X491344Y71500D03*
X488384Y92757D03*
X491430Y87714D03*
X511809Y92757D03*
X501544Y89900D03*
X506644Y70949D03*
Y87514D03*
X501544Y71199D03*
Y87300D03*
X506644Y90114D03*
X511809Y84714D03*
X501544Y84698D03*
X494927Y84714D03*
X506670Y73550D03*
X481691Y84714D03*
X488384D03*
X501520Y92500D03*
X506620Y84700D03*
X511809Y73849D03*
X488384Y73799D03*
X481691Y73849D03*
X506644Y92714D03*
X491380Y90314D03*
X497723Y90414D03*
X485037D03*
X495077Y73849D03*
X501544Y73799D03*
X485037Y71900D03*
X481691Y92757D03*
X485037Y87714D03*
X518502Y36049D03*
Y46914D03*
X521848Y67749D03*
X531888Y36049D03*
X538355Y35999D03*
X534534Y52614D03*
X531738Y46914D03*
X525195Y35999D03*
X518502Y65699D03*
X531888D03*
X525195D03*
X538381Y68550D03*
X521848Y34100D03*
X518502Y54957D03*
X521848Y49914D03*
X515155Y34100D03*
Y49914D03*
X531888Y54957D03*
X534534Y49914D03*
X525195Y54957D03*
X528241Y49914D03*
X538355Y52100D03*
Y49500D03*
X515155Y67749D03*
Y52614D03*
X521848D03*
X538355Y89900D03*
X534534Y67900D03*
X538381Y65950D03*
X528155Y67749D03*
X538355Y46898D03*
X538304Y54700D03*
X525195Y46914D03*
X538355Y71199D03*
Y87300D03*
X515155Y90414D03*
X534534D03*
X528191Y90314D03*
X521848Y90414D03*
X518502Y73849D03*
Y84714D03*
X531738D03*
X525195D03*
X538355Y84698D03*
X538331Y92500D03*
X531888Y73849D03*
X525195Y73799D03*
X538355D03*
X521848Y71900D03*
X518502Y92757D03*
X521848Y87714D03*
X515155Y71900D03*
Y87714D03*
X534534Y71500D03*
X531888Y92757D03*
X534534Y87714D03*
X528155Y71500D03*
X525195Y92757D03*
X528241Y87714D03*
X494927Y112357D03*
X497723Y106964D03*
X488634Y112357D03*
X491430Y106964D03*
X512024Y112357D03*
X501544Y110514D03*
X506644Y107655D03*
X501570Y107865D03*
X506670Y110264D03*
X512024Y104314D03*
X497723Y109564D03*
X501544Y113114D03*
X506670Y112865D03*
X501570Y105265D03*
X491430Y109564D03*
X506657Y105051D03*
X488634Y104314D03*
X495077D03*
X518317Y112357D03*
X521113Y106964D03*
X514820D03*
X531888Y112357D03*
X534534Y106964D03*
X525134Y112357D03*
X528241Y107314D03*
X538355Y110514D03*
X538381Y107865D03*
X514820Y109564D03*
X521113D03*
X528191Y109914D03*
X534534Y109564D03*
X538355Y113114D03*
X531738Y104314D03*
X525134D03*
X538381Y105265D03*
X518467Y104314D03*
X518352Y210345D03*
X528491Y212296D03*
X494692D03*
X501452Y216196D03*
X504832Y218147D03*
X511592Y214247D03*
X514972Y216196D03*
X518352Y214247D03*
X531871D03*
X514972Y212296D03*
Y208397D03*
X521731Y212296D03*
X525111Y210346D03*
X504832Y214247D03*
X498072D03*
X508212Y216196D03*
X535251Y212296D03*
X480052Y218147D03*
X511592Y206447D03*
Y210346D03*
Y218147D03*
X486812Y214247D03*
Y218147D03*
X498350Y209900D03*
X501452Y212296D03*
X480052Y214247D03*
Y206447D03*
X486812Y210346D03*
X508212Y212296D03*
X518352Y218147D03*
Y206445D03*
X538631Y210346D03*
Y214247D03*
Y206447D03*
X528491Y208397D03*
X525111Y218147D03*
X528491Y216196D03*
X535251Y204496D03*
X525111Y206447D03*
X531871D03*
X521731Y208397D03*
Y216196D03*
X531871Y218147D03*
X528491Y204496D03*
X538631Y202247D03*
X498072Y218147D03*
X494692Y216196D03*
X525111Y214247D03*
X531871Y210346D03*
X535251Y216196D03*
X538631Y218147D03*
X535251Y208397D03*
X483432Y220096D03*
X480052Y222047D03*
X501452Y251296D03*
Y255196D03*
X491312Y280547D03*
X486812Y261047D03*
X483432Y262996D03*
X498072Y280547D03*
X511592Y272747D03*
X504832Y276647D03*
X498072D03*
X491312D03*
X511592D03*
X504832Y272747D03*
X498072Y253247D03*
Y257147D03*
X504832Y280547D03*
X511592D03*
X498072Y272747D03*
X501452Y262996D03*
X498072Y261047D03*
X494692Y259096D03*
X525111Y249347D03*
X528491Y251296D03*
X525111Y241547D03*
X528491Y239596D03*
X531871Y253247D03*
X521731Y262996D03*
X525111Y264947D03*
X528491Y266896D03*
X521731Y278596D03*
X518352Y280547D03*
Y276646D03*
X484552D03*
X504832Y249347D03*
X501452Y270796D03*
X518352Y268847D03*
X538631Y276646D03*
Y245447D03*
X535251Y274696D03*
X494692Y239596D03*
Y231797D03*
X504832Y237647D03*
X508212Y227896D03*
X525111Y233746D03*
X511592Y237647D03*
X538631Y268847D03*
Y264947D03*
X531871Y245447D03*
X501452Y243496D03*
X535251Y262996D03*
X538631Y253247D03*
X531871Y280547D03*
X538631Y241547D03*
X521731Y270796D03*
X504832Y257147D03*
X508212Y251296D03*
X518352Y225947D03*
X531871Y233746D03*
Y225947D03*
X538631Y233746D03*
X531871Y272747D03*
X501452Y227896D03*
X514972Y231797D03*
X525111Y225947D03*
X494692Y220096D03*
X535251D03*
X504832Y222047D03*
X538631Y272747D03*
X494692Y274696D03*
X483432Y227896D03*
X480052Y229847D03*
X511592Y241547D03*
Y249347D03*
X486812Y245447D03*
X494692Y247396D03*
X483432Y251296D03*
X501452Y247396D03*
X480052Y237647D03*
X508212Y239596D03*
X498072Y233746D03*
X486812D03*
Y229847D03*
X494692Y235696D03*
X504832Y229847D03*
X486812Y225947D03*
Y249347D03*
X480052Y245447D03*
Y249347D03*
X498072Y245447D03*
X494692Y223996D03*
X504832Y225947D03*
X511592Y222047D03*
X498072Y249347D03*
Y222047D03*
Y225947D03*
X486812Y222047D03*
Y237647D03*
X480052Y233746D03*
X504832Y241547D03*
X480052D03*
X486812D03*
X494692Y243496D03*
X483432D03*
X504832Y245447D03*
X501452Y223996D03*
X508212Y231797D03*
Y220096D03*
Y223996D03*
X483432Y235696D03*
Y223996D03*
X494692Y251296D03*
X501452Y274696D03*
X508212Y278596D03*
X484552Y268847D03*
X494692Y255196D03*
X486812Y257147D03*
X511592Y268847D03*
X483432Y255196D03*
X480052Y257147D03*
X508212Y274696D03*
X504832Y268847D03*
X508707Y258532D03*
X504832Y253247D03*
X487932Y278596D03*
Y274696D03*
X494692Y278596D03*
X501452Y266896D03*
Y259096D03*
X484552Y280547D03*
X511592Y253247D03*
X508212Y266896D03*
X513857Y260881D03*
X504832Y261047D03*
X501452Y278596D03*
X504832Y264947D03*
X487932Y270796D03*
X498072Y268847D03*
X491312D03*
X487932Y266896D03*
X491312Y264947D03*
X480052D03*
X481172Y270796D03*
X494692Y262996D03*
X483432Y259096D03*
X481172Y274696D03*
Y278596D03*
X508212Y270796D03*
X494692D03*
X480052Y261047D03*
X518352Y229847D03*
X521731Y231797D03*
Y235696D03*
Y247396D03*
Y220096D03*
X538631Y225947D03*
Y222047D03*
Y237647D03*
X528491Y247396D03*
Y243496D03*
X538631Y249347D03*
X535251Y235696D03*
X528491Y227896D03*
Y235696D03*
Y220096D03*
X535251Y247396D03*
Y251296D03*
Y239596D03*
X531871Y222047D03*
X525111Y237647D03*
X514972Y220096D03*
X518352Y233746D03*
Y222047D03*
X531871Y241547D03*
Y249347D03*
X528491Y223996D03*
X531871Y237647D03*
X535251Y223996D03*
X518352Y245447D03*
Y241547D03*
Y237647D03*
X521731Y239596D03*
Y243496D03*
X525111Y245447D03*
X518352Y249347D03*
X514972Y247396D03*
Y227896D03*
Y235696D03*
Y239596D03*
Y223996D03*
X535251Y259096D03*
X531871Y261047D03*
X514972Y255196D03*
Y270796D03*
Y278596D03*
X525111Y253247D03*
X518352D03*
X528491Y274696D03*
X531871Y268847D03*
Y276646D03*
X535251Y266896D03*
X525111Y280547D03*
X521731Y266896D03*
Y259096D03*
Y274696D03*
X538631Y257147D03*
X521731Y255196D03*
X514972Y274696D03*
X518352Y257147D03*
X528491Y270796D03*
Y278596D03*
X535251Y255196D03*
X531871Y264947D03*
X518352D03*
X531871Y257147D03*
X528491Y255196D03*
X525111Y268847D03*
X528491Y262996D03*
X525111Y276646D03*
X484552Y272747D03*
X525111D03*
X518352D03*
X514972Y251296D03*
X510401Y260511D03*
X498072Y264947D03*
X518352Y261047D03*
X498072Y229847D03*
X501452Y239596D03*
Y231797D03*
X511592Y233746D03*
X525111Y229847D03*
X521731Y223996D03*
X525111Y222047D03*
X531871Y229847D03*
X535251Y227896D03*
Y231797D03*
X498072Y241547D03*
Y237647D03*
X501452Y235696D03*
X508212D03*
X511592Y225947D03*
Y229847D03*
X535251Y270796D03*
X538631Y261047D03*
X504832Y233746D03*
X501452Y220096D03*
X525111Y257147D03*
Y261047D03*
X521731Y251296D03*
X511592Y245447D03*
X514972Y243496D03*
X508212Y247396D03*
X521731Y227896D03*
X538631Y229847D03*
Y280547D03*
X535251Y243496D03*
X494692Y227896D03*
X528491Y231797D03*
X535251Y278596D03*
X491312Y288347D03*
Y284447D03*
X498072D03*
Y288347D03*
X501452Y286396D03*
X494692Y290296D03*
X498072Y292247D03*
X504832D03*
X508212Y282496D03*
X504832Y288347D03*
Y284447D03*
X494692Y282496D03*
X508212Y286396D03*
X511592Y292245D03*
X484552Y319546D03*
X481172Y333196D03*
X484552Y331247D03*
X514972Y282496D03*
X521731D03*
X518352Y284447D03*
X538631Y307847D03*
Y303947D03*
Y300047D03*
X535251Y298096D03*
Y305896D03*
X538631Y296147D03*
X531871D03*
X535251Y317596D03*
X525111Y315647D03*
X531871D03*
X535251Y313696D03*
X538631Y315647D03*
X528491Y282496D03*
X535251Y286396D03*
Y282496D03*
X504832Y300045D03*
Y303947D03*
Y311747D03*
X508212Y301996D03*
Y305896D03*
X494692Y294196D03*
X501452Y290296D03*
Y282496D03*
X491312Y292245D03*
Y300047D03*
X508212Y290296D03*
Y294196D03*
X511592Y307847D03*
Y284447D03*
X481172Y309797D03*
X494692D03*
X481172Y301996D03*
X487932Y309797D03*
X498072Y303947D03*
X487932Y286396D03*
X481172Y298096D03*
X487932Y282496D03*
X481172Y305896D03*
X487932Y290296D03*
X484552Y288347D03*
Y296147D03*
X481172Y294196D03*
X508212Y309797D03*
X511592Y300047D03*
Y288347D03*
X494692Y305896D03*
X491312Y311747D03*
X501452Y301996D03*
X491312Y307847D03*
X498072Y311747D03*
X511592Y296147D03*
X501452Y294196D03*
X498072Y296147D03*
X504832D03*
X508212Y298096D03*
X498072Y300047D03*
X484552Y307847D03*
Y300047D03*
Y292245D03*
X494692Y286396D03*
X501452Y298096D03*
X481172Y290296D03*
X508212Y329296D03*
X487932Y317596D03*
X504832Y319547D03*
X484552Y323446D03*
X508212Y317596D03*
Y325396D03*
X491312Y339047D03*
X494692Y337096D03*
X511592Y327347D03*
Y339047D03*
Y331247D03*
Y335147D03*
Y315647D03*
Y323446D03*
X508212Y340996D03*
X498072Y339047D03*
X504832Y327347D03*
X508212Y321496D03*
X481172Y329296D03*
X491312Y323446D03*
X501452Y313696D03*
X508212D03*
X481172D03*
X494692Y340996D03*
Y313696D03*
X501452Y329296D03*
X487932Y340996D03*
Y329296D03*
X494692D03*
X491312Y327347D03*
X498072Y331247D03*
X484552Y335147D03*
X481172Y337096D03*
X501452Y321496D03*
X481172Y340996D03*
X484552Y339047D03*
X487932Y337096D03*
Y333196D03*
X491312Y335147D03*
X494692Y333196D03*
X498072Y335147D03*
X491312Y319547D03*
X494692Y321496D03*
X501452Y317596D03*
X498072Y315647D03*
Y323446D03*
X494692Y325396D03*
X501452D03*
X494692Y317596D03*
X487932Y321496D03*
X484552Y327347D03*
X487932Y325396D03*
X504832Y331247D03*
X508212Y337096D03*
Y333196D03*
X504832Y335147D03*
X501452Y333196D03*
X504832Y339047D03*
X501452Y340996D03*
X504832Y315647D03*
X498072Y319547D03*
X504832Y323446D03*
X498072Y327347D03*
X491312Y331247D03*
X511592Y319547D03*
X538631Y311747D03*
X535251Y290296D03*
X514972Y305896D03*
Y309797D03*
X528491Y301996D03*
Y309797D03*
X525111Y311747D03*
Y307847D03*
Y303947D03*
X521731Y305896D03*
Y309797D03*
X518352Y307847D03*
X514972Y298096D03*
X518352Y292245D03*
Y288347D03*
X521731Y286396D03*
Y290296D03*
Y298096D03*
X525111Y292245D03*
Y296147D03*
X528491Y290296D03*
X525111Y288347D03*
X521731Y294196D03*
X518352Y300047D03*
Y296147D03*
X514972Y301996D03*
Y290296D03*
Y286396D03*
Y294196D03*
X525111Y284447D03*
X531871Y288347D03*
Y292245D03*
X528491Y294196D03*
X525111Y300047D03*
X531871D03*
X521731Y301996D03*
X528491Y286396D03*
Y298096D03*
X535251Y294196D03*
X538631Y292245D03*
Y288347D03*
Y284447D03*
X531871Y303947D03*
X535251Y301996D03*
X531871Y311747D03*
Y307847D03*
X535251Y309797D03*
X514972Y333196D03*
Y321496D03*
Y317596D03*
Y329296D03*
Y325396D03*
Y337096D03*
X518352Y319547D03*
X514972Y313696D03*
X528491D03*
X521731D03*
X518352Y323446D03*
Y315647D03*
X521731Y317596D03*
Y325396D03*
X518352Y327347D03*
Y339047D03*
X531871Y335147D03*
X525111D03*
X528491Y337096D03*
X531871Y327347D03*
X535251Y329296D03*
X538631Y335147D03*
Y339047D03*
X528491Y317596D03*
X531871Y319547D03*
X535251Y321496D03*
X538631Y319547D03*
X514972Y340996D03*
X518352Y331247D03*
X521731Y321496D03*
X525111Y339047D03*
X535251Y333196D03*
Y325396D03*
X484552Y315647D03*
X481172Y282496D03*
X518352Y303947D03*
X531871Y284447D03*
X484552D03*
X535251Y376096D03*
X518352Y401447D03*
X504832Y385847D03*
Y393647D03*
X508212Y376096D03*
X498072Y370247D03*
X504832D03*
X501452Y372197D03*
X504832Y342947D03*
X491312Y370247D03*
X498072Y366347D03*
X494692Y372197D03*
X504832Y366347D03*
X501452Y368296D03*
X487932D03*
X484552Y362447D03*
X498072D03*
X491312D03*
X494692Y360496D03*
X487932D03*
X501452Y344896D03*
X504832Y354647D03*
X494692Y344896D03*
Y348796D03*
X491312Y350747D03*
X508212Y344896D03*
Y348796D03*
X511592Y346847D03*
Y350747D03*
Y342947D03*
X504832Y362447D03*
X494692Y368296D03*
Y352696D03*
X508212Y356596D03*
X504832Y350747D03*
X491312Y366347D03*
X487932Y372197D03*
X484552Y370247D03*
X481172Y372197D03*
X484552Y366347D03*
X487932Y364396D03*
X494692D03*
X501452D03*
X491312Y358547D03*
X498072Y350747D03*
Y346847D03*
X501452Y360496D03*
X498072Y342947D03*
X487932Y348796D03*
X481172Y356596D03*
X484552Y358547D03*
Y350747D03*
Y354647D03*
X487932Y352696D03*
Y344896D03*
X491312Y346847D03*
X494692Y356596D03*
X498072Y358547D03*
Y354647D03*
X481172Y344896D03*
Y360496D03*
X484552Y346847D03*
X508212Y352696D03*
Y360496D03*
X504832Y346847D03*
Y358547D03*
X501452Y356596D03*
Y348796D03*
Y352696D03*
X511592Y370247D03*
X481172Y352696D03*
X484552Y393647D03*
X481172Y391696D03*
X484552Y385847D03*
X498072Y393647D03*
X494692Y391696D03*
X491312Y385847D03*
X498072D03*
X508212Y387796D03*
X501452Y391696D03*
Y395597D03*
X491312Y389747D03*
X504832Y381947D03*
Y378047D03*
X501452Y379996D03*
X481172Y395596D03*
X511592Y378047D03*
Y397546D03*
X491312Y378047D03*
X484552D03*
X481172Y379996D03*
X487932Y376096D03*
X491312Y381947D03*
X511592Y374146D03*
X501452Y383896D03*
X498072Y389747D03*
X494692Y376096D03*
X508212Y379996D03*
X491312Y374146D03*
X498072Y397546D03*
X487932Y403396D03*
Y399496D03*
X491312Y397546D03*
X487932Y395597D03*
X521731Y368296D03*
X518352Y366347D03*
X514972Y372197D03*
Y356596D03*
X521731Y360496D03*
Y356596D03*
Y348796D03*
X518352Y342947D03*
Y362447D03*
X521731Y372197D03*
X518352Y370247D03*
X525111Y354647D03*
X531871Y346847D03*
X535251Y356596D03*
X538631Y366347D03*
X528491Y364396D03*
X525111Y342947D03*
X514972Y348796D03*
Y344896D03*
Y352696D03*
X518352Y358547D03*
X521731Y344896D03*
X538631Y370247D03*
X525111Y350747D03*
Y370247D03*
X531871D03*
X525111Y362447D03*
X528491Y360496D03*
Y356596D03*
X525111Y366347D03*
X528491Y368296D03*
X521731Y364396D03*
X525111Y358547D03*
X531871Y354647D03*
X528491Y372197D03*
X525111Y378047D03*
Y374146D03*
X521731Y376096D03*
X514972Y403396D03*
Y379996D03*
X531871Y374146D03*
X521731Y399496D03*
X518352Y397546D03*
Y389747D03*
X535251Y383896D03*
X525111Y381947D03*
X538631Y393647D03*
Y378047D03*
X528491Y403396D03*
X531871Y401447D03*
Y389747D03*
X525111Y393647D03*
X514972Y399496D03*
X538631Y381947D03*
X531871Y385847D03*
X528491Y391696D03*
X525111Y397546D03*
X481172Y348796D03*
X535251Y395597D03*
Y387796D03*
Y391696D03*
Y352696D03*
X531871Y350747D03*
Y397546D03*
X528491Y399496D03*
X521731Y403396D03*
X538631Y385847D03*
Y389747D03*
X531871Y393647D03*
X535251Y399496D03*
X528491Y395597D03*
X525111Y401447D03*
X518352Y374146D03*
X521731Y379996D03*
X514972Y383896D03*
X511592Y381947D03*
X508212Y391696D03*
X504832Y389747D03*
X508212Y395597D03*
X518352Y378047D03*
Y381947D03*
Y385847D03*
X511592D03*
X501452Y387796D03*
X511592Y393647D03*
X504832Y397546D03*
X481172Y376096D03*
Y368296D03*
X487932Y387796D03*
Y391696D03*
Y379996D03*
X491312Y401447D03*
X481172Y387796D03*
X494692Y395597D03*
X484552Y381947D03*
X518352Y405347D03*
X484552D03*
X538750Y406200D03*
X531871Y405347D03*
X525111D03*
X511712Y495800D03*
X488384Y495887D03*
X494777D03*
X491380Y493744D03*
X506644Y490867D03*
X501560D03*
X497723Y493494D03*
X506620Y510100D03*
X506644Y518114D03*
X501544Y510098D03*
X485037Y515814D03*
X481691Y510114D03*
X491380Y515714D03*
X511809Y510114D03*
X497723Y515814D03*
X494927Y510114D03*
X488384D03*
X501520Y517900D03*
X506644Y498867D03*
X501560D03*
X514755Y491044D03*
X521048Y491144D03*
X538370Y490609D03*
X528241Y490944D03*
X534534Y490794D03*
X515155Y515814D03*
X530792Y495787D03*
X524595D03*
X517892Y495800D03*
X534534Y515814D03*
X528191Y515714D03*
X531738Y510114D03*
X525195D03*
X538355Y510098D03*
X538331Y517900D03*
X521848Y515814D03*
X518502Y510114D03*
X538370Y498609D03*
Y495909D03*
X538355Y515300D03*
X501544Y512700D03*
X506644Y512914D03*
X501544Y515300D03*
X528241Y513114D03*
X525195Y518157D03*
X534534Y513114D03*
X531888Y518157D03*
X515155Y513114D03*
X511809Y518157D03*
X491430Y513114D03*
X488384Y518157D03*
X521848Y513114D03*
X518502Y518157D03*
X497723Y513114D03*
X495077Y518157D03*
X485037Y513114D03*
X481691Y518157D03*
X506644Y496167D03*
X538370Y493209D03*
X501560Y493467D03*
X506644Y493567D03*
X501560Y496167D03*
X528191Y493544D03*
X524595Y498387D03*
X534534Y493394D03*
X530792Y498387D03*
X514755Y493744D03*
X511809Y498487D03*
X491430Y491144D03*
X488384Y498487D03*
X521048Y493844D03*
X517902Y498487D03*
X497723Y490894D03*
X494777Y498487D03*
X506644Y515514D03*
X538355Y512700D03*
X506670Y536750D03*
X501570Y529150D03*
X506657Y528936D03*
X501544Y536999D03*
X511809Y547914D03*
Y537049D03*
X491380Y553514D03*
X497723Y553614D03*
X485037D03*
X506620Y547900D03*
X501544Y547898D03*
X481691Y547914D03*
X494927D03*
X488384D03*
X481691Y537049D03*
X491344Y530949D03*
X488384Y536999D03*
X495077Y537049D03*
X497723Y531100D03*
X485037Y530949D03*
Y568749D03*
X481691Y574849D03*
Y585714D03*
X501544Y585698D03*
Y574799D03*
X506657Y566736D03*
X501570Y566950D03*
X506670Y574550D03*
X506620Y585700D03*
X488384Y585714D03*
X511809D03*
Y574849D03*
X494927Y585714D03*
X491344Y568749D03*
X501520Y555700D03*
X506644Y555914D03*
X497723Y568900D03*
X488384Y574799D03*
X495077Y574849D03*
X515155Y553614D03*
Y530949D03*
X534534Y531100D03*
X531888Y537049D03*
X528155Y530949D03*
X525195Y536999D03*
X538355D03*
X538381Y529150D03*
X525195Y547914D03*
X531738D03*
X538355Y547898D03*
X534534Y553614D03*
X528191Y553514D03*
X518502Y547914D03*
X521848Y553614D03*
X518502Y537049D03*
X521848Y530949D03*
X515155Y568749D03*
X538331Y555700D03*
X518502Y585714D03*
Y574849D03*
X521848Y568749D03*
X538355Y585698D03*
Y574799D03*
X538381Y566950D03*
X531738Y585714D03*
X525195D03*
X534534Y568900D03*
X525195Y574799D03*
X528155Y568749D03*
X531888Y574849D03*
X538355Y553100D03*
X538381Y531750D03*
X538355Y534399D03*
X501544D03*
X506644Y534149D03*
X501570Y531750D03*
X525195Y528899D03*
X528155Y534700D03*
X531888Y528899D03*
X534534Y534700D03*
X511809Y528899D03*
X515155Y535100D03*
X488384Y528899D03*
X491344Y534700D03*
X518502Y528899D03*
X521848Y535100D03*
X495077Y528899D03*
X497723Y534700D03*
X481691Y528899D03*
X485037Y535100D03*
X506644Y553314D03*
X538355Y550500D03*
X501544D03*
X506644Y550714D03*
X501544Y553100D03*
X528241Y550914D03*
X525195Y555957D03*
X534534Y550914D03*
X531888Y555957D03*
X515155Y550914D03*
X511809Y555957D03*
X491430Y550914D03*
X488384Y555957D03*
X521848Y550914D03*
X518502Y555957D03*
X497723Y550914D03*
X495077Y555957D03*
X485037Y550914D03*
X481691Y555957D03*
X497723Y588714D03*
X485037D03*
X506644Y569340D03*
X538355Y572199D03*
X501544D03*
X525195Y566699D03*
X528155Y572500D03*
X531888Y566699D03*
X534534Y572500D03*
X511809Y566699D03*
X515155Y572900D03*
X488384Y566699D03*
X491344Y572500D03*
X518502Y566699D03*
X521848Y572900D03*
X495077Y566699D03*
X497723Y572500D03*
X481691Y566699D03*
X485037Y572900D03*
X538355Y588300D03*
X501544D03*
X506644Y588514D03*
X528241Y588714D03*
X534534D03*
X515155D03*
X491430D03*
X521848D03*
X538381Y569550D03*
X506644Y531540D03*
Y571949D03*
X501570Y569550D03*
X525195Y612599D03*
X518502Y612649D03*
X538355Y612599D03*
X531888Y612649D03*
X501544Y612599D03*
X495077Y612649D03*
X488384Y612599D03*
X511809Y612649D03*
X497723Y591414D03*
X486250Y591020D03*
X491380Y591314D03*
X501520Y593500D03*
X506644Y593714D03*
X501570Y604750D03*
X506657Y604536D03*
X491344Y606549D03*
X497723Y606700D03*
X485037Y607230D03*
X506670Y612350D03*
X480950Y612430D03*
X515155Y606549D03*
Y591414D03*
X521848D03*
Y606549D03*
X534534Y591414D03*
X528191Y591314D03*
X538331Y593500D03*
X538381Y604750D03*
X534534Y606700D03*
X528155Y606549D03*
X538355Y590900D03*
X521848Y610700D03*
X495077Y604499D03*
Y593757D03*
X498092Y611200D03*
X481691Y604499D03*
Y593757D03*
X485037Y610700D03*
X506644Y591114D03*
Y607140D03*
X538355Y609999D03*
X501544D03*
Y590900D03*
X525195Y604499D03*
Y593757D03*
X531888Y604499D03*
X534534Y610300D03*
X531888Y593757D03*
X511809Y604499D03*
X515155Y610700D03*
X511809Y593757D03*
X488384Y604499D03*
Y593757D03*
X491724Y611668D03*
X518502Y604499D03*
Y593757D03*
X538381Y607350D03*
X506644Y609749D03*
X501570Y607350D03*
X528155Y610300D03*
X562006Y9114D03*
X568549D03*
X555313D03*
X548620D03*
X571345Y-7700D03*
X551966Y-7851D03*
X564966D03*
X558659D03*
X562006Y-1801D03*
X555313Y-1751D03*
X568699D03*
X548620D03*
X543503Y-2000D03*
X543468Y-9864D03*
X558659Y-3700D03*
X555313Y-9901D03*
X551966Y-3700D03*
X548620Y-9901D03*
X571345Y-4100D03*
X568699Y-9901D03*
X564966Y-4100D03*
X562006Y-9901D03*
X543455Y-7260D03*
Y-4651D03*
Y17114D03*
X564992Y14714D03*
X555313Y27899D03*
X548620D03*
X571345Y33700D03*
X568699Y27899D03*
X564966Y33700D03*
X562006Y27899D03*
X543455Y33149D03*
Y30540D03*
X555313Y17157D03*
X558659Y12114D03*
X548620Y17157D03*
X551966Y12114D03*
X568699Y17157D03*
X571345Y12114D03*
X561868Y17019D03*
X565052Y12114D03*
X543455Y14514D03*
Y11914D03*
X543415Y9300D03*
X558659Y14814D03*
Y29949D03*
X551966Y14814D03*
Y29949D03*
X564966D03*
X571345Y14814D03*
Y30100D03*
X543468Y27936D03*
X575166Y9098D03*
X595470Y-3700D03*
X592124Y-9901D03*
X588777Y-3700D03*
X585431Y-9901D03*
X575192Y-7050D03*
X580266Y-7260D03*
Y-4651D03*
X602163Y-1743D03*
Y9157D03*
Y16999D03*
X592124Y27899D03*
X585431D03*
X575192Y30750D03*
X575166Y33399D03*
X580266Y33149D03*
X592124Y17157D03*
X595470Y12114D03*
X585431Y17157D03*
X588777Y12114D03*
X575166Y14300D03*
X575214Y-9700D03*
X575166Y-1801D03*
X580279Y-9864D03*
X580314Y-2000D03*
X588777Y-7851D03*
X598817Y-9901D03*
X595470Y-7851D03*
X592124Y-1751D03*
X598817D03*
X585431D03*
X602163Y-9901D03*
X598817Y9157D03*
X592124Y9114D03*
X585431D03*
X580266Y14514D03*
X575166Y11700D03*
X580266Y11914D03*
X598817Y17057D03*
X602163Y27899D03*
X575182Y16900D03*
X575192Y28100D03*
X580192Y9300D03*
X588777Y29949D03*
X580279Y27936D03*
X595470Y29949D03*
Y14814D03*
X598817Y27899D03*
X588777Y14814D03*
X580266Y17114D03*
X575166Y-4401D03*
X580266Y30540D03*
X562006Y46914D03*
X555313Y65699D03*
X548620D03*
X568699D03*
X562006D03*
X543455Y68340D03*
X558659Y34100D03*
X555313Y54957D03*
X558659Y49914D03*
X551966Y34100D03*
X548620Y54957D03*
X551966Y49914D03*
X568699Y54957D03*
X571345Y49914D03*
X562006Y54957D03*
X565052Y49914D03*
X543455Y49714D03*
Y52314D03*
X551966Y52614D03*
X565352Y52864D03*
X548620Y46914D03*
Y36049D03*
X558659Y52614D03*
X568699Y36049D03*
X555313D03*
X562006Y35999D03*
X551966Y67749D03*
X564966D03*
X571345Y52614D03*
Y67900D03*
X558659Y67749D03*
X568549Y46914D03*
X555313D03*
X565266Y87374D03*
X543455Y70949D03*
X543468Y65736D03*
X543404Y47000D03*
X543415Y35800D03*
X543455Y54914D03*
Y87514D03*
Y90114D03*
Y92714D03*
X548620Y84714D03*
X568549D03*
X555313D03*
X562006D03*
X543481Y73550D03*
X543431Y84700D03*
X548620Y73849D03*
X568699D03*
X562006Y73799D03*
X555313Y73849D03*
X558659Y90414D03*
X551966D03*
X571345D03*
X558659Y71900D03*
X555313Y92757D03*
X558659Y87714D03*
X551966Y71900D03*
X548620Y92757D03*
X551966Y87714D03*
X571345Y71500D03*
X568699Y92757D03*
X571345Y87714D03*
X564966Y71500D03*
X562006Y92757D03*
X592124Y65699D03*
X585431D03*
X575192Y68550D03*
X580266Y68340D03*
X592124Y54957D03*
X595470Y34100D03*
Y49914D03*
X585431Y54957D03*
X588777Y34100D03*
Y49914D03*
X575166Y52100D03*
X580266Y52314D03*
X575166Y49500D03*
X580266Y49714D03*
X598817Y54857D03*
X602163Y46957D03*
Y54799D03*
Y36057D03*
X575166Y46898D03*
Y35999D03*
X575192Y65950D03*
X585431Y46914D03*
X595470Y52614D03*
X588777D03*
X585431Y36049D03*
X592124D03*
X598817D03*
Y46957D03*
X592124Y46914D03*
X598817Y65699D03*
X595470Y67749D03*
X588777D03*
X580266Y54914D03*
X580192Y35750D03*
X580279Y65736D03*
X602163Y65699D03*
X592124Y84714D03*
X585431D03*
X598817Y84757D03*
X580242Y84700D03*
X580266Y92714D03*
X588777Y90414D03*
X602163Y92599D03*
X595470Y71900D03*
X592124Y92757D03*
X595470Y87714D03*
X588777Y71900D03*
X585431Y92757D03*
X588777Y87714D03*
X575166Y89900D03*
X580266Y70949D03*
Y87514D03*
X575166Y71199D03*
Y87300D03*
X580266Y90114D03*
X598817Y92657D03*
X602163Y84757D03*
Y73857D03*
X575166Y73799D03*
X575142Y92500D03*
X575166Y84698D03*
X595470Y90414D03*
X585431Y73849D03*
X592124D03*
X598817D03*
X580292Y73550D03*
X555313Y112357D03*
X558659Y107314D03*
X548620Y112357D03*
X551966Y107314D03*
X543455Y107655D03*
X543481Y110264D03*
X548620Y104314D03*
X555313D03*
X558659Y110014D03*
X551966D03*
X543481Y112865D03*
X543468Y105051D03*
X602100Y109600D03*
X545391Y214247D03*
Y218147D03*
X548771Y216196D03*
X542011Y212296D03*
X555531Y216196D03*
X557000Y206800D03*
X548771Y212296D03*
X552151Y214247D03*
X547800Y201400D03*
X545391Y210346D03*
X558911Y218147D03*
X542011Y208396D03*
X563900Y213500D03*
X560739Y207625D03*
X552151Y218147D03*
X590500Y215800D03*
Y213000D03*
X599773Y199596D03*
X600286Y202921D03*
X577375Y204125D03*
X542011Y216196D03*
Y231797D03*
X548771D03*
X552151Y280547D03*
X548771Y274696D03*
Y220096D03*
X555531D03*
Y227896D03*
X542011Y278596D03*
Y262996D03*
X555531Y270796D03*
X552151Y264947D03*
X542011Y259096D03*
X545391Y257147D03*
Y249347D03*
X548771Y223996D03*
X542011Y243496D03*
X552151Y222047D03*
X562616Y223996D03*
X542011Y251296D03*
X545391Y245447D03*
X555531Y243496D03*
Y259096D03*
X552151Y253247D03*
X548771Y259096D03*
X562640Y231735D03*
X542011Y220096D03*
X552151Y225947D03*
X558911Y222047D03*
X552151Y233746D03*
X548771Y235696D03*
X558911Y229847D03*
X552151D03*
X562591Y220096D03*
X564084Y235685D03*
X545391Y225947D03*
Y222047D03*
Y233746D03*
X542011Y239596D03*
Y247396D03*
X552151Y241547D03*
X548771Y239596D03*
X552151Y249347D03*
X570400Y243500D03*
X555531Y231797D03*
X548771Y227896D03*
X552151Y245447D03*
X548771Y251296D03*
X542011Y223996D03*
X545391Y237647D03*
X555531Y247396D03*
X562591Y251296D03*
X548771Y243496D03*
X562591D03*
X572930Y232750D03*
Y228130D03*
X552151Y257147D03*
X562591Y255196D03*
X548771D03*
X573200Y262600D03*
X573100Y258600D03*
X548771Y266896D03*
X558911Y264947D03*
X563800Y275900D03*
X559211Y280547D03*
X548771Y278596D03*
X558911Y272747D03*
X555531Y274696D03*
X564500Y264800D03*
Y268800D03*
X552151Y261047D03*
X545391Y272747D03*
Y280547D03*
Y264947D03*
Y268847D03*
X542011Y274696D03*
X548771Y270796D03*
Y262996D03*
X545391Y276646D03*
X542011Y270796D03*
X600400Y226800D03*
X580360Y234590D03*
Y230060D03*
X581102Y220006D03*
X542011Y227896D03*
X545391Y229847D03*
X558911Y253247D03*
X548771Y247396D03*
X545391Y241547D03*
X562630Y227896D03*
X555531Y223996D03*
X542011Y235696D03*
X552151Y272747D03*
X566926Y268055D03*
X555531Y262996D03*
X558911Y225947D03*
X575600Y261800D03*
X555531Y251296D03*
X565124Y243496D03*
X558911Y241547D03*
X577849Y231119D03*
X545391Y261047D03*
X555531Y255196D03*
X545391Y253247D03*
X558911Y268847D03*
X570404Y229015D03*
X577832Y233729D03*
X558911Y249347D03*
X570528Y231543D03*
X567868Y243482D03*
X566926Y265555D03*
X552151Y276646D03*
X555531Y266896D03*
X558911Y257147D03*
X555531Y278596D03*
X552151Y268847D03*
X542011Y255196D03*
Y266896D03*
X575600Y259300D03*
X542011Y309797D03*
X545391Y311747D03*
X542011Y305896D03*
Y301996D03*
X552151Y311747D03*
X542011Y313696D03*
X548771Y321496D03*
X545391Y323446D03*
X552151Y319547D03*
Y315647D03*
X559211Y331103D03*
X555531Y329296D03*
X559211Y323446D03*
X555531Y321496D03*
X548771Y317596D03*
X555831Y313696D03*
X559211Y327347D03*
X552151D03*
X555531Y325396D03*
X555831Y317446D03*
X552151Y292245D03*
X559211Y284447D03*
X542011Y290296D03*
X560884D03*
X542011Y282496D03*
X545391Y307847D03*
X555831Y309797D03*
Y305896D03*
X548771Y309797D03*
X555831Y298096D03*
X552151Y284447D03*
X548771Y286396D03*
X552151Y288347D03*
Y296147D03*
X558145Y286727D03*
X545391Y296147D03*
Y288347D03*
Y292245D03*
Y300047D03*
X542011Y294196D03*
Y298096D03*
X545391Y303947D03*
X548771Y282496D03*
Y290296D03*
Y294196D03*
Y337096D03*
Y313696D03*
X561971Y317320D03*
X548771Y325396D03*
X558911Y335147D03*
X555531Y333196D03*
X562591D03*
X548771Y340996D03*
X561966Y325502D03*
X559211Y319547D03*
X552151Y323446D03*
X545391Y319547D03*
X542011Y321496D03*
X545391Y335147D03*
Y331247D03*
Y315647D03*
X548771Y329296D03*
X560884Y286396D03*
X545391Y284447D03*
X555531Y282496D03*
X555831Y294196D03*
X542011Y286396D03*
X552151Y366347D03*
Y370247D03*
X563500Y360500D03*
X555531Y372197D03*
X548771Y364396D03*
X552151Y393647D03*
X559212Y389747D03*
X548990Y403670D03*
X555750Y399770D03*
X552151Y350747D03*
X558911Y342947D03*
X562591Y348796D03*
X559212Y370247D03*
X548771Y368296D03*
X562591Y352696D03*
Y344896D03*
X563200Y356596D03*
X545391Y354647D03*
Y346847D03*
X542011Y368296D03*
X545391Y366347D03*
Y358547D03*
X542011Y360496D03*
Y348796D03*
Y364396D03*
Y372197D03*
Y352696D03*
X545391Y342947D03*
X548771Y372196D03*
X545391Y362447D03*
Y378047D03*
X552151Y374146D03*
X548771Y376096D03*
X559212Y374146D03*
X555531Y387797D03*
X559212Y381947D03*
Y393647D03*
X552151Y378047D03*
X545391Y397546D03*
Y385847D03*
X542011Y376096D03*
X559212Y385847D03*
X542011Y383896D03*
X545391Y374146D03*
X548771Y360496D03*
Y356596D03*
X542011Y379996D03*
X548771Y383896D03*
X545391Y370247D03*
X552151Y358547D03*
X548771Y352696D03*
X545391Y381947D03*
X548771Y379996D03*
X573867Y459903D03*
X575614Y461694D03*
X584076Y443828D03*
X588285Y448306D03*
X586136Y446335D03*
X592216Y445152D03*
X595070Y447970D03*
X558659Y493444D03*
X551366Y490744D03*
X543455Y490909D03*
X555313Y510114D03*
X548492Y495800D03*
X554792Y495887D03*
X543431Y510100D03*
X543455Y518114D03*
X551966Y515814D03*
X548620Y510114D03*
X543455Y498909D03*
X568549Y510114D03*
X562006D03*
X571345Y515814D03*
X558659D03*
X582912Y468948D03*
X581032Y467202D03*
X575166Y510098D03*
X575142Y517900D03*
X580266Y518114D03*
X580242Y510100D03*
X598817Y510157D03*
X595470Y515814D03*
X588777D03*
X602163Y517999D03*
X592124Y510114D03*
X585431D03*
X598817Y518057D03*
X602163Y510157D03*
X562006Y518157D03*
X595470Y513114D03*
X592124Y518157D03*
X571345Y513114D03*
X568699Y518157D03*
X551966Y513114D03*
X548620Y518157D03*
X558659Y513114D03*
X555313Y518157D03*
X543455Y496209D03*
Y493509D03*
X551366Y493344D03*
X548492Y498400D03*
X558659Y496144D03*
X554792Y498487D03*
X580266Y515514D03*
X543455D03*
X575166Y512700D03*
X580266Y512914D03*
X543455D03*
X575166Y515300D03*
X588777Y513114D03*
X585431Y518157D03*
X565266Y512774D03*
X543468Y528936D03*
X543481Y536750D03*
X543431Y547900D03*
X548620Y547914D03*
X551966Y553614D03*
X548620Y537049D03*
X551966Y530949D03*
X558659D03*
X555313Y537049D03*
X562006Y536999D03*
X564966Y530949D03*
X568699Y537049D03*
X571345Y553614D03*
Y531100D03*
X558659Y553614D03*
X555313Y547914D03*
X568549D03*
X562006D03*
X543455Y555914D03*
X571345Y568900D03*
X564966Y568749D03*
X562006Y574799D03*
X555313Y585714D03*
Y574849D03*
X558659Y568749D03*
X568549Y585714D03*
X562006D03*
X568699Y574849D03*
X551966Y568749D03*
X548620Y574849D03*
Y585714D03*
X543481Y574550D03*
X543431Y585700D03*
X543468Y566736D03*
X575166Y547898D03*
X575192Y529150D03*
X575166Y536999D03*
X598817Y547957D03*
X592124Y547914D03*
X595470Y530949D03*
X580242Y547900D03*
X580279Y528936D03*
X580292Y536750D03*
X592124Y537049D03*
X588777Y530949D03*
X598817Y528899D03*
Y537049D03*
X602163Y528899D03*
X585431Y547914D03*
Y537049D03*
X588777Y553614D03*
X595470D03*
X602163Y547957D03*
Y537057D03*
X580279Y566736D03*
X585431Y574849D03*
Y585714D03*
X598817Y585757D03*
Y574849D03*
Y566699D03*
X592124Y585714D03*
X595470Y568749D03*
X588777D03*
X592124Y574849D03*
X602163Y566699D03*
X598817Y555857D03*
X602163Y555799D03*
Y574857D03*
Y585757D03*
X575142Y555700D03*
X575192Y566950D03*
X575166Y585698D03*
Y574799D03*
X580266Y555914D03*
X580292Y574550D03*
X580242Y585700D03*
X562006Y528899D03*
X564966Y534700D03*
X592124Y528899D03*
X595470Y535100D03*
X568699Y528899D03*
X571345Y534700D03*
X548620Y528899D03*
X551966Y535100D03*
X555313Y528899D03*
X558659Y535100D03*
X580266Y553314D03*
X543455D03*
X575166Y550500D03*
X580266Y550714D03*
X543455D03*
X575166Y553100D03*
X588777Y550914D03*
X585431Y555957D03*
X565266Y550574D03*
X562006Y555957D03*
X595470Y550914D03*
X592124Y555957D03*
X571345Y550914D03*
X568699Y555957D03*
X551966Y550914D03*
X548620Y555957D03*
X558659Y550914D03*
X555313Y555957D03*
X580266Y531540D03*
X543455D03*
X575166Y534399D03*
X543455Y534149D03*
X575192Y531750D03*
X585431Y528899D03*
X588777Y535100D03*
X558659Y572900D03*
X575166Y588300D03*
X580266Y588514D03*
X543455D03*
X588777Y588714D03*
X565052D03*
X595470D03*
X571345D03*
X551966D03*
X558659D03*
X580266Y569340D03*
X575166Y572199D03*
X580266Y571949D03*
X543455D03*
X585431Y566699D03*
X588777Y572900D03*
X562006Y566699D03*
X564966Y572500D03*
X592124Y566699D03*
X595470Y572900D03*
X568699Y566699D03*
X571345Y572500D03*
X548620Y566699D03*
X551966Y572900D03*
X555313Y566699D03*
X580266Y534149D03*
X543455Y569340D03*
X575192Y569550D03*
X575166Y612599D03*
X585431Y612649D03*
X592124D03*
X598817D03*
X602163Y612657D03*
X555313Y612649D03*
X562006Y612599D03*
X568699Y612649D03*
X548620D03*
X571345Y591414D03*
X558659D03*
X571345Y606700D03*
X558659Y606549D03*
X564966D03*
X551966D03*
Y591414D03*
X543455Y593714D03*
X543468Y604536D03*
X543481Y612350D03*
X580292D03*
X580266Y593714D03*
X595470Y591414D03*
X588777D03*
X598817Y604499D03*
X595470Y606549D03*
X588777D03*
X598817Y593657D03*
X575192Y604750D03*
X575142Y593500D03*
X602163Y593599D03*
Y604499D03*
X580279Y604536D03*
X580266Y591114D03*
Y607140D03*
X543455Y591114D03*
Y607140D03*
X575166Y609999D03*
Y590900D03*
X585431Y604499D03*
Y593757D03*
X588777Y610700D03*
X562006Y604499D03*
Y593757D03*
X592124Y604499D03*
Y593757D03*
X595470Y610700D03*
X568699Y604499D03*
X571345Y610300D03*
X568699Y593757D03*
X548620Y604499D03*
X551966Y610700D03*
X548620Y593757D03*
X555313Y604499D03*
X558659Y610700D03*
X555313Y593757D03*
X580266Y609749D03*
X543455D03*
X575192Y607350D03*
X564966Y610300D03*
X608856Y-9901D03*
X612203D03*
X608856Y-1743D03*
X612203D03*
X615549D03*
Y9157D03*
X608856D03*
X612203D03*
X615549Y-9901D03*
X623000Y-3000D03*
X624770Y-640D03*
X620092Y13078D03*
X620192Y31978D03*
Y-5822D03*
X612203Y16999D03*
X608856D03*
X612203Y27899D03*
X608856D03*
X615549D03*
Y16999D03*
X647317Y-1310D03*
X660676Y-2600D03*
X656807Y-20652D03*
X657250Y-2050D03*
X663699Y3861D03*
X660000Y-17500D03*
X648550Y8550D03*
X651100Y8650D03*
X662700Y-17900D03*
X651300Y20000D03*
X659200Y31500D03*
X651300Y17500D03*
X661494Y32946D03*
X645430Y31067D03*
X656300Y22800D03*
X653800D03*
X656600Y31500D03*
X663300Y10000D03*
X651100Y11700D03*
X648500Y11600D03*
X648867Y31258D03*
X651442Y31225D03*
X659700Y22900D03*
X654016Y31150D03*
X647400Y-6900D03*
X605510Y27899D03*
Y9157D03*
X647000Y-9500D03*
X605510Y-1743D03*
Y-9901D03*
Y16999D03*
X647000Y-12100D03*
X659747Y-12132D03*
X620070Y50878D03*
X620192Y69778D03*
X612203Y54799D03*
X615549Y46957D03*
X608856Y54799D03*
X612203Y46957D03*
X608856D03*
X615549Y36057D03*
X608856D03*
X612203D03*
X608856Y65699D03*
X612203D03*
X615549D03*
Y54799D03*
X612203Y92599D03*
X608856D03*
X612203Y84757D03*
X608856D03*
X615549D03*
Y73857D03*
X608856D03*
X612203D03*
X615549Y92599D03*
X620092Y88678D03*
X663500Y48000D03*
X663700Y65600D03*
X663476Y45296D03*
X655600Y69100D03*
X658100D03*
X655600Y66100D03*
X658100D03*
X658567Y47639D03*
Y44639D03*
X656067D03*
Y47639D03*
X647600Y84200D03*
X647304Y91882D03*
X650204Y91282D03*
X649200Y88800D03*
Y86300D03*
X656500Y75300D03*
X652500D03*
X650000D03*
X652804Y90482D03*
X659000Y75300D03*
X646200Y86300D03*
Y88800D03*
X644904Y92382D03*
X650000Y72300D03*
X659000D03*
X656500D03*
X652500D03*
X652718Y93881D03*
X662352Y89566D03*
X605510Y92599D03*
Y73857D03*
Y36057D03*
Y46957D03*
Y84757D03*
Y65699D03*
Y54799D03*
X618800Y100100D03*
X616115Y108339D03*
X603163Y103971D03*
X608600Y103000D03*
X620054Y114096D03*
X633800Y119000D03*
X609482Y124568D03*
X622200Y112200D03*
X616167Y118627D03*
X605300Y124600D03*
X630000Y126572D03*
X624500Y129400D03*
X626900Y128300D03*
X633580Y125560D03*
X628673Y142718D03*
X632173Y142018D03*
X661700Y142300D03*
X644055Y144493D03*
X642673Y139811D03*
X639173Y140618D03*
X654555Y142193D03*
X651055Y142893D03*
X647555Y143643D03*
X658055Y141493D03*
X635673Y141318D03*
X636481Y124951D03*
X635951Y127419D03*
X661053Y115971D03*
X658490Y115432D03*
X650307Y115518D03*
X647809Y116121D03*
X645311Y116724D03*
X650120Y122700D03*
X660900Y123650D03*
Y126650D03*
X647120Y122700D03*
X657900Y126650D03*
Y123650D03*
X651920Y125750D03*
X656111Y121550D03*
X653111D03*
X654558Y115101D03*
X640043Y117728D03*
X639100Y124200D03*
X638800Y126700D03*
X648690Y125590D03*
X643674Y123573D03*
X644950Y125750D03*
X641950D03*
X642899Y117112D03*
X626040Y98281D03*
X613602Y118047D03*
Y109247D03*
X609860Y201356D03*
X613082Y200676D03*
X613773Y196796D03*
X610273Y197496D03*
X606400Y201000D03*
X606773Y198196D03*
X603273Y198896D03*
X613648Y204494D03*
X608648D03*
X604453Y202983D03*
X623648Y209494D03*
Y216994D03*
Y211994D03*
Y214494D03*
X613648Y209494D03*
Y211994D03*
X618648Y209494D03*
Y214494D03*
X621148Y211994D03*
Y216994D03*
X613648Y214494D03*
Y216994D03*
X623648Y206994D03*
X611148D03*
X618648D03*
X621148D03*
X616148D03*
Y211994D03*
Y216994D03*
X644750Y175650D03*
X660600Y175000D03*
X662786Y278084D03*
X660901Y279856D03*
X616148Y221994D03*
X623648Y224494D03*
Y226994D03*
X611148Y224494D03*
X613648D03*
X618648D03*
Y226994D03*
X621148D03*
X616148D03*
X608648D03*
Y224494D03*
X603300Y226700D03*
X613648Y226994D03*
X617235Y247735D03*
X614456Y244956D03*
X632500Y238500D03*
Y235000D03*
X632692Y248172D03*
X632532Y241717D03*
X630200Y248100D03*
X613648Y229494D03*
X621148D03*
X618648D03*
X611148D03*
X623648Y221994D03*
Y219494D03*
X611148Y221994D03*
X618648Y219494D03*
X621148Y221994D03*
X633308Y263808D03*
X621165Y256075D03*
X620850Y253416D03*
X613648Y219494D03*
Y221994D03*
X651235Y249165D03*
X657700Y250172D03*
X660588Y250312D03*
X662800Y248600D03*
X643500Y272262D03*
X654950Y253446D03*
X639320Y268000D03*
X652500Y273600D03*
X647487Y280308D03*
X643591Y266983D03*
X643500Y274868D03*
X642855Y269660D03*
X647469Y277639D03*
X642800Y264000D03*
X643100Y253700D03*
X642800Y261100D03*
X624500Y240500D03*
X627529Y280441D03*
X659900Y256900D03*
Y269200D03*
X662238Y296146D03*
X628950Y293550D03*
X654600Y296000D03*
X656042Y287439D03*
X664267Y292668D03*
X661232Y287321D03*
X655000Y284600D03*
X646700Y308850D03*
X652000Y284500D03*
X663200Y298600D03*
X644800Y292150D03*
X654500Y298600D03*
X652100Y288300D03*
X639045Y299555D03*
X639100Y309500D03*
X639622Y290210D03*
X643823Y289650D03*
X658500Y284500D03*
X658853Y294305D03*
X648900Y336600D03*
X646900Y320100D03*
Y317300D03*
X646800Y326100D03*
X646272Y328800D03*
X658900Y339150D03*
X636100Y329800D03*
X649000Y339400D03*
X638790Y329500D03*
X639350Y339980D03*
X639100Y319500D03*
X637143Y322000D03*
X637561Y312000D03*
X637600Y307000D03*
X662200Y284800D03*
X631250Y289650D03*
X628525Y287832D03*
X636799Y285670D03*
X636985Y288264D03*
X634407Y287915D03*
X641665Y281139D03*
X655900Y307700D03*
X656300Y312300D03*
X660700Y307700D03*
X655900Y316500D03*
X656000Y329800D03*
X655900Y320500D03*
X656000Y325100D03*
X660900Y329800D03*
X637561Y317000D03*
X637600Y302000D03*
X637143Y327000D03*
X664100Y348000D03*
X648800D03*
X658900D03*
X662936Y367171D03*
X659936Y364171D03*
X662936D03*
X654000Y348000D03*
X649600Y391200D03*
X664194Y351206D03*
X654194D03*
X659694D03*
X649194D03*
X609191Y451454D03*
X615300Y457900D03*
X624600Y419400D03*
X626737Y421000D03*
X619800Y416200D03*
X624300Y422100D03*
X627000Y423436D03*
X622900Y424200D03*
X619680Y422600D03*
X625200Y425400D03*
X621800Y421100D03*
X619700Y419500D03*
X634200Y436800D03*
X637300Y437200D03*
X640300Y437600D03*
X625430Y490100D03*
X607012Y465997D03*
X623660Y466746D03*
X605249Y480891D03*
X605826Y475894D03*
Y473394D03*
X634967Y470790D03*
X605206Y483291D03*
X618430Y491550D03*
X623400Y476300D03*
X619260Y466610D03*
X629300Y490000D03*
X612000Y484000D03*
X632113Y496892D03*
X619392Y514700D03*
X612515Y498752D03*
X612203Y510157D03*
X608856D03*
X615549D03*
X612203Y517999D03*
X608856D03*
X615549D03*
X623600Y521700D03*
X656900Y482290D03*
X649600Y492400D03*
X660500Y492000D03*
X656100Y486900D03*
X656050Y489500D03*
X637148Y472809D03*
X657227Y479116D03*
X662181Y479149D03*
X659770D03*
X648500Y477400D03*
X659070Y488709D03*
X639197Y490367D03*
X652000Y513900D03*
X655000D03*
X661500D03*
X658500D03*
X658900Y509300D03*
X646200Y499700D03*
X648025Y501575D03*
X609470Y484060D03*
X625569Y481568D03*
X628700Y482000D03*
X653800Y496600D03*
X641150Y484300D03*
X611250Y476750D03*
X605510Y517999D03*
Y510157D03*
X620192Y532978D03*
X608856Y547957D03*
X615549D03*
X612203D03*
X608856Y528899D03*
X612203D03*
X608856Y537057D03*
X615549D03*
X612203D03*
X615549Y528899D03*
X608856Y566699D03*
X612203D03*
Y555799D03*
X608856D03*
X615549Y574857D03*
X612203D03*
X615549Y585757D03*
X612203D03*
X608856Y574857D03*
Y585757D03*
X615549Y555799D03*
Y566699D03*
X618892Y555800D03*
X618292Y574300D03*
X662640Y528330D03*
X646150Y540350D03*
Y543350D03*
Y546350D03*
X650900Y552500D03*
X657100D03*
X654150Y530200D03*
X651100Y532700D03*
X651150Y530200D03*
X657250Y534300D03*
Y531300D03*
X659750Y534300D03*
Y531300D03*
X654200Y532800D03*
X653700Y552500D03*
X660200D03*
X652140Y577011D03*
Y574511D03*
X660217Y576734D03*
X649700Y574400D03*
X662000Y589000D03*
X651750Y584150D03*
X653100Y587000D03*
X661500Y569800D03*
X658900D03*
X650050Y568623D03*
X647350D03*
X663100Y574200D03*
X644800Y563300D03*
X647800D03*
X650800D03*
X653800D03*
X649700Y577000D03*
X605510Y566699D03*
Y528899D03*
Y555799D03*
Y585757D03*
Y574857D03*
Y537057D03*
Y547957D03*
X608856Y612657D03*
X615549D03*
X612203D03*
X631741Y615759D03*
X655100Y614100D03*
X612203Y604499D03*
X608856D03*
X612203Y593599D03*
X608856D03*
X615549Y604499D03*
Y593599D03*
X618192Y593600D03*
X620033Y608878D03*
X655100Y611500D03*
X644500Y594400D03*
X648180Y590702D03*
X646760Y592992D03*
X660230Y598170D03*
X627705Y611973D03*
X629977Y613024D03*
X605510Y604499D03*
Y612657D03*
Y593599D03*
X718975Y-4451D03*
X713824Y-18333D03*
X665942Y4716D03*
X674300Y9847D03*
X671800D03*
X669300D03*
X673900Y23100D03*
X671400D03*
X668900D03*
X690000Y15300D03*
X683800Y24856D03*
X670430Y29253D03*
X689900Y20800D03*
X692500Y15300D03*
X666100Y10000D03*
X684126Y28137D03*
X681426D03*
X692400Y20800D03*
X679936Y18406D03*
X670400Y26100D03*
X716858Y-14448D03*
X710263Y-14500D03*
X723827Y-14658D03*
X710327Y-11968D03*
X712796Y-16011D03*
X716921Y-6048D03*
X701100Y8100D03*
X704450Y4950D03*
X710800Y7100D03*
X705250Y8600D03*
X717720Y23279D03*
X715114Y26395D03*
X704500Y26300D03*
X723715Y23462D03*
X714823Y23610D03*
X704150Y19650D03*
X708000Y26600D03*
X700500D03*
X701120Y19619D03*
X698470Y19669D03*
X714337Y7852D03*
Y5352D03*
Y2852D03*
X718555Y-16147D03*
X719400Y14300D03*
X711791Y23716D03*
X710107Y-19839D03*
X708330Y-17806D03*
X665396Y23000D03*
X666500Y48000D03*
X665100Y68600D03*
X668100D03*
X666700Y65600D03*
X684904Y39943D03*
X689500Y37900D03*
X675235Y36797D03*
X685000Y46650D03*
X685100Y43000D03*
X670227Y34277D03*
X690100Y93200D03*
X664471Y86061D03*
X694600Y85000D03*
X693000Y92500D03*
X678020Y69870D03*
X678300Y92630D03*
Y95130D03*
X675630Y94988D03*
X681300Y95130D03*
Y92630D03*
X684300D03*
X687400Y93900D03*
X673830Y83050D03*
X676430D03*
X676500Y80500D03*
X673900D03*
X674010Y77970D03*
X676610D03*
X692200Y83800D03*
X695000Y67000D03*
X699880Y66840D03*
X724200Y64730D03*
X722460Y69550D03*
X713680Y60910D03*
X700360Y72160D03*
X694910Y72220D03*
X713050Y63650D03*
X710440Y63710D03*
X704880Y66750D03*
X697747Y72184D03*
X723700Y67400D03*
X713620Y58270D03*
X715800Y59490D03*
Y57000D03*
X713590Y53260D03*
X713610Y55730D03*
X700640Y69500D03*
X703120Y69380D03*
X702380Y66840D03*
X697440Y66900D03*
X700904Y38439D03*
X723603Y46929D03*
X721141Y46900D03*
X716742Y41062D03*
X713300Y86000D03*
X707329Y88955D03*
X705972Y86660D03*
X716176Y46822D03*
X716700Y43800D03*
X711100Y38700D03*
X714023Y38653D03*
X713674Y46822D03*
X714023Y41053D03*
X716900Y38500D03*
X711100Y41100D03*
X714000Y43900D03*
X722312Y48999D03*
X718600Y46921D03*
X719850Y48970D03*
X699800Y89100D03*
X713830Y82730D03*
X715130Y79574D03*
X697200Y79500D03*
X697100Y90600D03*
X703845Y88830D03*
X716268Y88683D03*
X716894Y84047D03*
X713115Y88629D03*
X701500Y85500D03*
X698300Y85300D03*
X709560Y84648D03*
X670795Y89189D03*
X692000Y45000D03*
Y48500D03*
X697500D03*
Y45000D03*
X670503Y115884D03*
X664700Y142800D03*
X675600Y144900D03*
Y150000D03*
X679900Y128200D03*
X682400Y127085D03*
X684900D03*
X673566Y116724D03*
X676494Y116940D03*
X668665Y118185D03*
X671249Y118744D03*
X677896Y119093D03*
X674896D03*
X693600Y103100D03*
X694459Y105382D03*
X691810Y105540D03*
X701953Y104902D03*
X715505Y155076D03*
X720700Y154750D03*
X725650Y155000D03*
X696100Y102700D03*
X696832Y104986D03*
X699400Y105060D03*
X704419Y104448D03*
X698600Y102600D03*
X691583Y200124D03*
X689033D03*
X686533D03*
Y196624D03*
X689033D03*
X691583D03*
X715550Y158880D03*
X705550D03*
X710550D03*
X709341Y190507D03*
X724888Y188930D03*
X709200Y198700D03*
X720369Y205199D03*
X714391Y215809D03*
X709182Y203948D03*
X709200Y201300D03*
X711800Y203100D03*
X706600Y201300D03*
X715100Y213344D03*
X715727Y218267D03*
X716480Y194700D03*
X709400Y195763D03*
X701956Y195294D03*
X705292Y195729D03*
X714137Y195682D03*
X711886Y194714D03*
X719686Y195421D03*
X722117Y195399D03*
X697568Y196197D03*
X707529Y193200D03*
X704907Y191638D03*
X701129Y192106D03*
X697746Y193205D03*
X716557Y198557D03*
X692513Y213800D03*
X692673Y206200D03*
X692500Y210100D03*
X690861Y211917D03*
Y215717D03*
X692400Y218100D03*
X690861Y204317D03*
Y208117D03*
X706500Y217400D03*
Y214900D03*
Y207800D03*
X706561Y211417D03*
Y204217D03*
X719315Y239104D03*
X669900Y224000D03*
X672500Y224100D03*
X678454Y278000D03*
X675380Y246340D03*
X678000Y246400D03*
X668100Y232200D03*
X667240Y246600D03*
X672530Y246300D03*
X677400Y232300D03*
X674300Y232200D03*
X675200Y224100D03*
X667600Y250200D03*
X688643Y225980D03*
X688388Y231280D03*
X678400Y224100D03*
X690380Y252240D03*
X690939Y266630D03*
X693530Y261240D03*
X690660Y264000D03*
X690704Y271324D03*
X690130Y277380D03*
X689960Y260500D03*
X671100Y232200D03*
X701800Y246480D03*
X669750Y246350D03*
X710572Y244773D03*
X719360Y241504D03*
X710627Y242061D03*
X702000Y243900D03*
X722050Y221150D03*
X707653Y226347D03*
X718300Y227400D03*
X701700Y226600D03*
X725725Y241560D03*
X710500Y224500D03*
X720450Y249950D03*
X710900Y231660D03*
X700000Y233700D03*
X704450Y226600D03*
X713800Y221544D03*
X709700Y275500D03*
X709600Y278100D03*
X704500Y252500D03*
X700800Y261300D03*
X715200Y258900D03*
X704090Y256080D03*
X710675Y263425D03*
X700900Y264100D03*
X697255Y267098D03*
X700400Y257200D03*
X694361Y223317D03*
Y220817D03*
X690861D03*
Y223317D03*
X672300Y269200D03*
X672200Y256800D03*
X706561Y219917D03*
X719900Y269300D03*
X725500Y279300D03*
X725300Y269400D03*
X719600Y279400D03*
X713700Y224144D03*
X713970Y308360D03*
X704175Y287275D03*
X704214Y290775D03*
X674469Y287375D03*
X686470Y282220D03*
X695000Y289500D03*
X670800Y292600D03*
X688100Y308600D03*
X680000Y281900D03*
X672150Y288350D03*
X695300Y338100D03*
X695400Y328000D03*
X686600Y335600D03*
X687400Y319833D03*
X687138Y317397D03*
X674700Y339200D03*
X687400Y328200D03*
X687300Y325200D03*
X684100Y338200D03*
X695400Y318000D03*
X706800Y281900D03*
X695800Y308000D03*
X696088Y297069D03*
X704500Y293800D03*
X707130Y310150D03*
X718200Y295000D03*
X713970Y310860D03*
X711900Y327700D03*
X712400Y324400D03*
X701100Y339000D03*
X698600Y338900D03*
X706300Y318400D03*
X683490Y282110D03*
X704404Y310875D03*
X697521Y320500D03*
X697120Y305349D03*
X670800Y298400D03*
X690048Y284053D03*
X665000Y284800D03*
X690048Y281053D03*
X678200Y307800D03*
X672700Y307700D03*
X667100D03*
X678100Y324800D03*
X672200Y329800D03*
X678100Y329600D03*
X666900Y329700D03*
X678200Y313700D03*
Y319300D03*
X688924Y288147D03*
X668000Y298400D03*
X704404Y315875D03*
X679000Y348000D03*
X674194Y358467D03*
X683417Y364972D03*
X677563Y365496D03*
X695700Y357300D03*
X695644Y354644D03*
X695700Y346300D03*
X688600Y365100D03*
X671936Y367171D03*
X665936Y370171D03*
X684900Y348000D03*
X674600D03*
X671936Y370171D03*
X665936Y367171D03*
X668936Y370171D03*
Y367171D03*
X665936Y364171D03*
X668936D03*
X669093Y348120D03*
X671936Y373171D03*
X668936D03*
X670300Y375600D03*
X683100Y392200D03*
X713900Y347800D03*
X698560Y374430D03*
X713900Y342800D03*
Y352800D03*
Y350300D03*
Y345300D03*
X679523Y385808D03*
X690040Y412030D03*
X685600Y432500D03*
X690600D03*
X680370Y427770D03*
X687400Y411200D03*
X690600Y437500D03*
X703876Y414949D03*
X705850Y417093D03*
X710600Y420267D03*
X710423Y417423D03*
X708346Y415859D03*
X708011Y419078D03*
X712980Y417900D03*
X713493Y420449D03*
X718546Y500283D03*
X723748Y499091D03*
X701255Y521538D03*
X676900Y489400D03*
X666500Y487600D03*
Y484600D03*
X669500D03*
Y481600D03*
X674300Y489500D03*
X689825Y491755D03*
X693604Y491803D03*
X664610Y512810D03*
X685050Y503970D03*
X682050D03*
X689825Y494255D03*
X693604Y494303D03*
X669300Y504000D03*
X677800Y485600D03*
X680300Y485700D03*
X676600Y501300D03*
X690500Y523300D03*
X675500Y521900D03*
X691000Y498200D03*
X688202Y497736D03*
X679049Y503746D03*
X671500Y501300D03*
X674000Y501200D03*
X704500Y512850D03*
X716267Y522020D03*
X703028Y495600D03*
X709028D03*
X706028D03*
X707511Y483439D03*
X720300Y485800D03*
X723792Y489148D03*
X721301Y488200D03*
X703028Y492600D03*
X706028D03*
X710137Y483583D03*
X708700Y499400D03*
X708500Y512500D03*
X700500Y512850D03*
X701200Y524250D03*
X712100Y512700D03*
X701500Y505500D03*
X710643Y505496D03*
X703800Y507100D03*
X716100Y525200D03*
X711339Y499478D03*
X713200Y505500D03*
X715900Y505650D03*
X715009Y512917D03*
X726040Y506080D03*
X721414Y508986D03*
X720565Y511338D03*
X686375Y527778D03*
X685200Y530500D03*
X684500Y532900D03*
X680910Y582000D03*
X693200Y575900D03*
X674200Y588900D03*
X690100Y575860D03*
X689193Y573493D03*
X693126Y581380D03*
X671599Y573493D03*
X671791Y588920D03*
X674099Y573493D03*
X669099D03*
X668891Y588900D03*
X696600Y581400D03*
X665700Y574200D03*
X713650Y540750D03*
X715650Y542250D03*
Y545250D03*
X713650Y546750D03*
X708000Y553250D03*
X720200Y551750D03*
X715650Y551250D03*
X716100Y527700D03*
X713600D03*
Y530200D03*
Y532700D03*
X716100D03*
Y530200D03*
X725000Y533700D03*
X696000Y553250D03*
X715650Y548250D03*
X713650Y549750D03*
X723200Y551750D03*
X699000Y553250D03*
X702000D03*
X705000D03*
X713650Y543750D03*
X723200Y554750D03*
X706500Y555750D03*
X703500D03*
X700500D03*
X720200Y554750D03*
X709500Y555750D03*
X712600Y571900D03*
X716300Y569400D03*
X707500Y587800D03*
X722200Y571300D03*
X702100Y568800D03*
X702000Y571400D03*
X725400Y580900D03*
X722500D03*
X691900Y531350D03*
Y534850D03*
X697500Y534750D03*
Y531250D03*
X713500Y618000D03*
X711500Y616274D03*
X665000Y598500D03*
X725173Y598171D03*
X724106Y609550D03*
X721106D03*
X708900Y589850D03*
X706100D03*
X712000Y597000D03*
Y599500D03*
X708800Y599300D03*
Y596700D03*
X712106Y604050D03*
X717612Y598554D03*
X716106Y609050D03*
X712106Y606650D03*
X722406Y598950D03*
X755000Y17255D03*
X732600Y3600D03*
X755500Y8700D03*
X753600Y-4300D03*
X734500Y-5700D03*
X734916Y-1587D03*
X732316D03*
X732191Y-4087D03*
X735020Y-8858D03*
X726327Y-14658D03*
X728837Y-12763D03*
X728716Y-15465D03*
X731210Y-15134D03*
X736715Y33487D03*
X734201Y33510D03*
X726250Y23550D03*
X729500Y23500D03*
X729600Y17991D03*
X734256D03*
X754600Y300D03*
X751900Y400D03*
X731457Y8471D03*
X732335Y6000D03*
X786414Y-9650D03*
X766300Y-1800D03*
X765400Y-9800D03*
X779771Y9114D03*
X773228D03*
Y-1801D03*
X779921Y-1751D03*
X776188Y-7851D03*
X769881Y-9901D03*
X782567Y-7700D03*
X786388Y9098D03*
Y-1801D03*
X782567Y33700D03*
X779921Y27899D03*
X776188Y33700D03*
X773228Y27899D03*
X786414Y30750D03*
X786388Y33399D03*
X764100Y17100D03*
X760100Y17255D03*
X763500Y23940D03*
X786414Y28150D03*
X769881Y27899D03*
X782567Y14814D03*
Y30100D03*
X769881Y16839D03*
X776224Y14714D03*
X776188Y29949D03*
X786364Y16900D03*
X756714Y23130D03*
X753675Y23239D03*
X756176Y-4300D03*
X776274Y12114D03*
X773228Y-9901D03*
X776188Y-4100D03*
X773228Y17157D03*
X782567Y12114D03*
X779921Y-9901D03*
X782567Y-4100D03*
X779921Y17157D03*
X769881Y9157D03*
X786388Y11700D03*
Y-4401D03*
X786414Y-7050D03*
X786388Y14300D03*
X736631Y36122D03*
X736655Y38531D03*
X731887Y40916D03*
X734155Y38531D03*
X734131Y36122D03*
X731843Y43571D03*
X756100Y36200D03*
X755500Y46700D03*
X737800Y55800D03*
X731200Y68600D03*
X733600Y68546D03*
X733642Y66146D03*
X731242Y66200D03*
X731332Y63801D03*
X733732Y63747D03*
X751600Y41000D03*
X755500Y55200D03*
X752600Y86200D03*
X735700Y82700D03*
X752680Y83500D03*
X733740Y95230D03*
X730923Y75315D03*
X731910Y92790D03*
X751708Y73800D03*
X755500Y84361D03*
X733671Y75412D03*
X753100Y92111D03*
X779921Y65699D03*
X773228D03*
X786414Y68550D03*
X779921Y54957D03*
X782567Y49914D03*
X773228Y54957D03*
X776274Y49914D03*
X786388Y52100D03*
Y49500D03*
X764100Y55100D03*
X763500Y59700D03*
X765900Y35800D03*
X786388Y35999D03*
X786364Y54700D03*
X786388Y46898D03*
X773228Y46914D03*
X779771D03*
X776188Y67749D03*
X769881Y66000D03*
X782567Y67900D03*
Y52614D03*
X769881Y54839D03*
X779921Y35983D03*
X773228D03*
X776224Y52514D03*
X769881Y92500D03*
X773228Y84714D03*
X779771D03*
X776224Y90314D03*
X782567Y90414D03*
X779921Y73849D03*
X773228Y73799D03*
X782567Y71500D03*
X779921Y92757D03*
X782567Y87714D03*
X776188Y71500D03*
X773228Y92757D03*
X776274Y87714D03*
X786388Y89900D03*
Y71199D03*
Y87300D03*
X761650Y94550D03*
X769500Y84700D03*
X763400Y78300D03*
X766824Y85943D03*
X763930Y85100D03*
X786414Y65950D03*
X786388Y73799D03*
X786364Y92500D03*
X786388Y84698D03*
X730038Y88408D03*
X732599D03*
X735241Y88329D03*
X763350Y81220D03*
X732734Y82626D03*
X769881Y46957D03*
X746600Y103900D03*
X730600Y154984D03*
X746000Y150500D03*
X740718Y150957D03*
X741700Y102000D03*
X752900Y101000D03*
X744200Y102800D03*
X769100Y102900D03*
X766500D03*
X764000Y95750D03*
X756800Y99400D03*
Y102000D03*
X758400Y156200D03*
X747600Y161450D03*
X740650Y164800D03*
X735600Y164900D03*
X740650Y158800D03*
X727776Y188811D03*
X733564Y189288D03*
X742091Y188333D03*
X747469Y188368D03*
X755248D03*
X739641Y190634D03*
X752708Y188455D03*
X750167Y188490D03*
X744928Y188438D03*
X737319Y189766D03*
X739359Y188125D03*
X735626Y187965D03*
X731155Y189256D03*
X754726Y205037D03*
X752226D03*
X749726D03*
X754726Y207537D03*
X752226D03*
X749726D03*
X742937Y218574D03*
X737536Y192392D03*
X771232Y214033D03*
X777182Y212033D03*
X766368Y183636D03*
X765227Y186164D03*
X765007Y188583D03*
X762667Y186186D03*
X762533Y188626D03*
X763881Y184103D03*
X760084Y188508D03*
X760258Y186077D03*
X767692Y185654D03*
X767476Y188323D03*
X757654Y188464D03*
X758400Y159200D03*
X774582Y212033D03*
X770200Y208600D03*
X765116Y216512D03*
X779932Y212033D03*
X770300Y204930D03*
X769044Y191348D03*
X775171Y218616D03*
X787371Y215216D03*
Y217716D03*
X777700Y218600D03*
X727969Y236770D03*
X736612Y237908D03*
X727997Y239195D03*
X736625Y240308D03*
X737837Y222364D03*
Y224964D03*
X740300Y228100D03*
X742897Y229573D03*
X731662Y247716D03*
X742937Y221174D03*
Y223774D03*
X740437Y224964D03*
Y222364D03*
X748700Y254000D03*
X751363Y254207D03*
X754758Y273356D03*
X749100Y279500D03*
X746303Y243122D03*
X746321Y240569D03*
X777000Y243500D03*
X766732Y225189D03*
X761580Y220160D03*
X760304Y235827D03*
X768560Y244055D03*
X765116Y248512D03*
X779932Y244033D03*
X766632Y222589D03*
X771650Y246451D03*
X765116Y280512D03*
X779400Y276200D03*
X766532Y254652D03*
X771650Y278451D03*
X766632Y257252D03*
X776700Y275500D03*
X748990Y267450D03*
X765007Y252363D03*
X769019Y276400D03*
X762616Y270113D03*
X761480Y242720D03*
X726328Y249979D03*
X731100Y269300D03*
Y279300D03*
X775200Y230500D03*
X775171Y227116D03*
Y234316D03*
X787371Y247216D03*
Y249716D03*
X775232Y221133D03*
X777700Y250600D03*
X775232Y223633D03*
X775171Y250616D03*
X775271Y262716D03*
X775171Y259116D03*
Y266316D03*
X775232Y253133D03*
Y255633D03*
X787371Y279216D03*
X748700Y257500D03*
X774347Y339983D03*
X762760Y339500D03*
X736000Y303400D03*
X741250Y298856D03*
X727300Y302910D03*
X727474Y338363D03*
Y335363D03*
X732474D03*
Y338363D03*
X756114Y316209D03*
X741512Y315538D03*
X729974Y338363D03*
Y335363D03*
X767310Y286530D03*
X779100Y307900D03*
X771600Y310600D03*
X776270Y307100D03*
X765007Y284363D03*
X771278Y307918D03*
X762842Y302434D03*
X765116Y312512D03*
X767000Y318500D03*
X779932Y340033D03*
X777182D03*
X766732Y321189D03*
X765007Y316363D03*
X765730Y335064D03*
X775271Y294716D03*
X775171Y291116D03*
Y298316D03*
X777700Y282600D03*
X775232Y287633D03*
Y285133D03*
X775171Y282616D03*
X787371Y281716D03*
Y311216D03*
X775271Y326716D03*
X775171Y323116D03*
Y330316D03*
X777800Y314700D03*
X775171Y314616D03*
X787371Y313716D03*
X775232Y317133D03*
Y319633D03*
X749800Y282300D03*
X727474Y344663D03*
Y367463D03*
X732474D03*
X729974D03*
X727474Y364863D03*
X732474D03*
X729974D03*
Y347663D03*
X727474D03*
X732474D03*
Y344663D03*
X732000Y380000D03*
X727574Y373463D03*
X732574D03*
X730074D03*
X732574Y376063D03*
X730074D03*
X729974Y344663D03*
X731100Y362300D03*
X772443Y371976D03*
X765116Y344512D03*
X779882Y372033D03*
X767477Y350708D03*
X771700Y342501D03*
X766732Y353189D03*
X777100Y372000D03*
X765007Y348363D03*
X760140Y362819D03*
X758952Y384100D03*
X763333Y400212D03*
X772300Y403520D03*
X764131Y376747D03*
X766643Y382724D03*
X771400Y374400D03*
X764957Y380363D03*
X775171Y346616D03*
Y362316D03*
X775271Y358716D03*
X775171Y355116D03*
X787371Y343216D03*
Y345716D03*
X775232Y349133D03*
X777600Y346600D03*
X775232Y351633D03*
X787321Y374916D03*
Y377316D03*
X775182Y383633D03*
Y381133D03*
X778000Y378700D03*
X775121Y378616D03*
Y394316D03*
X775221Y390716D03*
X775121Y387116D03*
X746130Y430130D03*
X755487Y409903D03*
Y412403D03*
X748085Y412338D03*
X750585D03*
X753085D03*
Y409838D03*
X750585D03*
X748085D03*
X749640Y431797D03*
X739933Y447401D03*
X747950Y441600D03*
X748500Y438900D03*
X728940Y457806D03*
X746151Y433077D03*
X766200Y417005D03*
X775417Y435799D03*
X777979Y436516D03*
X760326Y414167D03*
Y411667D03*
X757826D03*
Y414167D03*
X762989Y411728D03*
X763069Y414441D03*
X768080Y418780D03*
X766394Y414397D03*
X763706Y514250D03*
X728373Y488356D03*
X731339Y489319D03*
X743483Y492937D03*
X752496Y515974D03*
X732522Y526808D03*
Y524308D03*
X750518Y522108D03*
X734922Y526808D03*
X756000Y525950D03*
X729000Y511500D03*
X731600Y511600D03*
X748524Y502174D03*
X743524D03*
X748524Y499674D03*
X750931Y499916D03*
X746024Y499674D03*
X743524D03*
X746024Y502174D03*
X786388Y515300D03*
Y512700D03*
X769500Y510100D03*
X763950Y508540D03*
X766535Y517900D03*
X763950Y506040D03*
Y511040D03*
X776224Y515714D03*
X779771Y510114D03*
X773228D03*
X769881Y517900D03*
X782567Y515814D03*
X786388Y510098D03*
X786364Y517900D03*
X779921Y518157D03*
X782567Y513114D03*
X773228Y518157D03*
X776274Y513114D03*
X738648Y492050D03*
X752900Y521121D03*
Y518621D03*
X763544Y522236D03*
X732442Y529300D03*
X734842D03*
X736300Y541500D03*
X756000Y537000D03*
X737400Y529400D03*
X734900Y531800D03*
X732400D03*
X726200Y551750D03*
X732098Y550000D03*
X729550D03*
X732098Y553000D03*
X729550D03*
X736000Y537700D03*
Y535200D03*
X733500Y537700D03*
Y535200D03*
X728000Y533750D03*
X754910Y556400D03*
X726200Y554750D03*
X727400Y571300D03*
X755000Y574800D03*
X752500Y585150D03*
X727106Y586550D03*
X732098Y556000D03*
X729550D03*
X755000Y566000D03*
X732600Y573950D03*
X786414Y531750D03*
X786388Y534399D03*
X782567Y550914D03*
X776274D03*
X786388Y553100D03*
Y550500D03*
X764400Y528600D03*
X769500Y536983D03*
X765100Y537110D03*
X773228Y536999D03*
X763677Y547783D03*
X776188Y530949D03*
X782567Y531100D03*
X769818Y529200D03*
X779921Y537049D03*
X782567Y553614D03*
X773228Y547914D03*
X779771D03*
X776224Y553514D03*
X786388Y536999D03*
X786414Y529150D03*
X786388Y547898D03*
X779921Y528899D03*
X776188Y534700D03*
X786414Y569550D03*
X786388Y572199D03*
X782567Y588714D03*
X776274D03*
X786388Y588300D03*
X763300Y566000D03*
X769500Y585700D03*
X764117Y575658D03*
X766535Y555700D03*
X763450Y585200D03*
X765900Y587300D03*
X786364Y555700D03*
X769881D03*
X773228Y574799D03*
X782567Y568900D03*
X769700Y566900D03*
X776188Y568749D03*
X779921Y574849D03*
X773228Y585714D03*
X779771D03*
X786388Y574799D03*
Y585698D03*
X786414Y566950D03*
X779921Y555957D03*
X782567Y572500D03*
X779921Y566699D03*
X773228Y555957D03*
X776188Y572500D03*
X773228Y566699D03*
X769500Y547900D03*
Y574700D03*
X782567Y534700D03*
X773228Y528899D03*
X733032Y604000D03*
X779921Y612649D03*
X773228Y612599D03*
X786388D03*
X769500Y612583D03*
X755000Y614500D03*
X728000Y623500D03*
X727000Y606600D03*
X739307Y598850D03*
X755800Y604600D03*
X726857Y610871D03*
X729616Y610863D03*
X753300Y593600D03*
X732500Y611000D03*
X782567Y610300D03*
X779921Y593757D03*
Y604499D03*
X776188Y610300D03*
X773228Y593757D03*
Y604499D03*
X786414Y607350D03*
X786388Y590900D03*
Y609999D03*
X764400Y604600D03*
X766535Y593500D03*
X766600Y590700D03*
X769700Y604900D03*
X776188Y606549D03*
X782567Y606700D03*
Y591414D03*
X776224Y591314D03*
X786414Y604750D03*
X786364Y593500D03*
X755900Y593650D03*
X803346Y-1751D03*
X810039Y-1801D03*
X791514Y-2050D03*
X791501Y-9864D03*
X812999Y-7851D03*
X806692D03*
X799999D03*
X816582Y9114D03*
X796653D03*
X791464Y9100D03*
X810039Y9114D03*
X803346D03*
X816732Y-1751D03*
X796653D03*
X799999Y29949D03*
X812999Y33700D03*
X810039Y27899D03*
X803346D03*
X796653D03*
X816732D03*
X791488Y30540D03*
Y33149D03*
X806692Y29949D03*
X812999D03*
X791501Y27936D03*
X791488Y17114D03*
X799999Y14814D03*
X813035Y14714D03*
X806692Y14814D03*
X828275Y9100D03*
X833464Y9114D03*
X840157D03*
X819378Y-7700D03*
X823199Y9098D03*
Y-1801D03*
X823225Y-9650D03*
X828312Y-9864D03*
X843503Y-7851D03*
X836810D03*
X846850Y-1801D03*
X828325Y-2050D03*
X833464Y-1751D03*
X840157D03*
X846850Y9114D03*
X833464Y27899D03*
X846850D03*
X819378Y33700D03*
X823225Y30750D03*
X828299Y30540D03*
X823199Y33399D03*
X828299Y33149D03*
X819378Y14814D03*
Y30100D03*
X843503Y14814D03*
X823175Y16900D03*
X823225Y28150D03*
X828312Y27936D03*
X836810Y29949D03*
X828299Y17114D03*
X836810Y14814D03*
X843503Y29949D03*
X840157Y27899D03*
X796653Y-9901D03*
X833464D03*
X840157D03*
X843503Y-3700D03*
X799999Y12114D03*
X836810D03*
X843503D03*
X840157Y17157D03*
X828299Y-4651D03*
Y11914D03*
X823199Y-4401D03*
Y11700D03*
X791488Y-4651D03*
Y11914D03*
X828299Y14514D03*
Y-7260D03*
X823199Y14300D03*
X823225Y-7050D03*
X791488Y-7260D03*
Y14514D03*
X819378Y12114D03*
X816732Y-9901D03*
Y17157D03*
X819378Y-4100D03*
X799999Y-3700D03*
X796653Y17157D03*
X803346Y-9901D03*
X806692Y12114D03*
Y-3700D03*
X803346Y17157D03*
X846850Y-9901D03*
Y17157D03*
X833464D03*
X836810Y-3700D03*
X810039Y-9901D03*
X813085Y12114D03*
X812999Y-4100D03*
X810039Y17157D03*
X791488Y54914D03*
X799999Y52614D03*
X796653Y46914D03*
X810039Y65699D03*
X803346D03*
X796653D03*
X816732D03*
X791488Y68340D03*
X810039Y54957D03*
X813085Y49914D03*
X806692Y34100D03*
X803346Y54957D03*
X806692Y49914D03*
X799999Y34100D03*
X796653Y54957D03*
X799999Y49914D03*
X816732Y54957D03*
X791488Y52314D03*
Y49714D03*
X791464Y46900D03*
X810039Y35999D03*
X803346Y36049D03*
X799999Y90414D03*
X791488Y92714D03*
X806692Y90414D03*
X812999Y71500D03*
X810039Y92757D03*
X813085Y87714D03*
X806692Y71900D03*
X803346Y92757D03*
X806692Y87714D03*
X799999Y71900D03*
X796653Y92757D03*
X799999Y87714D03*
X816732Y92757D03*
X791488Y70949D03*
Y87514D03*
Y90114D03*
X816582Y46914D03*
X816732Y36049D03*
X799999Y67749D03*
X812999D03*
X806692D03*
X791501Y65736D03*
X803346Y46914D03*
X806692Y52614D03*
X813035Y52514D03*
X810039Y46914D03*
X791514Y35750D03*
X796653Y36049D03*
X816582Y73849D03*
X791514Y73550D03*
X796653Y73849D03*
X810039Y73799D03*
X803346Y73849D03*
X816582Y84714D03*
X813035Y90314D03*
X803346Y84714D03*
X810039D03*
X796653D03*
X791464Y84700D03*
X846850Y65699D03*
X823225Y68550D03*
X828299Y68340D03*
X843503Y34100D03*
X833464Y54957D03*
X836810Y34100D03*
Y49914D03*
X846850Y54957D03*
X819378Y49914D03*
X823199Y52100D03*
X828299Y52314D03*
X823199Y49500D03*
X828299Y49714D03*
X819378Y67900D03*
Y52614D03*
X846850Y35999D03*
X833464Y36049D03*
X840157D03*
X823225Y65950D03*
X823175Y54700D03*
X823199Y46898D03*
Y35999D03*
X828299Y54914D03*
X828275Y46900D03*
X828325Y35750D03*
X833464Y46914D03*
X836810Y52614D03*
X840157Y46914D03*
X828312Y65736D03*
X836810Y67749D03*
X843503D03*
X846850Y46914D03*
X843503Y52614D03*
X840157Y65699D03*
X833464D03*
X823175Y92500D03*
X823199Y84698D03*
X846850Y73799D03*
X843503Y90414D03*
X846850Y84714D03*
X828325Y73550D03*
X840157Y73849D03*
X833464D03*
X828299Y92714D03*
X836810Y90414D03*
X840157Y84714D03*
X833464D03*
X828275Y84700D03*
X843503Y71900D03*
X840157Y92757D03*
X843503Y87714D03*
X836810Y71900D03*
X833464Y92757D03*
X836810Y87714D03*
X846850Y92757D03*
X819378Y71500D03*
Y87714D03*
X823199Y89900D03*
X828299Y70949D03*
Y87514D03*
X823199Y71199D03*
Y87300D03*
X828299Y90114D03*
X840157Y54957D03*
X843503Y49914D03*
X819378Y90364D03*
X823199Y73799D03*
X822400Y212400D03*
X799300Y195600D03*
Y199100D03*
X813700Y195600D03*
X790871Y215216D03*
Y217716D03*
X845100Y268200D03*
X847600D03*
X842600D03*
X847600Y243400D03*
X841400Y243300D03*
X847600Y238400D03*
X841400Y238300D03*
X847600Y240900D03*
X841400Y240800D03*
X789500Y231800D03*
X790900Y234000D03*
Y229700D03*
X790846Y225774D03*
X790882Y221723D03*
X790871Y247216D03*
Y249716D03*
X789471Y227742D03*
X789576Y223737D03*
X789554Y219723D03*
X790900Y253900D03*
X789432Y252000D03*
X790871Y266216D03*
X789432Y255800D03*
X790867Y257724D03*
X789432Y259800D03*
X789500Y263900D03*
X790885Y261711D03*
X790871Y279216D03*
X842600Y299900D03*
X845100D03*
X847600D03*
X845100Y331500D03*
X842600D03*
X847600D03*
X790871Y311216D03*
X789432Y284200D03*
Y288300D03*
Y292400D03*
X789400Y296200D03*
X790871Y298216D03*
X790937Y294270D03*
X790900Y290300D03*
Y286200D03*
X790871Y281716D03*
Y313716D03*
X789432Y319900D03*
Y323900D03*
X790900Y322000D03*
Y326000D03*
X790871Y330216D03*
X789500Y328000D03*
X789478Y315671D03*
X790800Y317700D03*
X805600Y403900D03*
X847600Y363000D03*
X845100D03*
X842600D03*
X847577Y381842D03*
X824000Y402863D03*
X840871Y391380D03*
X837272Y391420D03*
X827800Y402863D03*
X832300D03*
X789432Y348100D03*
Y352100D03*
X789597Y356105D03*
X789500Y360200D03*
X790900Y358200D03*
X790835Y354048D03*
X790867Y350024D03*
X790871Y345716D03*
Y343216D03*
Y362216D03*
X790821Y374916D03*
X790900Y389300D03*
X789500Y391300D03*
X790900Y393400D03*
Y381100D03*
X789582Y383200D03*
X790900Y385300D03*
X789500Y387300D03*
X790821Y377316D03*
X789282Y379200D03*
X797000Y404700D03*
X797200Y409830D03*
X805367Y407400D03*
X797780Y423484D03*
X800610Y415000D03*
X798500Y412600D03*
X799999Y513114D03*
X791488Y512914D03*
Y515514D03*
X816582Y510114D03*
X806692Y515814D03*
X813035Y515714D03*
X810039Y510114D03*
X791488Y518114D03*
X791464Y510100D03*
X799999Y515814D03*
X796653Y510114D03*
X803346D03*
Y518157D03*
X806692Y513114D03*
X796653Y518157D03*
X819378Y515764D03*
X843503Y515814D03*
X846850Y510114D03*
X823175Y517900D03*
X823199Y510098D03*
X828299Y518114D03*
X840157Y510114D03*
X833464D03*
X836810Y515814D03*
X846850Y518157D03*
X813085Y513114D03*
X810039Y518157D03*
X823199Y512700D03*
Y515300D03*
X819378Y513114D03*
X816732Y518157D03*
X828299Y515514D03*
Y512914D03*
X836810Y513114D03*
X833464Y518157D03*
X843503Y513114D03*
X840157Y518157D03*
X796653Y528899D03*
X791488Y534149D03*
Y531540D03*
X813085Y550914D03*
X806692D03*
X799999D03*
X791488Y550714D03*
Y553314D03*
X816582Y537049D03*
Y547914D03*
X810039Y536999D03*
X806692Y530949D03*
X812999D03*
X803346Y537049D03*
X796653D03*
X799999Y530949D03*
X791501Y528936D03*
X791514Y536750D03*
X799999Y553614D03*
X810039Y547914D03*
X796653D03*
X803346D03*
X791464Y547900D03*
X806692Y553614D03*
X813035Y553514D03*
X806692Y535100D03*
X803346Y528899D03*
X799999Y535100D03*
X816732Y555957D03*
Y566699D03*
X791488Y571949D03*
X813085Y588714D03*
X806692D03*
X799999D03*
X791488Y588514D03*
Y555914D03*
X810039Y585714D03*
X806692Y568749D03*
X810039Y574799D03*
X812999Y568749D03*
X803346Y585714D03*
X796653D03*
X791514Y574550D03*
X791464Y585700D03*
X799999Y568749D03*
X796653Y574849D03*
X803346D03*
X791501Y566736D03*
X816582Y585714D03*
Y574849D03*
X810039Y555957D03*
X812999Y572500D03*
X810039Y566699D03*
X803346Y555957D03*
X806692Y572900D03*
X803346Y566699D03*
X796653Y555957D03*
X799999Y572900D03*
X796653Y566699D03*
X846850Y528899D03*
X843503Y550914D03*
X836810D03*
X819378D03*
X823199Y553100D03*
X828299Y550714D03*
X823199Y550500D03*
X828299Y553314D03*
X819378Y553564D03*
Y531100D03*
X836810Y530949D03*
X833464Y537049D03*
X846850Y547914D03*
X833464D03*
X840157D03*
X828275Y547900D03*
X843503Y553614D03*
X836810D03*
X846850Y536999D03*
X843503Y530949D03*
X823199Y547898D03*
Y536999D03*
X823225Y529150D03*
X828325Y536750D03*
X840157Y537049D03*
X828312Y528936D03*
X840157Y555957D03*
X843503Y572900D03*
X840157Y566699D03*
X833464Y555957D03*
Y566699D03*
X846850Y555957D03*
Y566699D03*
X823225Y569550D03*
X828299Y571949D03*
X823199Y572199D03*
X828299Y569340D03*
X843503Y588714D03*
X836810D03*
X819378D03*
X828299Y588514D03*
X823199Y588300D03*
X819378Y568900D03*
X823175Y555700D03*
X828299Y555914D03*
X828275Y585700D03*
X823225Y566950D03*
X823199Y585698D03*
Y574799D03*
X828312Y566736D03*
X840157Y585714D03*
X833464D03*
X828325Y574550D03*
X840157Y574849D03*
X833464D03*
X836810Y568749D03*
X846850Y585714D03*
Y574799D03*
X843503Y568749D03*
X812999Y534700D03*
X823225Y531750D03*
X816732Y528899D03*
X819378Y534700D03*
X828299Y534149D03*
X836810Y535100D03*
X840157Y528899D03*
X843503Y535100D03*
X791488Y569340D03*
X836810Y572900D03*
X819378Y572500D03*
X810039Y528899D03*
X823199Y534399D03*
X828299Y531540D03*
X833464Y528899D03*
X846850Y612599D03*
X840157Y612649D03*
X833464D03*
X823199Y612599D03*
X810039D03*
X803346Y612649D03*
X796653D03*
X816582D03*
X812999Y610300D03*
X810039Y593757D03*
Y604499D03*
X806692Y610700D03*
X803346Y593757D03*
Y604499D03*
X799999Y610700D03*
X796653Y593757D03*
Y604499D03*
X816732Y593757D03*
Y604499D03*
X791488Y609749D03*
Y591114D03*
X791514Y612350D03*
X806692Y606549D03*
X812999D03*
X799999D03*
X791501Y604536D03*
X806692Y591414D03*
X813035Y591314D03*
X799999Y591414D03*
X791488Y593714D03*
X840157Y593757D03*
X843503Y610700D03*
X840157Y604499D03*
X833464Y593757D03*
X836810Y610700D03*
X833464Y604499D03*
X846850Y593757D03*
X819378Y610300D03*
X823199Y590900D03*
X828299Y609749D03*
X823199Y609999D03*
X828299Y591114D03*
Y607140D03*
X819378Y606700D03*
Y591364D03*
X823225Y604750D03*
X823175Y593500D03*
X843503Y591414D03*
X828312Y604536D03*
X843503Y606549D03*
X836810D03*
X828325Y612350D03*
X836810Y591414D03*
X828299Y593714D03*
X791488Y607140D03*
X846850Y604499D03*
X823225Y607350D03*
X870275Y9114D03*
X865086Y9100D03*
X860010Y9098D03*
X876968Y9114D03*
Y-1751D03*
X873621Y-7851D03*
X865123Y-9864D03*
X860036Y-9650D03*
X849810Y-7851D03*
X856189Y-7700D03*
X860010Y-1801D03*
X865136Y-2050D03*
X853543Y-1751D03*
X870275D03*
X853393Y9114D03*
X856189Y33700D03*
X853543Y27899D03*
X876968D03*
X849810Y33700D03*
X870275Y27899D03*
X860036Y30750D03*
X865110Y30540D03*
X860010Y33399D03*
X865110Y33149D03*
X860036Y28150D03*
X859986Y16900D03*
X865110Y17114D03*
X856189Y14814D03*
X849846Y14714D03*
X873621Y14814D03*
Y29949D03*
X865123Y27936D03*
X849810Y29949D03*
X856189Y30100D03*
X896847Y-9650D03*
X910432Y-7851D03*
X883661Y-1801D03*
X880314Y-7851D03*
X886621D03*
X907086Y-1751D03*
X890354D03*
X896821Y-1801D03*
X901947Y-2050D03*
X901934Y-9864D03*
X893000Y-7700D03*
X883661Y9114D03*
X907086D03*
X896821Y9098D03*
X901897Y9100D03*
X890204Y9114D03*
X886621Y33700D03*
X883661Y27899D03*
X907086D03*
X896847Y30750D03*
X901921Y33149D03*
X896821Y33399D03*
X901921Y30540D03*
X910432Y29949D03*
X896797Y16900D03*
X893000Y14814D03*
X901921Y17114D03*
X901934Y27936D03*
X893000Y30100D03*
X880314Y14814D03*
X886657Y14714D03*
X886621Y29949D03*
X880314D03*
X896847Y28150D03*
X910432Y14814D03*
X893000Y33700D03*
X890354Y27899D03*
X870275Y-9901D03*
X876968D03*
X880314Y-3700D03*
X907086Y-9901D03*
X873621Y12114D03*
X880314D03*
X876968Y17157D03*
X910432Y12114D03*
X901921Y11914D03*
Y-4651D03*
X865110Y11914D03*
Y-4651D03*
X896821Y-4401D03*
Y11700D03*
X860010D03*
Y-4401D03*
X901921Y-7260D03*
Y14514D03*
X865110Y-7260D03*
Y14514D03*
X896847Y-7050D03*
X896821Y14300D03*
X860036Y-7050D03*
X860010Y14300D03*
X907086Y17157D03*
X886707Y12114D03*
X883661Y-9901D03*
Y17157D03*
X886621Y-4100D03*
X893000Y12114D03*
X890354Y-9901D03*
X893000Y-4100D03*
X890354Y17157D03*
X873621Y-3700D03*
X870275Y17157D03*
X849896Y12114D03*
X849810Y-4100D03*
X853543Y-9901D03*
X856189Y12114D03*
Y-4100D03*
X853543Y17157D03*
X910432Y-3700D03*
X870275Y65699D03*
X860036Y68550D03*
X865110Y68340D03*
X853543Y54957D03*
X856189Y49914D03*
X876968Y54957D03*
X849896Y49914D03*
X873621Y34100D03*
X870275Y54957D03*
X873621Y49914D03*
X860010Y52100D03*
X865110Y52314D03*
X860010Y49500D03*
X865110Y49714D03*
X859986Y54700D03*
X870275Y36049D03*
X865136Y35750D03*
X865086Y46900D03*
X876968Y46914D03*
Y36049D03*
X873621Y67749D03*
Y52614D03*
X860010Y46898D03*
X860036Y65950D03*
X865123Y65736D03*
X849810Y67749D03*
X856189Y67900D03*
X853393Y46914D03*
X870275D03*
X865110Y54914D03*
X860010Y35999D03*
X856189Y52614D03*
X853543Y36049D03*
X849846Y52514D03*
X853543Y65699D03*
X876968D03*
Y84714D03*
Y73849D03*
X873621Y90414D03*
X870275Y73849D03*
X853543D03*
X860010Y73799D03*
X849846Y90314D03*
X856189Y90414D03*
X865110Y92714D03*
X870275Y84714D03*
X865086Y84700D03*
X853393Y84714D03*
X860010Y84698D03*
X859986Y92500D03*
X865136Y73550D03*
X856189Y71500D03*
X853543Y92757D03*
X856189Y87714D03*
X876968Y92757D03*
X849810Y71500D03*
X849896Y87714D03*
X873621Y71900D03*
X870275Y92761D03*
X873621Y87714D03*
X860010Y89900D03*
X865110Y70949D03*
Y87514D03*
X860010Y71199D03*
Y87300D03*
X865110Y90114D03*
X883661Y54957D03*
X886707Y49914D03*
X910432Y34100D03*
X907086Y54957D03*
X910432Y49914D03*
X896821Y52100D03*
X901921Y49714D03*
X896821Y49500D03*
X901921Y52314D03*
X910432Y67749D03*
X893000Y67900D03*
X901934Y65736D03*
X896847Y65950D03*
X910432Y52614D03*
X890204Y46914D03*
X896821Y35999D03*
X901921Y54914D03*
X896797Y54700D03*
X883661Y35999D03*
X886621Y67749D03*
X880314D03*
X883661Y46914D03*
X880314Y52614D03*
X886657Y52514D03*
X901947Y35750D03*
X901897Y46900D03*
X896821Y46898D03*
X893000Y52614D03*
X890354Y36049D03*
X907086D03*
X883661Y73799D03*
X910432Y90414D03*
X907086Y84714D03*
X901897Y84700D03*
X880314Y71900D03*
Y87714D03*
X893000Y71500D03*
X890354Y92757D03*
X893000Y87714D03*
X886621Y71500D03*
X883661Y92757D03*
X886707Y87714D03*
X910432Y71900D03*
X907086Y92757D03*
X910432Y87714D03*
X896821Y89900D03*
X901921Y70949D03*
Y87514D03*
X896821Y71199D03*
Y87300D03*
X901921Y90114D03*
X907086Y46914D03*
X890354Y65699D03*
X883661D03*
X907086D03*
X896847Y68550D03*
X901921Y68340D03*
X880314Y34100D03*
Y49914D03*
X890354Y54957D03*
X893000Y49914D03*
X896821Y84698D03*
X893000Y90414D03*
X890204Y84714D03*
X896797Y92500D03*
X901921Y92714D03*
X890354Y73849D03*
X896821Y73799D03*
X901947Y73550D03*
X907086Y73849D03*
X883661Y84714D03*
X886657Y90314D03*
X880314Y90414D03*
X886657Y109884D03*
X907086Y104284D03*
X901934Y105051D03*
X896847Y105265D03*
X890354Y112327D03*
X893000Y106934D03*
X883661Y112327D03*
X886707Y107284D03*
X907086Y112327D03*
X910432Y107284D03*
X896821Y110514D03*
X901921Y107655D03*
X896847Y107865D03*
X901947Y110264D03*
X890204Y104284D03*
X893000Y109534D03*
X896821Y113114D03*
X901947Y112865D03*
X910432Y109984D03*
X883661Y104284D03*
X882008Y321100D03*
X851430Y367468D03*
X849896Y513114D03*
X870275Y518161D03*
X873621Y513114D03*
X860010Y515300D03*
X865110Y512914D03*
X860010Y512700D03*
X865110Y515514D03*
X873621Y515814D03*
X876968Y510114D03*
X870275D03*
X859986Y517900D03*
X865086Y510100D03*
X860010Y510098D03*
X865110Y518114D03*
X853393Y510114D03*
X856189Y515814D03*
X849846Y515714D03*
X853543Y518157D03*
X856189Y513114D03*
X876968Y518157D03*
X910432Y513114D03*
X896821Y515300D03*
X901921Y512914D03*
X896821Y512700D03*
X901921Y515514D03*
X907000Y495800D03*
X882900Y495900D03*
X893000Y493094D03*
X886500Y493400D03*
X910432Y491044D03*
X901921Y490514D03*
X896785D03*
X901921Y498514D03*
X896785D03*
X889100Y498500D03*
X901897Y510100D03*
X893000Y515814D03*
X890204Y510114D03*
X896821Y510098D03*
X901921Y518114D03*
X896797Y517900D03*
X880314Y515814D03*
X886657Y515714D03*
X883661Y510114D03*
X910432Y515814D03*
X907086Y510114D03*
X880314Y513114D03*
X890354Y518157D03*
X893000Y513114D03*
X883661Y518157D03*
X907086D03*
X886500Y490800D03*
X882900Y498500D03*
X896836Y493209D03*
X901921Y493214D03*
X910432Y493744D03*
X901921Y495814D03*
X896836Y495909D03*
X907086Y498487D03*
X893000Y495694D03*
X889200Y495900D03*
X886707Y513114D03*
X849810Y534700D03*
X873621Y535100D03*
X860036Y531750D03*
X865110Y534149D03*
Y531540D03*
X856189Y550914D03*
X849896D03*
X873621D03*
X860010Y553100D03*
X865110Y550714D03*
X860010Y550500D03*
X865110Y553314D03*
X860010Y536999D03*
X865123Y528936D03*
X873621Y530949D03*
Y553614D03*
X876968Y537049D03*
Y547914D03*
X860010Y547898D03*
X870275Y547914D03*
X853393D03*
X865086Y547900D03*
X856189Y553614D03*
X849846Y553514D03*
X870275Y537049D03*
X853543D03*
X856189Y531100D03*
X849810Y530949D03*
X865136Y536750D03*
X860036Y529150D03*
X856189Y534700D03*
X853543Y528899D03*
X876968D03*
X849810Y568749D03*
X865086Y585700D03*
X860010Y585698D03*
X865136Y574550D03*
X853543Y555957D03*
X856189Y572500D03*
X853543Y566699D03*
X876968Y555957D03*
Y566699D03*
X870275Y555961D03*
X873621Y572900D03*
X870275Y566699D03*
X860036Y569550D03*
X865110Y571949D03*
Y569340D03*
X856189Y588714D03*
X849896D03*
X873621D03*
X865110Y588514D03*
X860010Y588300D03*
X859986Y555700D03*
X865110Y555914D03*
X860010Y574799D03*
X853393Y585714D03*
X870275D03*
X873621Y568749D03*
X876968Y574849D03*
Y585714D03*
X860036Y566950D03*
X865123Y566736D03*
X870275Y574849D03*
X853543D03*
X856189Y568900D03*
X907086Y528899D03*
X896847Y531750D03*
X896821Y534399D03*
X901921Y531540D03*
X880314Y550914D03*
X890354Y537049D03*
X893000Y531100D03*
X896821Y536999D03*
X901934Y528936D03*
X901947Y536750D03*
X910432Y530949D03*
X907086Y537049D03*
X886621Y530949D03*
X883661Y536999D03*
X880314Y530949D03*
Y553614D03*
X886657Y553514D03*
X883661Y547914D03*
X893000Y553614D03*
X910432D03*
X890204Y547914D03*
X896821Y547898D03*
X901897Y547900D03*
X907086Y547914D03*
X880314Y535100D03*
X893000Y534700D03*
X890354Y528899D03*
X886621Y534700D03*
X880314Y568749D03*
X886621D03*
X883661Y574799D03*
Y585714D03*
X880314Y572900D03*
Y588714D03*
X893000D03*
X886707D03*
X896821Y588300D03*
X901921Y555914D03*
X896797Y555700D03*
X901934Y566736D03*
X896847Y566950D03*
X901897Y585700D03*
X890354Y574849D03*
X896821Y574799D03*
X893000Y568900D03*
X901947Y574550D03*
X896821Y585698D03*
X890204Y585714D03*
X910432Y568749D03*
X907086Y574849D03*
Y585714D03*
X901921Y588514D03*
X910432Y588714D03*
X886707Y550914D03*
X883661Y566699D03*
Y555957D03*
X901921Y553314D03*
X896821Y550500D03*
X901921Y550714D03*
X896821Y553100D03*
X910432Y550914D03*
X893000D03*
X901921Y571949D03*
X896847Y569550D03*
X907086Y566699D03*
X910432Y572900D03*
X907086Y555957D03*
X890354Y566699D03*
X893000Y572500D03*
X890354Y555957D03*
X883661Y528899D03*
X870275D03*
X860010Y534399D03*
X849810Y572500D03*
X860010Y572199D03*
X910432Y535100D03*
X901921Y534149D03*
X886621Y572500D03*
X901921Y569340D03*
X896821Y572199D03*
X890354Y612649D03*
X896821Y612599D03*
X883661D03*
X907086Y612649D03*
X870275D03*
X876968D03*
X860010Y612599D03*
X853543Y612649D03*
Y593757D03*
X856189Y610300D03*
X853543Y604499D03*
X876968Y593757D03*
Y604499D03*
X849810Y610300D03*
X870275Y593761D03*
X873621Y610700D03*
X870275Y604499D03*
X860010Y590900D03*
X860036Y607350D03*
X865110Y609749D03*
X860010Y609999D03*
X865110Y591114D03*
X859986Y593500D03*
X865110Y593714D03*
X856189Y591414D03*
X849846Y591314D03*
X860036Y604750D03*
X865123Y604536D03*
X856189Y606700D03*
X849810Y606549D03*
X865136Y612350D03*
X873621Y606549D03*
Y591414D03*
X886657Y591314D03*
X896847Y604750D03*
X901934Y604536D03*
X880314Y610700D03*
X893000Y610300D03*
X890354Y593757D03*
Y604499D03*
X886621Y610300D03*
X883661Y593757D03*
X896847Y607350D03*
X896821Y590900D03*
Y609999D03*
X901921Y591114D03*
X901947Y612350D03*
X896797Y593500D03*
X901921Y593714D03*
X893000Y591414D03*
X910432D03*
Y606549D03*
X893000Y606700D03*
X880314Y606549D03*
X886621D03*
X880314Y591414D03*
X901921Y609749D03*
X907086Y604499D03*
Y593757D03*
X910432Y610700D03*
X865110Y607140D03*
X883661Y604499D03*
X901921Y607140D03*
X923432Y-7851D03*
X929811Y-7700D03*
X933658Y-9650D03*
X917125Y-7851D03*
X913779Y-1751D03*
X933632Y-1801D03*
X927165Y-1751D03*
X920472Y-1801D03*
X927015Y9114D03*
X933632Y9098D03*
X913779Y9114D03*
X920472D03*
X933658Y-7050D03*
X933632Y-4401D03*
X929811Y-4100D03*
X927165Y-9901D03*
X923432Y-4100D03*
X920472Y-9901D03*
X933658Y30750D03*
X933632Y33399D03*
X929811Y33700D03*
X927165Y27899D03*
X923432Y33700D03*
X920472Y27899D03*
X933632Y14300D03*
Y11700D03*
X927165Y17157D03*
X929811Y12114D03*
X920472Y17157D03*
X923518Y12114D03*
X923432Y29949D03*
X917125D03*
Y14814D03*
X929811D03*
X933608Y16900D03*
X923468Y14714D03*
X933658Y28150D03*
X929811Y30100D03*
X913779Y27899D03*
X938745Y-9864D03*
X938758Y-2050D03*
X938708Y9100D03*
X947243Y-7851D03*
X950590Y-1751D03*
X957283Y-1843D03*
X953936Y-7851D03*
X943897Y-1751D03*
Y9114D03*
X950590D03*
X957765Y-7180D03*
X938732Y-7260D03*
Y-4651D03*
X953936Y-3700D03*
X950590Y-9901D03*
X947243Y-3700D03*
X943897Y-9901D03*
X960629Y-9786D03*
X963976Y-1843D03*
X970669Y-1743D03*
X967322Y-9786D03*
X963976Y9114D03*
X970669D03*
X967322Y-4536D03*
X938732Y33149D03*
Y30540D03*
X950590Y27899D03*
X943897D03*
X938732Y14514D03*
Y11914D03*
X950590Y17157D03*
X953936Y12114D03*
X943897Y17157D03*
X947243Y12114D03*
X967322Y28014D03*
X960629Y17057D03*
Y28014D03*
X967322Y17057D03*
X938745Y27936D03*
X938732Y17114D03*
X957283Y9300D03*
X953936Y14814D03*
Y29949D03*
X957600Y13200D03*
X957700Y32100D03*
X970800Y13200D03*
X970942Y32100D03*
X947243Y29949D03*
Y14814D03*
X913779Y-9901D03*
X917125Y-3700D03*
Y12114D03*
X913779Y17157D03*
X960629Y-4536D03*
X963976Y-7108D03*
X970669D03*
X933632Y52100D03*
Y49500D03*
X927165Y54957D03*
X929811Y49914D03*
X920472Y54957D03*
X923518Y49914D03*
X933658Y65950D03*
X923432Y67749D03*
X929811Y67900D03*
X917125Y67749D03*
X920472Y35999D03*
X917125Y52614D03*
X913779Y46914D03*
Y36049D03*
X927015Y73849D03*
X913779D03*
X920472Y73799D03*
X933632D03*
X913779Y84714D03*
X920472D03*
X933608Y92500D03*
X917125Y71900D03*
X913779Y92757D03*
X917125Y87714D03*
X933632Y89900D03*
Y71199D03*
Y87300D03*
X929811Y71500D03*
X927165Y92757D03*
X920472Y46914D03*
X933632Y35999D03*
X927165Y36049D03*
X927015Y46914D03*
X933608Y54700D03*
X933632Y46898D03*
X929811Y52614D03*
X913779Y65699D03*
X933658Y68550D03*
X927165Y65699D03*
X920472D03*
X913779Y54957D03*
X917125Y34100D03*
Y49914D03*
X929811Y87714D03*
X923432Y71500D03*
X920472Y92757D03*
X923518Y87714D03*
X933632Y84698D03*
X927015Y84714D03*
X923468Y90314D03*
X929811Y90414D03*
X917125D03*
X953936Y52614D03*
X957558Y50729D03*
X938732Y68340D03*
X950590Y65699D03*
X943897D03*
X938732Y49714D03*
Y52314D03*
X953936Y34100D03*
X950590Y54957D03*
X953936Y49914D03*
X947243Y34100D03*
X943897Y54957D03*
X947243Y49914D03*
X967322Y65814D03*
X960629D03*
X970669Y35957D03*
Y46914D03*
X967322Y54857D03*
X963976Y35957D03*
Y46914D03*
X960629Y54857D03*
X938758Y35750D03*
X938708Y46900D03*
X938732Y54914D03*
X938745Y65736D03*
X950590Y36049D03*
X953936Y67749D03*
X950590Y46914D03*
X970800Y50860D03*
X947243Y67749D03*
X943897Y36049D03*
Y46914D03*
X947243Y52614D03*
X957283Y35957D03*
X947243Y87714D03*
X963976Y73757D03*
X960629Y89964D03*
X963976Y87392D03*
X967322Y89964D03*
X970669Y87392D03*
Y73757D03*
X967322Y84714D03*
X938708Y84700D03*
X938732Y92714D03*
X938758Y73550D03*
X957600Y70400D03*
X970942Y69900D03*
X943897Y84714D03*
X947243Y90414D03*
X943897Y73849D03*
X950590D03*
X953886Y90414D03*
X950590Y84714D03*
X957774Y87394D03*
X957200Y73800D03*
X957283Y92657D03*
X938732Y70949D03*
Y87514D03*
Y90114D03*
X953936Y71900D03*
X950590Y92757D03*
X953936Y87714D03*
X947243Y71900D03*
X943897Y92757D03*
X960629Y84714D03*
X963976Y92657D03*
X970669Y92757D03*
X933658Y105265D03*
X913779Y112327D03*
X917125Y107284D03*
X933632Y110514D03*
X933658Y107865D03*
X927165Y112327D03*
X929811Y106934D03*
X920472Y112327D03*
X923518Y107284D03*
X929811Y109534D03*
X933632Y113114D03*
X923468Y109884D03*
X917125Y109984D03*
X920472Y104284D03*
X913779D03*
X927015D03*
X938732Y107655D03*
X938758Y110264D03*
X950590Y109700D03*
X953786Y107684D03*
X944497Y110927D03*
X947243Y105084D03*
X963245Y105725D03*
X938758Y112865D03*
X938745Y105051D03*
X947250Y107700D03*
X950600Y112300D03*
X953800Y105000D03*
X944507Y205210D03*
Y209109D03*
X937747Y213009D03*
Y205210D03*
X917467Y209109D03*
X920847Y203260D03*
X927607D03*
Y207159D03*
X934367D03*
Y199360D03*
X930987Y201309D03*
X934367Y214960D03*
X930987Y213009D03*
X920847Y211060D03*
X927607Y214960D03*
Y211060D03*
X937747Y216909D03*
X924227D03*
Y213009D03*
X920847Y207159D03*
X927607Y218860D03*
X934367D03*
X930987Y205210D03*
X968166Y218860D03*
X951256Y194841D03*
X958026Y201309D03*
X967036Y193507D03*
X947887Y203260D03*
Y207159D03*
X944507Y213009D03*
Y201309D03*
X947887Y199360D03*
X941127D03*
Y207159D03*
X947887Y211060D03*
Y218860D03*
X941127D03*
Y214960D03*
X947887D03*
X954647D03*
X962526Y205210D03*
X961406Y214960D03*
Y211060D03*
Y218860D03*
X951267Y209109D03*
X958026Y213009D03*
X954647Y211060D03*
Y218860D03*
X941127Y203260D03*
Y211060D03*
X964786Y213009D03*
Y216909D03*
Y209109D03*
X971546Y252009D03*
X937747Y240309D03*
X930987Y244209D03*
X934367Y226660D03*
X924227Y236409D03*
X920847Y238360D03*
X913787Y226660D03*
X913700Y222710D03*
X913787Y238360D03*
X924227Y232509D03*
X927607Y230559D03*
Y234460D03*
X930987Y232509D03*
X934367Y234460D03*
X924227Y228610D03*
X930987Y220809D03*
X924227Y224709D03*
X937747Y232509D03*
Y236409D03*
X924227Y240309D03*
X917467D03*
X930987D03*
X924227Y248109D03*
Y244209D03*
X917467D03*
X913787Y250060D03*
X934367Y246160D03*
X927607Y250060D03*
X924227Y220809D03*
X937747Y224709D03*
X934367Y230559D03*
X913787Y246160D03*
X920847D03*
X937747Y220809D03*
X930987Y224709D03*
Y236409D03*
X937747Y248109D03*
X927607Y242260D03*
X937747Y279310D03*
X917000Y276000D03*
X920847Y277360D03*
X924227Y279310D03*
X913787Y273460D03*
Y253960D03*
X927607D03*
X934367D03*
X937747Y252009D03*
X930987D03*
X924227D03*
X917467D03*
Y259809D03*
X924227D03*
X930987D03*
X920847Y265660D03*
X930987Y275409D03*
X937747D03*
Y271509D03*
Y255909D03*
X934367Y277360D03*
X930987Y271509D03*
X934367Y273460D03*
X927607Y269560D03*
X917467Y263709D03*
X913787Y265660D03*
X924227Y267609D03*
X934367Y265660D03*
X924227Y263709D03*
Y275409D03*
X927607Y277360D03*
X920847Y273460D03*
Y269560D03*
X924227Y255909D03*
X920847Y257860D03*
X913787Y261760D03*
X917467Y255909D03*
X930987Y267609D03*
X937747Y263709D03*
X927607Y257860D03*
X934367D03*
X927607Y265660D03*
X916967Y279310D03*
X930987D03*
X951267Y248109D03*
X958026Y244209D03*
X968166Y242260D03*
X944507Y228610D03*
Y224709D03*
Y244209D03*
Y248109D03*
X941127Y242260D03*
Y250060D03*
Y246160D03*
X947887D03*
X941127Y222760D03*
X947887Y226660D03*
Y234460D03*
X941127Y238360D03*
Y234460D03*
Y230559D03*
Y226660D03*
X971546Y248109D03*
X968166Y246160D03*
X958026Y220809D03*
X944507D03*
X951267Y224709D03*
Y240309D03*
X958026D03*
X964786D03*
X954647Y246160D03*
Y250060D03*
X958026Y228610D03*
Y236409D03*
X961406Y238360D03*
X951267Y228610D03*
X954647Y226660D03*
X958026Y224709D03*
Y232509D03*
X954647Y230559D03*
X961406Y222760D03*
X968166Y226660D03*
X971546Y236409D03*
X968166Y238360D03*
X971546Y220809D03*
X964786Y232509D03*
Y220809D03*
X944507Y279310D03*
X947887Y253960D03*
X941127D03*
X958026Y252009D03*
X968166Y277360D03*
X951267Y275409D03*
X961406Y277360D03*
X958026Y263709D03*
X968166Y269560D03*
X961406Y261760D03*
X958026Y255909D03*
X951267Y259809D03*
X958026D03*
X954647Y277360D03*
Y265660D03*
X951267Y267609D03*
X954647Y273460D03*
X958026Y275409D03*
X954647Y269560D03*
X961406D03*
X971546Y275409D03*
Y263709D03*
X941127Y277360D03*
Y265660D03*
X944507Y275409D03*
Y263709D03*
X941127Y269560D03*
Y257860D03*
Y261760D03*
X947887Y277360D03*
Y265660D03*
X971546Y259809D03*
Y255909D03*
X964786Y279310D03*
Y267609D03*
Y271509D03*
X961406Y273460D03*
X971546Y267609D03*
X958026D03*
Y279310D03*
X951267D03*
X947887Y230559D03*
X971546Y224709D03*
X944507Y236409D03*
X954647Y242260D03*
X947887Y261760D03*
X951267Y236409D03*
X947887Y238360D03*
X951267Y255909D03*
X971546Y232509D03*
X947887Y242260D03*
X944507Y255909D03*
X964786Y224709D03*
X961406Y230559D03*
X971546Y341709D03*
X944507Y326110D03*
X937747Y287109D03*
X920500Y304660D03*
Y300760D03*
X930987Y302709D03*
X924227D03*
X920500Y311960D03*
X927607Y304660D03*
X924227Y306609D03*
X930987D03*
Y310509D03*
X934367Y304660D03*
X924227Y310509D03*
X920500Y308560D03*
Y289060D03*
X934367Y296860D03*
X930987Y294909D03*
X920500Y296860D03*
Y292959D03*
X927607Y296860D03*
X924227Y298809D03*
X930987D03*
X924227Y283209D03*
X927607Y281260D03*
X920500Y285500D03*
X924227Y287109D03*
X920847Y281260D03*
X930987Y287109D03*
X934367Y289060D03*
Y285160D03*
Y300760D03*
X927607D03*
Y308560D03*
X934367D03*
X927607Y285160D03*
Y292959D03*
X934367D03*
Y281260D03*
X930987Y283209D03*
X924227Y291009D03*
X930987D03*
X927607Y289060D03*
X937747Y302709D03*
Y306609D03*
Y310509D03*
Y283209D03*
Y291009D03*
Y294909D03*
Y298809D03*
X920847Y335860D03*
X913787Y331960D03*
X917467Y337809D03*
X937747Y333909D03*
X927607Y339760D03*
X934367Y328060D03*
Y339760D03*
X927607Y331960D03*
X930987Y333909D03*
X937747Y337809D03*
Y314409D03*
X924227D03*
X930987D03*
X934367Y312460D03*
X927607D03*
X920847Y324160D03*
X924227Y318309D03*
X920547Y316160D03*
X917167Y318309D03*
Y322209D03*
X917467Y326110D03*
X920847Y320260D03*
X937747Y318309D03*
Y341709D03*
Y326110D03*
X917467Y333909D03*
Y341709D03*
X913787Y339760D03*
X924227Y333909D03*
Y337809D03*
Y341709D03*
X913787Y328060D03*
X924227Y330009D03*
X920847Y328060D03*
X917467Y330009D03*
X930987Y326110D03*
X934367Y331960D03*
X927607Y328060D03*
X934367Y324160D03*
X924227Y322209D03*
X927607Y320260D03*
X930987Y318309D03*
X934367Y316360D03*
X927607D03*
X930987Y337809D03*
X924227Y326110D03*
X971546Y294909D03*
X944507Y283209D03*
X961406Y292959D03*
Y285160D03*
X954647Y292959D03*
Y285160D03*
X968166Y292959D03*
Y300760D03*
X971546Y310509D03*
X964786D03*
X954647Y308560D03*
X961406D03*
X954647Y300760D03*
X961406D03*
X964786Y283209D03*
X971546D03*
X947887Y308560D03*
X941127D03*
Y300760D03*
X947887D03*
X941127Y285160D03*
Y292959D03*
X947887D03*
Y285160D03*
X968166Y281260D03*
X964786Y291009D03*
X954647Y281260D03*
X958026Y283209D03*
X951267Y287109D03*
X958026D03*
X951267Y283209D03*
X961406Y281260D03*
Y296860D03*
X964786Y298809D03*
Y302709D03*
X971546D03*
X961406Y304660D03*
X958026Y302709D03*
X951267D03*
X968166Y308560D03*
X964786Y306609D03*
X968166Y304660D03*
X971546Y306609D03*
X951267Y310509D03*
X954647Y304660D03*
X958026Y306609D03*
Y310509D03*
X951267Y306609D03*
X944507Y302709D03*
Y306609D03*
Y310509D03*
X941127Y304660D03*
X947887D03*
X944507Y294909D03*
Y287109D03*
X971546Y298809D03*
X968166Y285160D03*
X964786Y287109D03*
X944507Y291009D03*
X941127Y281260D03*
Y289060D03*
Y296860D03*
X944507Y298809D03*
X947887Y289060D03*
Y296860D03*
Y281260D03*
X968166Y296860D03*
X964786Y294909D03*
X971546Y291009D03*
Y287109D03*
X968166Y289060D03*
X961406D03*
X958026Y298809D03*
X951267D03*
Y291009D03*
X958026D03*
X954647Y289060D03*
Y296860D03*
X958026Y294909D03*
X951267D03*
X958026Y333909D03*
Y337809D03*
Y341709D03*
Y318309D03*
X951267D03*
X954647Y316360D03*
X961406D03*
Y324160D03*
X971546Y337809D03*
X964786Y330009D03*
X971546D03*
X951267D03*
X958026D03*
X954647Y339760D03*
X951267Y333909D03*
X944507Y337809D03*
X968166Y312460D03*
X964786Y314409D03*
X951267Y337809D03*
X954647Y331960D03*
Y328060D03*
X971546Y322209D03*
X968166Y320260D03*
X964786Y322209D03*
X968166Y335860D03*
X947887Y339760D03*
X944507Y314409D03*
X951267D03*
X958026D03*
X961406Y312460D03*
X954647D03*
X941127D03*
X947887D03*
X971546Y314409D03*
Y318309D03*
X964786D03*
X951267Y322209D03*
X954647Y324160D03*
X961406Y320260D03*
X954647D03*
X958026Y322209D03*
X951267Y326110D03*
X968166Y316360D03*
X958026Y326110D03*
X947887Y316360D03*
X941127D03*
X944507Y322209D03*
Y318309D03*
X947887Y331960D03*
Y328060D03*
X941127Y331960D03*
Y328060D03*
Y339760D03*
Y335860D03*
X944507Y333909D03*
X968166Y328060D03*
Y324160D03*
X964786Y333909D03*
X961406Y328060D03*
X971546Y333909D03*
X930987Y369010D03*
X937747D03*
X913787Y347560D03*
X920847Y343660D03*
X934367Y359260D03*
X930987Y361209D03*
X937747Y349509D03*
X927607Y355360D03*
X937747Y353409D03*
X930987Y349509D03*
X937747Y357309D03*
X930987Y353409D03*
X937747Y365109D03*
Y345609D03*
Y361209D03*
X924227Y365109D03*
X930987D03*
X927607Y367060D03*
X934367Y370959D03*
Y363160D03*
X927607D03*
X924227Y369010D03*
X913787Y343660D03*
X934367D03*
X927607D03*
Y347560D03*
X934367Y351460D03*
X930987Y357309D03*
Y345609D03*
X917467Y353409D03*
Y349509D03*
X913787Y355360D03*
X924227Y349509D03*
Y345609D03*
Y353409D03*
Y361209D03*
Y357309D03*
X920847Y355360D03*
X917167Y361209D03*
Y369010D03*
X920847Y347560D03*
X934367Y382660D03*
X930987Y384609D03*
Y376809D03*
X934367Y390460D03*
X927607Y386560D03*
Y390460D03*
X930987Y396309D03*
X934367Y398260D03*
X927607Y394359D03*
X917467Y388509D03*
X924227Y392410D03*
X920847Y390460D03*
X930987Y380709D03*
X927607Y374860D03*
X934367D03*
X937747Y376809D03*
X930987Y372909D03*
X934367Y394359D03*
X930987Y388509D03*
X937747D03*
Y384609D03*
Y392410D03*
X924227Y400209D03*
X920847Y394359D03*
Y398260D03*
X927607D03*
X924227Y372909D03*
X937747Y400209D03*
X917100Y380709D03*
X937747D03*
X924227D03*
X920847Y382660D03*
X924227Y376809D03*
X927607Y382660D03*
X968166Y370959D03*
X958026Y361209D03*
X954647Y347560D03*
X961406Y359260D03*
X958026Y357309D03*
X951267D03*
X941127Y355360D03*
Y347560D03*
Y351460D03*
X958026Y345609D03*
X951267Y349509D03*
X954647Y351460D03*
X958026Y353409D03*
X968166Y355360D03*
Y351460D03*
X971546Y353409D03*
X947887Y367060D03*
X954647Y355360D03*
X944507Y361209D03*
X968166Y363160D03*
X961406D03*
X971546Y369010D03*
X944507Y345609D03*
X951267D03*
X947887Y355360D03*
X951267Y361209D03*
X968166Y367060D03*
X964786Y357309D03*
X971546Y361209D03*
X968166Y359260D03*
X958026Y365109D03*
X964786D03*
X954647Y370959D03*
Y367060D03*
X958026Y369010D03*
X951267D03*
X961406Y370959D03*
X954647Y363160D03*
X947887Y359260D03*
X964786Y369010D03*
X954647Y343660D03*
X971546Y349509D03*
X947887Y363160D03*
X941127D03*
X947887Y370959D03*
X941127D03*
Y367060D03*
X944507Y369010D03*
X947887Y343660D03*
X941127Y359260D03*
X944507Y349509D03*
Y353409D03*
X941127Y343660D03*
X947887Y351460D03*
X964786Y349509D03*
Y353409D03*
X961406Y355360D03*
Y347560D03*
Y351460D03*
X958026Y380709D03*
X954647Y374860D03*
X951267Y376809D03*
Y384609D03*
Y380709D03*
X944507Y388509D03*
X941127Y394359D03*
X968166Y374860D03*
X958026Y372909D03*
X941127Y374860D03*
X961406D03*
X944507Y372909D03*
X941127Y382660D03*
Y378760D03*
X947887D03*
X944507Y384609D03*
X947887Y390460D03*
Y386560D03*
X941127Y390460D03*
X947887Y398260D03*
X941127D03*
X944507Y396309D03*
X947887Y394359D03*
X964786Y376809D03*
X971546D03*
X968166Y378760D03*
Y386560D03*
X964786Y392410D03*
X968166Y390460D03*
Y394359D03*
X964786Y388509D03*
X961406Y378760D03*
X954647D03*
X958026Y384609D03*
X961406Y382660D03*
X951267Y388509D03*
X958026D03*
X954647Y394359D03*
X961406Y386560D03*
X952216Y402421D03*
X970416Y401941D03*
X971546Y380709D03*
X968166Y382660D03*
X947887Y374860D03*
X944507Y380709D03*
X933632Y515300D03*
Y512700D03*
X927165Y518157D03*
X929811Y513114D03*
X920472Y518157D03*
X923518Y513114D03*
X920700Y495944D03*
X913800Y495800D03*
X927165Y495944D03*
X929811Y515814D03*
X933632Y510098D03*
X923600Y491144D03*
X917192Y491219D03*
X933632Y490644D03*
X929811D03*
X933632Y498644D03*
X933608Y517900D03*
X913779Y510114D03*
X917125Y515814D03*
X923468Y515714D03*
X920472Y510114D03*
X927015D03*
X913779Y518157D03*
X917125Y513114D03*
X938732Y490644D03*
X950700Y490700D03*
X943897Y490444D03*
X970669Y512792D03*
X967322Y515364D03*
X963976Y512792D03*
X960629Y515364D03*
X967322Y510114D03*
X938708Y510100D03*
X938732Y518114D03*
Y498644D03*
X954000Y497300D03*
X953886Y515814D03*
X950590Y510114D03*
X943897D03*
X947243Y515814D03*
X947443Y497644D03*
X957774Y512794D03*
X957283Y518057D03*
X938732Y512914D03*
Y515514D03*
X943897Y518157D03*
X947243Y513114D03*
X961309Y499136D03*
X947443Y494944D03*
X944000Y493100D03*
X923600Y493744D03*
X929811Y493244D03*
X933647Y493344D03*
X938732D03*
X917192Y493919D03*
X920700Y498644D03*
X927165D03*
X938732Y495944D03*
X933647D03*
X913779Y498487D03*
X954000Y494700D03*
X950700Y493300D03*
X960629Y510114D03*
X963976Y518057D03*
X970669Y518157D03*
X953936Y513114D03*
X950590Y518157D03*
X933658Y531750D03*
X929811Y534700D03*
X927165Y528899D03*
X923432Y534700D03*
X920472Y528899D03*
X933632Y536999D03*
X929811Y531100D03*
X933658Y529150D03*
X913779Y537049D03*
X917125Y530949D03*
X927015Y537049D03*
X923432Y530949D03*
X920472Y536999D03*
X923468Y553514D03*
X917125Y553614D03*
X913779Y547914D03*
X927015D03*
X920472D03*
X933632Y547898D03*
X929811Y553614D03*
X917125Y535100D03*
X913779Y528899D03*
X933608Y555700D03*
X933632Y585698D03*
X933658Y566950D03*
X929811Y568900D03*
X933632Y574799D03*
X920472D03*
X927015Y585714D03*
X920472D03*
X913779Y574849D03*
X917125Y568749D03*
X913779Y585714D03*
X923432Y568749D03*
X927015Y574849D03*
X960629Y529014D03*
X963976Y536957D03*
X970669D03*
X967322Y529014D03*
X963976Y547914D03*
X970669D03*
X938745Y528936D03*
X938758Y536750D03*
X938708Y547900D03*
X957600Y533100D03*
X970942D03*
X957701Y552000D03*
X970731D03*
X950590Y537049D03*
X957283Y536957D03*
X953936Y530949D03*
X957283Y548200D03*
X953886Y553614D03*
X950590Y547914D03*
X947243Y530949D03*
X943897Y537049D03*
Y547914D03*
X947243Y553614D03*
X938732Y534149D03*
Y531540D03*
X947243Y535100D03*
X953936Y588714D03*
X967322Y555857D03*
X960629D03*
X970669Y585714D03*
Y574757D03*
X960629Y566814D03*
X963976Y585714D03*
Y574757D03*
X967322Y566814D03*
X938732Y555914D03*
X938745Y566736D03*
X938758Y574550D03*
X938708Y585700D03*
X957600Y570900D03*
X970942D03*
X950590Y574849D03*
Y585714D03*
X957283Y574757D03*
X957456Y588334D03*
X953936Y568749D03*
X943897Y574849D03*
X947243Y568749D03*
X943897Y585714D03*
X938732Y588514D03*
X933632Y588300D03*
X929811Y588714D03*
X923518D03*
X947243D03*
Y550914D03*
X923518D03*
X929811D03*
X938732Y553314D03*
X933632Y550500D03*
X938732Y550714D03*
X933632Y553100D03*
X917125Y550914D03*
X943897Y566699D03*
X947243Y572900D03*
X943897Y555957D03*
X920472Y566699D03*
X923432Y572500D03*
X920472Y555957D03*
X927165Y566699D03*
X929811Y572500D03*
X927165Y555957D03*
X938732Y571949D03*
X933658Y569550D03*
X913779Y555957D03*
X953936Y550914D03*
Y572900D03*
X950590Y555957D03*
X917125Y588714D03*
X950590Y528899D03*
X953936Y535100D03*
X933632Y534399D03*
X943897Y528899D03*
X938732Y569340D03*
X933632Y572199D03*
X913779Y566699D03*
X917125Y572900D03*
X950590Y566699D03*
X963976Y566814D03*
X960629Y574757D03*
Y536957D03*
X970669Y529014D03*
X933632Y612599D03*
X923432Y606549D03*
X917125D03*
X933658Y604750D03*
X917125Y610700D03*
X913779Y593757D03*
X929811Y610300D03*
X927165Y593757D03*
X923468Y591314D03*
X917125Y591414D03*
X933608Y593500D03*
X929811Y591414D03*
X927015Y612449D03*
X920472Y612399D03*
X913779Y612449D03*
X929811Y606700D03*
X950590Y604499D03*
X967322Y593657D03*
X963976Y612457D03*
X970669D03*
X960629Y604614D03*
X967322D03*
X960629Y593657D03*
X967322Y609864D03*
X938758Y612350D03*
X938745Y604536D03*
X938732Y593714D03*
X957500Y591000D03*
X970731Y589800D03*
X953936Y606549D03*
X957283Y611600D03*
X950590Y612249D03*
X953886Y591414D03*
X947243Y606549D03*
X943897Y612249D03*
X947243Y591414D03*
X957765Y607220D03*
X938732Y609749D03*
Y607140D03*
Y591114D03*
X953936Y610700D03*
X950590Y593757D03*
X933632Y590900D03*
Y609999D03*
X927165Y604499D03*
X923432Y610300D03*
X920472Y593757D03*
Y604499D03*
X947243Y610700D03*
X943897Y593757D03*
Y604499D03*
X963976Y607292D03*
X970669D03*
X913779Y604499D03*
X933658Y607350D03*
X960629Y609864D03*
X1025670Y6640D03*
X1023740Y18150D03*
X980708Y-4536D03*
X987401Y-9901D03*
X997441Y-7108D03*
X990748Y-1743D03*
X977362Y-7108D03*
X980708Y9114D03*
X990748Y9122D03*
X977362Y28014D03*
X987401D03*
Y17057D03*
X977362D03*
X997441Y28022D03*
Y17057D03*
X983900Y13200D03*
Y32100D03*
X1028400Y6500D03*
X1030407Y-8938D03*
X1000787Y-4536D03*
Y9122D03*
X1017519Y-1858D03*
Y-9786D03*
X1007480Y-1858D03*
X1007280Y9114D03*
X1017519D03*
X1007480Y-9786D03*
X1020866Y-1858D03*
X1027202Y-11005D03*
X1028639Y-6615D03*
X1008200Y30736D03*
X1014173Y28014D03*
X1010826D03*
X1007480Y17014D03*
Y28014D03*
X1017519D03*
Y17042D03*
X1025291Y20734D03*
X1007100Y11714D03*
X1008227Y33342D03*
X1030400Y26150D03*
X1030450Y23150D03*
X1007100Y14314D03*
X1026700Y1700D03*
X984055Y-7108D03*
X990748D03*
X987401Y-4536D03*
X994094Y-9786D03*
Y-4536D03*
X997441Y-1743D03*
X1000787Y-9901D03*
X1004133Y-1742D03*
X1004134Y-7108D03*
X980708Y-9786D03*
X984055Y-1743D03*
X1010826Y9114D03*
Y-1858D03*
X1012270Y17014D03*
X1010826Y-9786D03*
X1014173Y9114D03*
Y-1858D03*
X1014919Y17042D03*
X1014173Y-9786D03*
X974015Y-4536D03*
Y-9901D03*
X977362Y-1743D03*
X1020650Y46900D03*
X987401Y65814D03*
X977362D03*
X987401Y54857D03*
X977362D03*
X990748Y46922D03*
Y35957D03*
X980708D03*
Y46914D03*
X997441Y65822D03*
Y54857D03*
X983900Y51000D03*
X997441Y92757D03*
X990748Y73757D03*
Y87392D03*
X977362Y92757D03*
X987401Y89964D03*
X980708Y84714D03*
Y73757D03*
X983900Y69900D03*
X1007370Y52333D03*
Y49659D03*
X1014173Y54842D03*
Y35942D03*
X1013873Y46914D03*
X1010826Y54842D03*
Y35942D03*
X1011126Y46914D03*
X1000787Y35957D03*
Y46922D03*
X1017519Y54842D03*
X1007480Y46914D03*
X1008226Y54842D03*
X1008217Y35942D03*
X1007480Y65736D03*
X1016600Y65950D03*
X1017519Y35942D03*
Y46914D03*
X1030300Y63200D03*
X1014350Y73000D03*
X1017919Y92500D03*
X1017519Y87500D03*
X1000787Y84599D03*
Y73757D03*
X1007480Y87500D03*
X1007573Y92500D03*
X1008099Y73479D03*
X1017350Y73450D03*
X1024945Y86377D03*
Y83877D03*
X1007380Y68335D03*
X1030400Y56500D03*
X1031600Y42900D03*
X1007380Y70935D03*
X1023900Y74100D03*
Y77200D03*
X984055Y92757D03*
X990748D03*
X987401Y84599D03*
X994094Y89964D03*
Y84714D03*
X997441Y87392D03*
X1000787Y89964D03*
X1004023Y87392D03*
Y92757D03*
X980708Y89964D03*
X984055Y87392D03*
X974015Y84599D03*
Y89964D03*
X977362Y87392D03*
X1012043Y87500D03*
X1012400Y92500D03*
X1014842Y87500D03*
X1015215Y92500D03*
X976200Y105600D03*
X974100Y103500D03*
X976700Y103021D03*
X995206Y218860D03*
X983936Y199108D03*
X973808Y201308D03*
X998586Y209109D03*
Y216909D03*
X995206Y203260D03*
X988446Y218860D03*
X995206Y214960D03*
X981686Y218860D03*
X974926Y211060D03*
X985066Y216909D03*
X988446Y211058D03*
X979426Y214958D03*
X1012105Y216909D03*
X1008725Y211060D03*
X1001965Y214960D03*
X1027875Y193507D03*
X1032385Y201309D03*
X1015485Y203260D03*
Y214960D03*
X1022245D03*
X1012105Y205210D03*
X1025625Y205211D03*
X1029005Y214960D03*
X1007595Y193507D03*
X1005345Y205210D03*
X1008725Y214960D03*
X1005345Y209109D03*
X1001965Y211060D03*
X1025625Y209109D03*
X1012105D03*
X1032385D03*
X998586Y205210D03*
X991826D03*
X1022245Y211060D03*
X1018865Y216909D03*
X1032385D03*
X995206Y222760D03*
X1022245Y234460D03*
X991826Y240309D03*
X995206Y234460D03*
X1008725D03*
X1032385Y228610D03*
X995206Y238360D03*
X988446Y234460D03*
X998586Y248109D03*
Y220809D03*
X985066Y248109D03*
X981686Y250060D03*
X974926D03*
X988446Y246160D03*
Y250060D03*
Y230560D03*
X978306Y248109D03*
X974926Y238360D03*
X985066Y244209D03*
X981686Y238360D03*
X995206Y230559D03*
X981686Y242260D03*
X974926D03*
X988446D03*
X998586Y244209D03*
Y232509D03*
X991826Y244209D03*
Y232509D03*
X995206Y226660D03*
X991826Y248109D03*
X988446Y238360D03*
X985066Y236409D03*
X981686Y234460D03*
X974926Y226660D03*
X991826Y220809D03*
X974926Y230559D03*
Y234460D03*
Y222760D03*
X985066Y224709D03*
X978306Y232509D03*
Y220809D03*
X974926Y253960D03*
X988446D03*
X978306Y252009D03*
X985066D03*
X974926Y265660D03*
X991826Y259809D03*
X985066D03*
X981686Y269560D03*
X995206D03*
X985066Y267609D03*
X991826Y263709D03*
X988446Y265660D03*
X998586Y263709D03*
X991826Y271509D03*
X995206Y273460D03*
X991826Y279310D03*
Y275409D03*
X974926Y269560D03*
X978306Y267609D03*
Y259809D03*
X991826Y255909D03*
X995206Y265660D03*
X991826Y252009D03*
Y267609D03*
X974926Y273460D03*
X995206Y277360D03*
X998586Y267609D03*
Y271509D03*
Y275409D03*
Y279310D03*
X1029005Y238360D03*
X1015485Y222760D03*
X1008725D03*
X1032385Y232509D03*
X1018865Y244209D03*
X1012105D03*
X1018865Y232509D03*
X1015485Y226660D03*
X1022245D03*
X1012105Y232509D03*
X1025625D03*
X1029005Y226660D03*
X1005345Y244209D03*
X1008725Y226660D03*
X1005345Y232509D03*
X1001965Y226660D03*
X1005345Y248109D03*
X1008725Y238360D03*
X1001965D03*
X1005345Y220809D03*
X1029005Y250060D03*
X1032385Y248109D03*
X1025625D03*
X1022245Y250060D03*
X1025625Y220809D03*
X1012105D03*
X1015485Y238360D03*
X1022245D03*
X1018865Y220809D03*
X1032385D03*
X1001965Y261760D03*
X1012105Y255909D03*
X1022245Y253960D03*
X1025625Y252009D03*
X1017735Y264300D03*
X1014355Y266300D03*
X1021115Y262300D03*
X1024495Y260300D03*
X1027875Y258400D03*
X1031255Y256400D03*
X1005345Y263709D03*
X1001965Y265660D03*
X1009256Y269777D03*
X1008725Y261760D03*
X1006665Y277360D03*
X1006700Y270700D03*
X1006665Y273460D03*
X1011100Y268100D03*
X1015485Y257860D03*
X1018865Y255909D03*
X1012105Y259809D03*
X1015485Y253960D03*
X1018865Y252009D03*
X1005345Y259809D03*
X1008725Y257860D03*
X988446Y261760D03*
X1012105Y228610D03*
X1015485Y234460D03*
X1001965D03*
X998586Y240309D03*
X1001965Y222760D03*
X1025625Y228610D03*
X1005345Y240309D03*
Y228610D03*
X1012105Y240309D03*
X1029005Y234460D03*
X1025625Y240309D03*
X995206Y246160D03*
X1018865Y240309D03*
X981686Y261760D03*
X985066Y255909D03*
X978306D03*
X998586Y341709D03*
X995206Y296860D03*
X985066Y294909D03*
X981686Y281260D03*
Y292959D03*
Y300760D03*
X988446D03*
X978306Y310509D03*
X991826D03*
X985066D03*
X974926Y300760D03*
X988446Y292959D03*
X991826Y283209D03*
X988446Y281260D03*
X985066Y283209D03*
X978306D03*
X974926Y292959D03*
Y281260D03*
X985066Y287109D03*
X988446Y285160D03*
X991826Y287109D03*
X995206Y281260D03*
X978306Y298809D03*
Y287109D03*
X981686Y285160D03*
X978306Y294909D03*
X981686Y296860D03*
Y289060D03*
X978306Y291009D03*
X998586Y302709D03*
Y306609D03*
Y310509D03*
Y287109D03*
Y294909D03*
Y291009D03*
Y298809D03*
Y283209D03*
X985066Y302709D03*
X978306D03*
X988446Y304660D03*
Y308560D03*
X985066Y306609D03*
X995206Y304660D03*
Y308560D03*
X991826Y306609D03*
X978306D03*
X981686Y308560D03*
Y304660D03*
X974926D03*
Y308560D03*
X995206Y300760D03*
X991826Y302709D03*
X974926Y285160D03*
Y296860D03*
Y289060D03*
X995206Y292959D03*
X988446Y296860D03*
X991826Y294909D03*
X995206Y289060D03*
X988446D03*
X991826Y291009D03*
X985066D03*
X995206Y285160D03*
X985066Y298809D03*
X991826D03*
Y333909D03*
X995206Y335860D03*
Y339760D03*
Y328060D03*
X991826Y326110D03*
X981686Y339760D03*
X978306Y333909D03*
Y330009D03*
Y326110D03*
X981686Y331960D03*
X985066Y330009D03*
X974926Y324160D03*
X988446Y339760D03*
X981686Y335860D03*
X978306Y341709D03*
X974926Y312460D03*
X981686D03*
X988446D03*
X991826Y314409D03*
Y330009D03*
X995206Y331960D03*
X988446D03*
X995206Y324160D03*
X988446Y316360D03*
X991826Y318309D03*
X995206Y320260D03*
X991826Y322209D03*
X998586Y333909D03*
X985066Y337809D03*
Y341709D03*
X974926Y328060D03*
X998586Y314409D03*
X995206Y312460D03*
X998586Y318309D03*
Y322209D03*
Y326110D03*
Y330009D03*
X995206Y316360D03*
X985066Y314409D03*
X978306D03*
Y318309D03*
Y322209D03*
X981686Y320260D03*
X974926Y316360D03*
Y320260D03*
X985066Y326110D03*
X981686Y328060D03*
X988446D03*
Y324160D03*
X985066Y318309D03*
Y322209D03*
X988446Y320260D03*
X981686Y324160D03*
X974926Y339760D03*
Y335860D03*
X981686Y316360D03*
X1006665Y300760D03*
Y304660D03*
Y308560D03*
Y285160D03*
Y296860D03*
Y289060D03*
Y281260D03*
Y292959D03*
X1008725Y335860D03*
X1005345Y333909D03*
X1001965Y331960D03*
X1007595Y327609D03*
X1021115Y335409D03*
X1018865Y341709D03*
X1017735Y333460D03*
X1015485Y339760D03*
X1024495Y337360D03*
X1012105Y337809D03*
X1016399Y324304D03*
X1022393Y326580D03*
X1024893D03*
X1017393D03*
X1028393Y329580D03*
X1019893Y326580D03*
X1027393D03*
X1017957Y312421D03*
X1025438Y312381D03*
X1022915Y312372D03*
X1020404Y312408D03*
X1028039Y312414D03*
X1025755Y328951D03*
X1008725Y339760D03*
X1005345Y337809D03*
X1001965Y335860D03*
X1012105Y341709D03*
X1006665Y312460D03*
X1014355Y331509D03*
X1010975Y329560D03*
X1027875Y339309D03*
X1031255Y341260D03*
X1006665Y324160D03*
Y316360D03*
Y320260D03*
X991826Y341709D03*
X988446Y335860D03*
X998586Y345609D03*
X981686Y367060D03*
X978306Y372909D03*
X1029005Y355360D03*
X1015485Y351460D03*
X1012105Y349509D03*
X1025625D03*
X1001965Y343660D03*
X1018865Y369010D03*
X995206Y363160D03*
X1032385Y369010D03*
X995206Y343660D03*
X985066Y361209D03*
X974926Y355360D03*
Y347560D03*
X978306Y353409D03*
Y349509D03*
Y357309D03*
X974926Y359260D03*
X981686D03*
X998586Y369010D03*
Y357309D03*
X981686Y347560D03*
X978306Y345609D03*
X981686Y355360D03*
X985066Y349509D03*
X998586D03*
X978306Y365109D03*
X981686Y363160D03*
X974926D03*
Y367060D03*
Y370959D03*
X988446Y367060D03*
X998586Y365109D03*
Y353409D03*
X991826Y365109D03*
X995206Y370959D03*
X991826Y353409D03*
X974926Y343660D03*
X995206Y359260D03*
X988446D03*
Y347560D03*
X991826Y345609D03*
X988446Y351460D03*
Y355360D03*
X998586Y388509D03*
X991826Y380709D03*
X998586D03*
X991826Y372909D03*
X988446Y374860D03*
X998586Y392410D03*
X988446Y382660D03*
X995206D03*
X985066Y372909D03*
X974926Y374860D03*
X985066Y384609D03*
X998586Y376809D03*
X991826Y388509D03*
X995206Y390460D03*
X974926Y386560D03*
X991826Y376809D03*
X974066Y399911D03*
X978306Y376809D03*
X974926Y378760D03*
X981686D03*
X985066Y380709D03*
X995206Y386560D03*
X1022245Y343660D03*
X1005345Y365109D03*
X1008725Y370959D03*
X1001965D03*
X1005345Y353409D03*
X1018865Y365109D03*
X1012105D03*
X1025625D03*
X1022245Y370959D03*
X1015485D03*
X1018865Y353409D03*
X1012105D03*
X1025625D03*
X1029005Y370959D03*
X1032385Y365109D03*
X1005345Y345609D03*
X1018865Y349509D03*
X1032385Y353409D03*
X1008725Y343660D03*
X1001965Y359260D03*
X1005345Y349509D03*
X1008725Y359260D03*
X1015485D03*
X1018865Y345609D03*
X1022245Y347560D03*
X1015485Y343660D03*
X1025625Y345609D03*
X1022245Y359260D03*
X1029005Y347560D03*
Y359260D03*
X1032385Y349509D03*
X1018865Y357309D03*
X1001965Y363160D03*
X1022245Y355360D03*
X1012105Y357309D03*
X1008725Y351460D03*
X1032385Y388509D03*
Y376809D03*
X1022245Y386560D03*
X1007595Y402800D03*
X1012105Y380709D03*
X1022245Y374860D03*
X1015485D03*
X1025625Y380709D03*
X1029005Y386560D03*
X1018865Y380709D03*
X1001965Y374860D03*
X1029005D03*
X1008725Y386560D03*
X1005345Y380709D03*
X1008725Y374860D03*
Y382660D03*
X1001965D03*
X1005345Y392410D03*
X1029005Y390460D03*
X1025625Y392410D03*
X1022245Y382660D03*
X1015485D03*
X1012105Y392410D03*
X1018865D03*
X1029005Y382660D03*
X1027875Y402800D03*
X1005345Y376809D03*
Y388509D03*
X1001965Y386560D03*
X1025625Y376809D03*
Y388509D03*
X1018865Y376809D03*
X1012105D03*
X1018865Y388509D03*
X1012105D03*
X985066Y345609D03*
X1025625Y357309D03*
X1032385Y380709D03*
X1025625Y369010D03*
X1015485Y363160D03*
X1022245D03*
X1012105Y369010D03*
X991826D03*
Y357309D03*
X995206Y351460D03*
X1005345Y357309D03*
Y369010D03*
X1008725Y363160D03*
X1029005D03*
X1001965Y351460D03*
X985066Y353409D03*
X987401Y515364D03*
X990748Y512792D03*
X997441Y518157D03*
X973795Y499793D03*
X977362Y512792D03*
X974015Y509999D03*
X984055Y512792D03*
X980708Y515364D03*
X984055Y518157D03*
X976421Y499768D03*
X980708Y510114D03*
X977362Y518157D03*
X1034200Y506956D03*
X1000490Y509999D03*
X1016473Y515152D03*
Y510114D03*
X1008650Y515200D03*
X1008526Y510114D03*
X1024800Y516356D03*
Y518856D03*
X976530Y497170D03*
X974015Y515364D03*
X990748Y518157D03*
X994094Y515364D03*
X997441Y512792D03*
X1000787Y515364D03*
X1003915Y512792D03*
X1004134Y518157D03*
X1011126Y510114D03*
X1013873Y515152D03*
X987401Y509999D03*
X994094Y510114D03*
X1011250Y515200D03*
X1013873Y510114D03*
X1026500Y581000D03*
X1019800Y555800D03*
X990748Y536957D03*
X977362Y529014D03*
X980708Y536957D03*
X987401Y529014D03*
X990748Y547922D03*
X980708Y547914D03*
X997441Y529022D03*
X983900Y533100D03*
Y552000D03*
X977362Y555857D03*
X987401D03*
X997441D03*
X977362Y566814D03*
X990748Y574757D03*
Y585722D03*
X980708Y585714D03*
Y574757D03*
X997441Y566822D03*
X987401Y566814D03*
X983900Y570900D03*
X1007147Y550511D03*
Y553111D03*
X1007207Y534137D03*
X1013500Y529200D03*
X1026500Y538500D03*
Y541000D03*
X1007207Y531537D03*
X1026500Y546400D03*
X1013873Y547914D03*
X1000787Y536957D03*
Y547922D03*
X1017300Y536200D03*
X1017519Y529057D03*
X1017300Y547914D03*
X1007518Y536727D03*
X1007480Y528942D03*
X1007280Y547914D03*
X1026400Y543700D03*
X1016800Y566814D03*
X1019277Y585714D03*
X1016800Y574742D03*
X1006406Y588366D03*
X1007332Y572010D03*
X1016473Y585714D03*
X1026500Y577500D03*
X1007332Y569410D03*
X1014173Y566814D03*
Y555842D03*
Y574742D03*
X1010928Y555842D03*
X1000787Y585722D03*
Y574757D03*
X1016819Y555842D03*
X1007518D03*
Y566814D03*
X1007480Y574742D03*
X1006633Y585714D03*
X1011126Y547914D03*
Y585714D03*
X1013873D03*
X1010826Y566814D03*
Y574742D03*
X984054Y529014D03*
X997441Y574757D03*
X987401D03*
X994094Y529022D03*
X1004133D03*
X1020800Y612600D03*
X1029777Y613581D03*
X980708Y604614D03*
X997441Y612357D03*
X977362Y593657D03*
X987401D03*
X997441D03*
Y607292D03*
X977362D03*
X990748Y612457D03*
X980708Y609864D03*
X987401Y604499D03*
X983900Y589800D03*
X977362Y612457D03*
X1016778Y611759D03*
X1017519Y604614D03*
Y593642D03*
X1007480Y612242D03*
X1020700Y604600D03*
X1020300Y593700D03*
X1023200Y610700D03*
X1022950Y593650D03*
X1025450D03*
X1006406Y590966D03*
X1004133Y612358D03*
X1000787Y609864D03*
X1007480Y604614D03*
X1006634Y593642D03*
X990748Y607292D03*
X987401Y609864D03*
X994094D03*
X1000787Y604499D03*
X1004134Y607292D03*
X984055Y612457D03*
X1011572Y593642D03*
X1010826Y604614D03*
X1014173Y612242D03*
X1014919Y593642D03*
X974015Y609864D03*
Y604499D03*
X984055Y607292D03*
X994094Y604614D03*
X1010826Y612242D03*
X1014173Y604614D03*
X1044290Y11792D03*
X1043800Y-9700D03*
X1047637Y-4536D03*
X1057676Y-1743D03*
X1047637Y9107D03*
X1057677D03*
X1050983Y-7108D03*
X1047637Y28007D03*
X1057677D03*
X1050984Y17042D03*
X1045525Y15357D03*
X1057792Y13200D03*
Y32100D03*
X1071062Y-1817D03*
X1061023Y-9786D03*
X1067716Y-4536D03*
Y-9901D03*
X1081102Y-4536D03*
X1074409D03*
X1084448Y-7108D03*
X1077755D03*
X1091141Y-1843D03*
X1067716Y9107D03*
X1091141D03*
X1074409D03*
X1081102D03*
X1061023Y-4536D03*
X1081102Y28007D03*
X1074409D03*
X1061024Y17057D03*
X1067716Y28007D03*
Y17042D03*
X1091141D03*
X1084450Y17057D03*
X1077757D03*
X1091141Y28007D03*
X1083116Y13200D03*
Y32100D03*
X1070976Y13200D03*
Y32100D03*
X1071062Y-7108D03*
X1094488Y-4536D03*
Y-9786D03*
X1081102Y-9901D03*
X1064369Y-7108D03*
X1087795Y-4536D03*
X1050983Y-1743D03*
X1054330Y-9901D03*
X1044291Y-2200D03*
X1087795Y-9786D03*
X1074409D03*
X1084448Y-1743D03*
X1057676Y-7108D03*
X1064369Y-1743D03*
X1077755D03*
X1054330Y-4536D03*
X1047637Y-9901D03*
X1044100Y54700D03*
X1044290Y49592D03*
X1050984Y54842D03*
X1047637Y35942D03*
Y46907D03*
X1057677Y35942D03*
Y46907D03*
X1044290Y68964D03*
X1057676Y87392D03*
X1050983Y92757D03*
X1047637Y84599D03*
X1035000Y81200D03*
X1057677Y73742D03*
X1047637D03*
X1057792Y51000D03*
Y69900D03*
X1061024Y54857D03*
X1067716Y54842D03*
Y35942D03*
Y46907D03*
Y65807D03*
X1091141Y54842D03*
Y35942D03*
X1084450Y54857D03*
X1081102Y35942D03*
X1074409D03*
X1077757Y54857D03*
X1081102Y46907D03*
X1074409D03*
X1091141D03*
Y65807D03*
X1083116Y51000D03*
X1070976D03*
X1083116Y69900D03*
X1070976D03*
X1067716Y89964D03*
Y84599D03*
X1081102D03*
X1091141Y87392D03*
Y92657D03*
X1077755Y92757D03*
X1074409Y84714D03*
X1084448Y92757D03*
X1061023Y89964D03*
X1067716Y73742D03*
X1074409D03*
X1081102D03*
X1091141D03*
X1061023Y84714D03*
X1057677Y65807D03*
X1047637D03*
X1044290Y87392D03*
X1057676Y92757D03*
X1071062D03*
X1064369Y87392D03*
X1054330Y84599D03*
X1047637Y89964D03*
X1064369Y92757D03*
X1050983Y87392D03*
X1054330Y89964D03*
X1074409Y65807D03*
X1081102D03*
Y89964D03*
X1087795Y84714D03*
Y89964D03*
X1074409D03*
X1084448Y87392D03*
X1077755D03*
X1094488Y84714D03*
Y89964D03*
X1050983Y105800D03*
X1057734Y105750D03*
X1035900Y98800D03*
X1077304Y105800D03*
X1071111D03*
X1064428D03*
X1071120Y103116D03*
X1057734D03*
X1064427D03*
X1050983D03*
X1077304Y103100D03*
X1045904Y213009D03*
X1057314Y209109D03*
X1045904D03*
X1035765Y211060D03*
X1039145Y216909D03*
X1035765Y214960D03*
X1042524D03*
X1042506Y195041D03*
X1045904Y197359D03*
X1054000Y199100D03*
X1035765Y207159D03*
X1042524Y203260D03*
X1049284Y214960D03*
Y203260D03*
X1039145Y209109D03*
X1068822Y218147D03*
X1072202Y216196D03*
X1065242Y208397D03*
X1068822Y214247D03*
X1065242Y212296D03*
Y204496D03*
X1071072Y199583D03*
X1095861Y218147D03*
X1089101Y214247D03*
Y210346D03*
X1092481Y216196D03*
X1095861Y206446D03*
X1091351Y199841D03*
X1075582Y206446D03*
Y218147D03*
X1082341D03*
X1078962Y216196D03*
X1078961Y212296D03*
X1082341Y214247D03*
X1085721Y212296D03*
Y216196D03*
X1084591Y198931D03*
X1045904Y228610D03*
X1078962Y235696D03*
Y243496D03*
X1042524Y234460D03*
X1035765D03*
X1049284D03*
X1039145Y236409D03*
X1045904Y220809D03*
X1057314D03*
X1049284Y222760D03*
X1042524Y226660D03*
X1039145Y232509D03*
X1035765Y226660D03*
X1057314Y240309D03*
X1049284Y226660D03*
X1045904Y232509D03*
X1057314D03*
Y244209D03*
X1049284Y246160D03*
X1035765Y238360D03*
Y250060D03*
X1057314Y248109D03*
X1039145D03*
X1042524Y250060D03*
X1049284D03*
X1045904Y248109D03*
X1042524Y238360D03*
X1039145Y220809D03*
X1038015Y256500D03*
X1041395Y254259D03*
X1048154D03*
X1051534Y256500D03*
X1044774Y256400D03*
X1054914Y254500D03*
X1034635Y254259D03*
X1050002Y264899D03*
X1047002D03*
X1043502D03*
X1040502D03*
X1089101Y222047D03*
Y225947D03*
X1065242Y220096D03*
X1075582Y225947D03*
X1095861Y229847D03*
X1068822Y233746D03*
X1065242Y235696D03*
Y223996D03*
X1068822Y237647D03*
Y249347D03*
X1065242Y247396D03*
X1068822Y241547D03*
X1072202Y243496D03*
Y251296D03*
X1092481Y223996D03*
Y231797D03*
X1089101Y233746D03*
X1068822Y229847D03*
X1095861Y233746D03*
X1092481Y247396D03*
X1089101Y245447D03*
X1085721Y247396D03*
X1089101Y249347D03*
X1092481Y251296D03*
X1095861Y249347D03*
X1089101Y237647D03*
X1095861D03*
Y245447D03*
X1078962Y251296D03*
X1082341Y245447D03*
Y249347D03*
X1078962Y247396D03*
X1092481Y243496D03*
X1075582Y245447D03*
X1085721Y251296D03*
X1075582Y249347D03*
X1085721Y243496D03*
X1089101Y241547D03*
X1085721Y223996D03*
X1075582Y229847D03*
X1082341D03*
X1078962Y227896D03*
Y220096D03*
Y223996D03*
X1085721Y231797D03*
X1082341Y237647D03*
X1075582D03*
X1072202Y231797D03*
Y223996D03*
X1065242Y239596D03*
X1068822Y245447D03*
X1085721Y227896D03*
X1095861Y222047D03*
X1082341D03*
X1079859Y265000D03*
X1089101Y253247D03*
X1092481Y255196D03*
X1095861Y257147D03*
X1089100Y264500D03*
X1092300Y267200D03*
X1095700Y268790D03*
X1089000Y267000D03*
X1067692Y254000D03*
X1071072Y255728D03*
X1087971Y257800D03*
X1091351Y259600D03*
X1094731Y261500D03*
X1084591Y255497D03*
X1081212Y257600D03*
X1095861Y253247D03*
X1092100Y264500D03*
X1078962Y239596D03*
X1082341Y233746D03*
X1085721Y239596D03*
X1075582Y233746D03*
X1039145Y228610D03*
X1049284Y238360D03*
X1072202Y239596D03*
X1057314Y224709D03*
X1047756Y338341D03*
X1044256D03*
X1050756D03*
X1053702Y338404D03*
X1095702Y309904D03*
X1071102Y292904D03*
X1068102D03*
X1063902D03*
X1075302Y309904D03*
X1082502D03*
X1092756Y309841D03*
X1089702Y309904D03*
X1085502D03*
X1078302D03*
X1071102D03*
X1068102D03*
X1063902D03*
X1060902D03*
Y292904D03*
X1085502D03*
X1082502D03*
X1078302D03*
X1075302D03*
X1089702D03*
X1092702D03*
X1093601Y370247D03*
X1076435Y343595D03*
X1052664Y357309D03*
X1049284Y370959D03*
X1035765D03*
X1042524D03*
X1045904Y365109D03*
X1039145D03*
X1052664D03*
X1035765Y355360D03*
X1042524Y359260D03*
X1049284Y351460D03*
X1045904Y353409D03*
X1035765Y351460D03*
Y359260D03*
X1039145Y353409D03*
X1042524Y351460D03*
X1054914Y347000D03*
X1042524Y355360D03*
X1045904Y357309D03*
X1039145D03*
X1045904Y369010D03*
X1049284Y359260D03*
X1034635Y343209D03*
X1038015Y345160D03*
X1041395Y347109D03*
X1048154D03*
X1044774Y345160D03*
X1051534D03*
X1039145Y388509D03*
X1045904D03*
X1052664D03*
X1039145Y376809D03*
X1045904D03*
X1042524Y386560D03*
X1045904Y380709D03*
X1035765Y374860D03*
Y386560D03*
X1052664Y380709D03*
X1049284Y374860D03*
X1042524D03*
X1039145Y380709D03*
X1052664Y392410D03*
X1040265Y394359D03*
X1049284Y382660D03*
X1035765D03*
X1042524D03*
Y390460D03*
X1056176Y402471D03*
X1041395Y402800D03*
X1052664Y376809D03*
X1060694Y351460D03*
X1086841Y358547D03*
X1094731Y346546D03*
X1086841Y354647D03*
X1090221Y352696D03*
X1091351Y348497D03*
X1073322Y354647D03*
X1076702Y356596D03*
X1080082Y354647D03*
X1083462Y368296D03*
X1076702Y372197D03*
Y368296D03*
X1073322Y362447D03*
X1086841D03*
X1090221Y372197D03*
Y364396D03*
X1093601Y366347D03*
X1090221Y368296D03*
X1076702Y360496D03*
X1083462D03*
Y352696D03*
X1076702D03*
X1093601Y358547D03*
X1086841Y366347D03*
X1073322D03*
X1083462Y372197D03*
X1093601Y362447D03*
X1090221Y356596D03*
X1080082Y366347D03*
Y362447D03*
X1071072Y348497D03*
X1087971Y346546D03*
X1074452D03*
X1081212D03*
X1077832Y348497D03*
X1084591D03*
X1090221Y379996D03*
X1073323Y401449D03*
X1078962Y399496D03*
X1093601Y401447D03*
Y389747D03*
X1090221Y383896D03*
X1073322Y389747D03*
X1083462Y387796D03*
X1073322Y381947D03*
X1080082D03*
X1076702Y391696D03*
Y387796D03*
X1060694Y390460D03*
Y374860D03*
X1073322Y374146D03*
X1086841D03*
X1073323Y397548D03*
X1073322Y385847D03*
X1080082Y393647D03*
X1083462Y391696D03*
X1080082Y385847D03*
X1083462Y376096D03*
X1080082Y378047D03*
X1083462Y379996D03*
X1076702Y376096D03*
X1090221Y395595D03*
X1086841Y389747D03*
X1093601Y393647D03*
X1090221Y391696D03*
X1093601Y385847D03*
X1086841D03*
X1093601Y397546D03*
Y378047D03*
X1086841Y381947D03*
X1080082Y370247D03*
X1052664Y353409D03*
X1060694Y355360D03*
X1061039Y359351D03*
X1039145Y369010D03*
X1042524Y363160D03*
X1035765D03*
X1052664Y369010D03*
X1049284Y363160D03*
X1076702Y379996D03*
X1093601Y405347D03*
X1077832Y407800D03*
X1035750Y503006D03*
X1050983Y512792D03*
X1054330Y509999D03*
X1044290Y512792D03*
X1047637Y509999D03*
X1057676Y512792D03*
X1035000Y521556D03*
X1050983Y518157D03*
X1067716Y509999D03*
X1074409Y510114D03*
X1061023Y515364D03*
X1091141Y518057D03*
X1077755Y518157D03*
X1081102Y509999D03*
X1084448Y518157D03*
X1082800Y497650D03*
X1091141Y512792D03*
X1067716Y515364D03*
X1061023Y510114D03*
X1087795D03*
X1077755Y512792D03*
X1071062Y518157D03*
X1084448Y512792D03*
X1057676Y518157D03*
X1064369Y512792D03*
X1047637Y515364D03*
X1064369Y518157D03*
X1054330Y515364D03*
X1087795D03*
X1074409D03*
X1094488Y510114D03*
Y515364D03*
X1081102D03*
X1084800Y499400D03*
X1057792Y552000D03*
Y533100D03*
X1044203Y537058D03*
X1044290Y550592D03*
X1057677Y547907D03*
Y536942D03*
X1047637Y547907D03*
Y536942D03*
X1044195Y529026D03*
X1057677Y574742D03*
Y585707D03*
X1047637Y574742D03*
Y585707D03*
X1044290Y569492D03*
X1057792Y570900D03*
X1047637Y566807D03*
X1057677D03*
X1050984Y555842D03*
X1074409Y547907D03*
X1081102D03*
X1091141D03*
Y529007D03*
Y536942D03*
X1074409D03*
X1081102D03*
X1067716D03*
Y529007D03*
X1070976Y552000D03*
Y533100D03*
X1084003Y532904D03*
X1083116Y552000D03*
X1074409Y566807D03*
X1061024Y555857D03*
X1077757D03*
X1084450D03*
X1091141Y555842D03*
X1067716D03*
X1081102Y574742D03*
Y585707D03*
X1074409D03*
X1091141Y574742D03*
Y585707D03*
X1067716Y574742D03*
Y585599D03*
Y566807D03*
X1091141D03*
X1074409Y574742D03*
X1070976Y570900D03*
X1083116D03*
X1057677Y529007D03*
X1047637D03*
X1044290Y588392D03*
X1081102Y566807D03*
X1087797Y566822D03*
X1094490Y574757D03*
X1054331Y529022D03*
X1094490Y536957D03*
X1071062Y612560D03*
X1064369Y612657D03*
X1084448D03*
X1091141Y612557D03*
X1050984Y612658D03*
X1057676Y612657D03*
X1046500Y623500D03*
X1050984Y593642D03*
X1047637Y609864D03*
X1044290Y607292D03*
X1057792Y589800D03*
X1054330Y609864D03*
X1087795D03*
X1071062Y607292D03*
X1061024Y593657D03*
X1061023Y604614D03*
X1077757Y593657D03*
X1084450D03*
X1067716Y593642D03*
Y609864D03*
Y604499D03*
X1081102Y609864D03*
X1091141Y593642D03*
Y607292D03*
X1084448D03*
X1077755D03*
X1061023Y609864D03*
X1070242Y589800D03*
X1083108D03*
X1077755Y612657D03*
X1044291Y612658D03*
X1057676Y607292D03*
X1047637Y604499D03*
X1094488Y604614D03*
X1081102Y604499D03*
X1054330D03*
X1050983Y607292D03*
X1074409Y609864D03*
Y593642D03*
X1087795Y604614D03*
X1074409D03*
X1094488Y609864D03*
X1064369Y607292D03*
X1119453Y-9864D03*
X1097352Y-7180D03*
X1104141Y-7851D03*
X1110520Y-7700D03*
X1114340Y-1801D03*
X1107874Y-1751D03*
X1101181Y-1801D03*
X1107724Y9114D03*
X1101181D03*
X1114340Y9098D03*
X1114400Y28100D03*
X1110520Y14814D03*
X1104177Y14714D03*
X1098500Y17000D03*
X1114300Y16900D03*
X1110520Y33700D03*
X1107874Y27899D03*
X1104141Y33700D03*
X1101181Y27899D03*
X1114366Y30750D03*
X1119440Y33149D03*
X1114340Y33399D03*
X1119440Y30540D03*
X1097834Y11100D03*
X1119400Y9300D03*
X1119453Y27936D03*
X1119440Y17114D03*
X1097900Y13700D03*
Y31900D03*
X1110520Y30100D03*
X1097834Y28100D03*
X1104141Y29949D03*
X1156300Y-2000D03*
X1151152Y-1801D03*
X1131299Y9114D03*
X1124606D03*
X1151152Y9098D03*
X1137992Y9114D03*
X1144535D03*
X1147331Y-4100D03*
X1144685Y-9901D03*
X1140952Y-4100D03*
X1137992Y-9901D03*
X1151178Y-7050D03*
X1156252Y-7260D03*
X1151152Y-4401D03*
X1156252Y-4651D03*
X1124606Y27899D03*
X1147331Y33700D03*
X1144685Y27899D03*
X1140952Y33700D03*
X1137992Y27899D03*
X1151177Y30750D03*
X1156251Y33149D03*
X1127952Y-7851D03*
X1124606Y-1751D03*
X1131299D03*
X1134645Y-7851D03*
X1156265Y-9864D03*
X1151200Y-9700D03*
X1147331Y-7700D03*
X1140952Y-7851D03*
X1137992Y-1801D03*
X1144685Y-1751D03*
X1151151Y33399D03*
X1156251Y30540D03*
X1144685Y17157D03*
X1147331Y12114D03*
X1137992Y17157D03*
X1141038Y12114D03*
X1151152Y14300D03*
X1156252Y14514D03*
X1151152Y11700D03*
X1156252Y11914D03*
X1156212Y9300D03*
X1127952Y14814D03*
X1151211Y28100D03*
X1156252Y17114D03*
X1151112Y16900D03*
X1147331Y30100D03*
Y14814D03*
X1134645Y29949D03*
X1140952D03*
X1140988Y14714D03*
X1134645Y14814D03*
X1156265Y27936D03*
X1127952Y29949D03*
X1131299Y27899D03*
X1119440Y-4651D03*
X1114340Y-4401D03*
X1119440Y-7260D03*
X1114366Y-7050D03*
X1124606Y-9901D03*
X1127952Y-3700D03*
X1131299Y-9901D03*
X1107874D03*
X1110520Y-4100D03*
X1134645Y-3700D03*
X1119440Y11914D03*
X1114340Y11700D03*
X1119440Y14514D03*
X1114340Y14300D03*
X1127952Y12114D03*
X1124606Y17157D03*
X1131299D03*
X1110520Y12114D03*
X1107874Y17157D03*
X1134645Y12114D03*
X1101181Y17157D03*
X1104227Y12114D03*
X1101181Y-9901D03*
X1104141Y-4100D03*
X1114340Y35999D03*
X1098235Y68090D03*
X1110520Y67900D03*
X1104141Y67749D03*
X1114366Y65950D03*
X1107874Y65699D03*
X1101181D03*
X1114366Y68550D03*
X1119440Y68340D03*
X1107874Y54957D03*
X1110520Y49914D03*
X1101181Y54957D03*
X1104227Y49564D03*
X1114340Y52100D03*
X1119440Y49714D03*
X1114340Y49500D03*
X1119440Y52314D03*
Y54914D03*
X1119400Y47100D03*
Y35800D03*
X1098100Y51000D03*
X1119453Y65736D03*
X1107874Y36049D03*
X1098022Y35761D03*
X1101181Y35999D03*
X1107724Y46914D03*
X1110520Y52614D03*
X1098581Y54883D03*
X1104177Y52514D03*
X1101181Y46900D03*
X1098125Y46975D03*
X1114300Y54700D03*
X1114340Y46898D03*
X1098259Y70896D03*
X1101181Y84714D03*
X1098218Y85296D03*
X1114340Y73799D03*
X1107874Y73849D03*
X1101181Y73799D03*
X1098207Y73589D03*
X1110520Y90314D03*
X1114340Y84698D03*
X1114316Y92500D03*
X1107724Y84714D03*
X1119440Y92714D03*
X1119416Y84700D03*
X1119466Y73550D03*
X1098300Y89900D03*
X1104177Y90314D03*
X1110520Y71500D03*
X1107874Y92757D03*
X1110520Y87714D03*
X1104227D03*
X1114340Y89900D03*
X1119440Y70949D03*
Y87514D03*
X1114340Y71199D03*
Y87300D03*
X1119440Y90114D03*
X1127952Y34100D03*
X1124606Y54957D03*
X1127952Y49914D03*
X1144685Y54957D03*
X1147331Y49914D03*
X1137992Y54957D03*
X1141038Y49914D03*
X1151151Y52100D03*
X1156251Y49714D03*
X1151151Y49500D03*
X1156251Y52314D03*
X1127952Y67749D03*
X1156211Y35800D03*
X1156200Y47000D03*
X1151152Y35999D03*
Y46898D03*
X1151100Y54700D03*
X1147331Y52614D03*
X1134645D03*
X1137992Y46914D03*
Y35999D03*
X1144535Y46914D03*
X1144685Y36049D03*
X1156252Y54914D03*
X1134645Y67749D03*
X1140952D03*
X1156265Y65736D03*
X1151178Y65950D03*
X1147331Y67900D03*
X1131299Y46914D03*
X1124606D03*
X1127952Y52614D03*
X1131299Y36049D03*
X1124606D03*
X1131299Y65699D03*
X1124606D03*
X1144685D03*
X1137992D03*
X1151178Y68550D03*
X1156252Y68340D03*
X1131299Y54957D03*
X1134645Y34100D03*
Y49914D03*
X1131299Y73849D03*
X1124606D03*
X1127952Y90414D03*
X1131299Y84714D03*
X1124606D03*
X1147331Y90414D03*
X1137992Y73799D03*
X1144535Y84714D03*
X1140988Y90314D03*
X1137992Y84714D03*
X1134645Y90414D03*
Y71900D03*
X1131299Y92757D03*
X1134645Y87714D03*
X1127952Y71900D03*
X1124606Y92757D03*
X1127952Y87714D03*
X1147331Y71500D03*
X1144685Y92757D03*
X1147331Y87714D03*
X1140952Y71500D03*
X1137992Y92757D03*
X1141038Y87714D03*
X1151152Y89900D03*
X1156252Y70949D03*
Y87514D03*
X1151152Y71199D03*
Y87300D03*
X1156252Y90114D03*
X1144685Y73849D03*
X1156252Y92714D03*
X1151128Y92500D03*
X1151152Y84698D03*
X1156228Y84700D03*
X1156278Y73550D03*
X1151152Y73799D03*
X1101181Y92757D03*
X1104141Y71500D03*
X1138242Y104314D03*
X1144685D03*
X1144535Y112357D03*
X1147331Y106964D03*
X1138242Y112357D03*
X1141038Y106964D03*
X1151152Y110514D03*
X1156252Y107655D03*
X1151178Y107865D03*
X1156278Y110264D03*
Y112865D03*
X1151152Y113114D03*
X1141038Y109564D03*
X1147331D03*
X1156265Y105051D03*
X1151178Y105265D03*
X1129660Y210346D03*
X1136420D03*
X1144300Y212296D03*
X1147680Y214247D03*
X1144300Y216196D03*
X1147680Y218147D03*
X1154440D03*
X1099241Y216196D03*
Y212296D03*
X1109381Y214247D03*
X1116141Y218147D03*
X1106001Y212296D03*
X1102621Y218147D03*
Y214247D03*
X1119521Y216196D03*
X1119520Y212296D03*
X1104871Y198050D03*
X1106001Y216196D03*
X1112761D03*
X1129660Y206447D03*
X1126280Y216196D03*
Y212296D03*
X1125300Y199900D03*
X1122900Y214247D03*
Y218147D03*
X1129660Y214247D03*
X1147950Y209900D03*
X1136420Y218147D03*
Y214247D03*
X1151060Y212296D03*
X1157820D03*
Y216196D03*
X1151060D03*
X1154440Y214247D03*
X1140920Y280547D03*
X1157820Y274696D03*
X1154440Y268847D03*
X1140920Y272747D03*
X1154440Y280547D03*
Y276647D03*
X1147680D03*
X1140920D03*
X1154440Y272747D03*
X1147680D03*
X1151060Y270796D03*
X1144300Y220096D03*
X1154440Y237647D03*
X1147680Y241547D03*
X1157820Y227896D03*
X1147680Y229847D03*
X1109381Y257147D03*
X1112761Y255196D03*
X1102621Y253247D03*
X1106001Y255196D03*
X1144300Y274696D03*
X1106001Y227896D03*
X1116141Y222047D03*
X1109381D03*
Y225947D03*
X1116141Y233746D03*
X1112761Y239596D03*
X1119521Y231797D03*
X1099241Y227896D03*
Y220096D03*
X1102621Y229847D03*
X1099241Y223996D03*
X1109381Y233746D03*
X1112761Y231797D03*
Y223996D03*
X1116141Y237647D03*
X1109381D03*
X1106001Y223996D03*
X1102621Y237647D03*
X1119521Y239596D03*
X1106001D03*
X1102621Y233746D03*
X1099241Y239596D03*
X1102621Y245447D03*
X1112761Y251296D03*
X1116141Y245447D03*
X1106001Y243496D03*
X1112761D03*
X1109381Y241547D03*
X1106001Y251296D03*
X1099241D03*
Y247396D03*
X1119521Y223996D03*
Y220096D03*
Y227896D03*
Y247396D03*
Y251296D03*
X1106001Y231797D03*
X1116141Y229847D03*
X1096756Y278941D03*
X1099186Y278938D03*
X1102336Y274819D03*
X1107561Y269038D03*
X1116141Y264947D03*
X1111631Y271300D03*
X1106001Y262996D03*
Y259096D03*
X1099241Y255196D03*
Y259096D03*
X1119521Y270796D03*
X1118391Y274997D03*
X1119521Y255196D03*
X1102621Y261047D03*
Y257147D03*
X1109381Y261047D03*
X1116141Y257147D03*
X1112761Y259096D03*
X1110648Y276899D03*
X1100200Y273300D03*
X1101491Y265400D03*
X1104871Y267300D03*
X1098111Y263400D03*
X1116141Y268847D03*
X1112761Y262996D03*
X1116141Y261047D03*
X1119521Y278596D03*
X1129660Y237647D03*
X1126280Y223996D03*
Y231797D03*
X1122900Y229847D03*
X1126280Y227896D03*
X1133040D03*
X1129660Y225947D03*
Y222047D03*
X1126280Y239596D03*
X1122900Y233746D03*
X1144300Y223996D03*
X1154440Y225947D03*
X1147680Y245447D03*
X1122900Y237647D03*
X1129660Y233746D03*
Y241547D03*
X1126280Y251296D03*
Y243496D03*
X1122900Y245447D03*
X1144300Y243496D03*
X1147680Y249347D03*
X1151060Y247396D03*
X1154440Y245447D03*
X1144300Y247396D03*
Y251296D03*
X1136420Y245447D03*
X1154440Y241547D03*
X1136420D03*
X1157820Y239596D03*
X1147680Y222047D03*
X1144300Y235696D03*
X1136420Y229847D03*
Y233746D03*
Y222047D03*
Y225947D03*
Y237647D03*
X1133040Y223996D03*
Y235696D03*
Y243496D03*
Y251296D03*
X1147680Y225947D03*
X1151060Y223996D03*
X1147680Y233746D03*
X1154440Y229847D03*
X1157820Y220096D03*
Y223996D03*
Y231797D03*
X1147680Y280547D03*
X1137540Y266896D03*
X1147680Y268847D03*
X1137540Y270796D03*
X1140920Y268847D03*
Y264947D03*
X1144300Y262996D03*
X1126280Y266896D03*
X1129660Y264947D03*
X1122900D03*
Y268847D03*
X1154440Y253247D03*
X1130780Y278596D03*
X1129660Y261047D03*
X1130780Y274696D03*
X1126280Y259096D03*
X1122900Y257147D03*
X1157820Y278596D03*
Y270796D03*
X1151060Y266896D03*
Y274696D03*
X1137540D03*
X1151060Y259096D03*
X1144300Y255196D03*
X1133040Y259096D03*
X1134160Y268847D03*
X1136420Y257147D03*
X1144300Y278596D03*
Y270796D03*
X1137540Y278596D03*
X1126280Y262996D03*
X1154440Y261047D03*
X1127400Y280547D03*
Y276646D03*
X1134160Y280547D03*
X1157820Y266896D03*
X1151060Y278596D03*
X1154440Y264947D03*
X1119521Y266896D03*
Y262996D03*
X1134160Y276646D03*
X1157820Y247396D03*
X1154440Y249347D03*
X1151060Y220096D03*
X1154440Y233746D03*
X1144300Y227896D03*
X1151060Y235696D03*
X1144300Y239596D03*
X1151060Y243496D03*
Y239596D03*
X1144300Y266896D03*
X1108125Y276799D03*
X1157820Y251296D03*
X1154440Y257147D03*
X1122900Y261047D03*
X1119521Y259096D03*
X1147680Y264947D03*
X1154440Y222047D03*
X1147680Y237647D03*
X1144300Y231797D03*
X1129660Y245447D03*
X1109381D03*
X1122900Y249347D03*
X1112761Y247396D03*
X1106001D03*
X1129660Y253247D03*
X1109381D03*
X1126280Y255196D03*
X1116141Y253247D03*
X1136420Y249347D03*
X1157820Y235696D03*
X1151060Y227896D03*
Y231797D03*
X1144300Y290296D03*
X1147680Y292247D03*
X1154440D03*
X1157820Y282496D03*
X1154440Y288347D03*
Y284447D03*
X1144300Y282496D03*
X1157820Y286396D03*
X1137540D03*
X1140920Y288347D03*
Y284447D03*
X1147680D03*
Y288347D03*
X1151060Y286396D03*
X1137540Y301996D03*
X1151060Y337096D03*
X1120641Y339047D03*
X1154440Y311747D03*
X1157820Y305896D03*
X1154440Y303947D03*
X1157820Y301996D03*
X1154440Y300047D03*
X1119521Y282496D03*
Y301996D03*
X1101256Y308841D03*
X1103756Y307841D03*
Y310341D03*
X1119521Y286396D03*
Y305896D03*
X1113900Y297800D03*
X1113132Y291702D03*
X1098756Y309841D03*
X1119521Y298096D03*
Y294196D03*
Y290296D03*
Y309797D03*
X1113500Y323400D03*
X1119521Y313696D03*
Y317596D03*
X1109200Y325100D03*
X1108251Y338746D03*
X1117261Y340996D03*
X1104871Y340697D03*
X1119521Y321496D03*
X1102300Y336700D03*
X1118391Y332897D03*
X1105900Y334000D03*
X1134160Y307847D03*
X1151060Y294196D03*
X1147680Y300047D03*
Y296147D03*
X1140920Y307847D03*
Y311747D03*
X1151060Y301996D03*
X1144300Y305896D03*
X1147680Y311747D03*
X1130780Y290296D03*
X1127400Y288347D03*
X1130780Y309797D03*
Y301996D03*
X1127400Y303947D03*
Y307847D03*
X1157820Y290296D03*
X1151060Y298096D03*
Y290296D03*
Y282496D03*
X1144300Y286396D03*
Y294196D03*
X1157820D03*
X1140920Y300047D03*
X1134160Y292247D03*
Y300047D03*
X1140920Y292247D03*
X1137540Y282496D03*
X1144300Y309797D03*
X1137540D03*
X1147680Y303947D03*
X1154440Y307847D03*
X1157820Y298096D03*
X1127400Y284447D03*
Y300047D03*
X1130780Y294196D03*
X1127400Y296147D03*
Y292247D03*
X1130780Y298096D03*
Y305896D03*
X1137540Y290296D03*
X1134160Y296147D03*
Y288347D03*
X1147680Y307847D03*
X1151060Y309797D03*
Y305896D03*
X1144300Y301996D03*
Y298096D03*
X1137540D03*
X1140920Y303947D03*
X1137540Y305896D03*
X1140920Y296147D03*
X1137540Y294196D03*
X1127400Y311747D03*
X1154440Y296147D03*
X1130780Y313696D03*
X1157820D03*
X1134160Y335147D03*
Y339047D03*
X1140920Y319547D03*
X1124021Y340996D03*
Y337096D03*
X1127400Y327347D03*
X1157820Y337096D03*
Y333196D03*
X1134160Y323446D03*
X1151060Y340996D03*
Y333196D03*
X1154440Y319547D03*
X1157820Y317596D03*
X1137540D03*
X1157820Y329296D03*
X1147680Y327347D03*
X1154440Y335147D03*
X1144300Y340996D03*
Y337096D03*
X1140920Y339047D03*
Y331247D03*
X1154440Y323446D03*
Y315647D03*
X1147680Y319547D03*
X1157820Y325396D03*
X1154440Y339047D03*
Y331247D03*
X1144300Y317596D03*
X1137540Y321496D03*
X1134160Y327347D03*
X1137540Y325396D03*
X1127400Y319547D03*
Y315647D03*
X1124021Y325396D03*
X1127400Y323446D03*
X1124021Y329296D03*
Y333196D03*
X1154440Y327347D03*
X1147680Y339047D03*
X1157820Y321496D03*
X1130780Y329296D03*
X1140920Y323446D03*
X1144300Y313696D03*
X1151060D03*
X1144300Y325396D03*
Y321496D03*
X1151060Y329296D03*
X1147680Y335147D03*
Y331247D03*
X1140920Y335147D03*
X1144300Y333196D03*
X1151060Y325396D03*
Y321496D03*
X1147680Y323446D03*
X1137540Y329296D03*
X1144300D03*
X1140920Y327347D03*
X1130780Y340996D03*
Y337096D03*
X1127400Y331247D03*
Y335147D03*
Y339047D03*
X1147680Y315647D03*
X1151060Y317596D03*
X1137540Y337096D03*
Y340996D03*
Y333196D03*
X1130780Y282496D03*
Y286396D03*
X1134160Y311747D03*
Y315647D03*
X1116999Y286826D03*
X1134160Y284447D03*
X1110501Y344896D03*
X1107121Y350747D03*
X1113881Y342947D03*
X1154440Y370246D03*
X1151060Y372196D03*
X1157820D03*
X1140920Y342947D03*
Y401447D03*
X1154440Y374146D03*
X1147680D03*
X1124021Y344896D03*
X1127400Y350747D03*
X1120641Y346847D03*
X1151060Y376096D03*
X1157820Y368296D03*
X1144300Y379996D03*
Y387796D03*
X1157820Y376096D03*
X1144300Y383896D03*
X1147680Y381947D03*
Y378047D03*
X1100361Y350747D03*
X1113881D03*
Y358547D03*
X1117261Y348796D03*
X1100361Y358547D03*
X1103741Y348796D03*
Y352696D03*
X1110501D03*
X1107121Y346847D03*
Y354647D03*
Y358547D03*
Y362447D03*
X1103741Y372197D03*
X1110501Y364396D03*
X1103741D03*
X1113881Y366347D03*
X1117261Y372197D03*
Y368296D03*
X1110501Y372197D03*
X1096981Y368296D03*
Y372197D03*
X1100361Y366347D03*
X1103741Y368296D03*
X1110501D03*
X1103741Y356596D03*
X1113881Y362447D03*
X1107121Y370247D03*
X1096981Y352696D03*
X1117261D03*
X1096981Y360496D03*
X1117261D03*
X1101491Y342646D03*
X1098111Y344597D03*
X1113881Y346847D03*
Y401447D03*
X1103741Y383896D03*
X1113881Y381947D03*
X1110501Y387796D03*
X1096981Y383896D03*
X1117261Y391696D03*
X1096981Y379996D03*
Y387796D03*
X1113881Y374146D03*
X1100361D03*
X1107121Y378047D03*
Y374146D03*
X1110501Y391696D03*
Y395595D03*
X1107121Y389747D03*
X1100361Y385847D03*
X1107121D03*
X1100361Y393647D03*
X1103741Y391696D03*
X1100361Y397547D03*
X1113881Y385847D03*
Y397546D03*
Y393647D03*
X1103741Y379996D03*
X1113881Y378047D03*
X1117261Y376096D03*
X1110501Y379996D03*
X1107121Y381947D03*
X1096981Y376096D03*
X1100361Y378047D03*
X1151060Y368296D03*
X1147680Y366347D03*
X1120641Y350747D03*
Y358547D03*
Y366347D03*
X1127400Y362447D03*
X1124021Y348796D03*
Y352696D03*
X1127400Y354647D03*
Y358547D03*
X1134160D03*
X1130780Y360496D03*
X1127400Y342947D03*
X1134160Y346847D03*
Y362447D03*
Y366347D03*
Y370247D03*
X1147680Y342947D03*
X1151060Y356596D03*
Y360496D03*
X1144300D03*
X1137540D03*
X1144300Y356596D03*
X1140920Y358547D03*
X1147680Y346847D03*
Y350747D03*
X1151060Y352696D03*
Y348796D03*
X1147680Y358547D03*
X1157820Y360496D03*
X1154440Y358547D03*
Y342947D03*
Y354647D03*
X1157820Y352696D03*
X1147680Y354647D03*
X1144300Y348796D03*
X1140920Y346847D03*
Y350747D03*
X1144300Y344896D03*
X1151060D03*
X1154440Y346847D03*
X1140920Y362447D03*
X1154440Y366347D03*
X1144300Y372197D03*
X1137540D03*
Y368296D03*
X1140920Y366347D03*
Y370247D03*
X1151060Y364396D03*
X1144300D03*
X1137540D03*
X1147680Y362447D03*
X1130780Y352696D03*
Y344896D03*
X1124021Y372197D03*
X1130780D03*
X1124021Y364396D03*
X1120641Y370247D03*
X1130780Y368296D03*
X1127400Y366347D03*
X1124021Y356596D03*
X1157820D03*
X1144300Y352696D03*
X1154440Y350747D03*
Y362447D03*
X1144300Y368296D03*
X1120641Y342947D03*
X1137540Y352696D03*
X1130780Y356596D03*
X1134160Y342947D03*
Y354647D03*
Y350747D03*
X1137540Y348796D03*
Y344896D03*
Y403396D03*
Y399496D03*
X1124021Y391696D03*
X1130780Y395596D03*
X1127400Y385847D03*
Y389747D03*
X1130780Y391696D03*
X1124021Y379996D03*
X1127400Y381947D03*
X1130780Y379996D03*
X1137540Y395597D03*
X1140920Y397546D03*
X1137540Y376096D03*
X1157820Y387796D03*
X1140920Y378047D03*
Y381947D03*
X1147680Y393647D03*
X1124021Y387796D03*
X1120641Y381947D03*
X1134160Y389747D03*
X1144300Y395597D03*
X1137540Y391696D03*
X1124021Y376096D03*
X1130780D03*
X1127400Y378047D03*
X1157820Y379996D03*
X1147680Y389747D03*
X1144300Y376096D03*
X1151060Y383896D03*
X1120641Y385847D03*
Y393647D03*
Y378047D03*
Y401447D03*
X1140920Y374146D03*
X1151060Y395597D03*
Y391696D03*
X1147680Y385847D03*
Y397546D03*
X1151060Y379996D03*
X1154440Y378047D03*
Y381947D03*
X1140920Y389747D03*
X1134160Y393647D03*
Y385847D03*
Y378047D03*
X1140920Y385847D03*
X1144300Y391696D03*
X1130780Y348796D03*
X1127400Y346847D03*
X1154440Y397546D03*
Y385847D03*
X1157820Y391696D03*
X1154440Y389747D03*
X1157820Y395597D03*
X1151060Y387796D03*
X1154440Y393647D03*
X1134160Y381947D03*
X1100361Y389747D03*
X1117261Y407296D03*
X1113881Y405347D03*
X1096699Y407782D03*
X1134160Y405347D03*
X1119440Y518114D03*
X1114316Y517900D03*
X1114340Y510098D03*
X1110520Y515714D03*
X1097343Y512794D03*
X1104177Y515714D03*
X1101181Y510114D03*
X1098300Y515300D03*
X1107724Y510114D03*
X1110520Y513114D03*
X1104227D03*
X1119440Y515514D03*
X1151152Y515300D03*
X1156252Y512914D03*
X1151152Y512700D03*
X1156252Y515514D03*
Y496167D03*
X1137992Y495887D03*
X1144385D03*
X1140988Y493744D03*
X1156252Y490867D03*
X1147331Y493494D03*
X1151168Y490867D03*
X1147331Y490894D03*
X1141038Y491144D03*
X1156252Y493567D03*
X1127952Y515814D03*
X1124606Y510114D03*
X1131299D03*
X1156252Y518114D03*
X1147331Y515814D03*
X1151128Y517900D03*
X1156252Y498867D03*
X1151168D03*
X1151152Y510098D03*
X1134645Y515814D03*
X1137992Y510114D03*
X1140988Y515714D03*
X1144535Y510114D03*
X1156228Y510100D03*
X1127952Y513114D03*
X1144685Y518157D03*
X1147331Y513114D03*
X1137992Y518157D03*
X1141038Y513114D03*
X1114340Y512700D03*
X1119440Y512914D03*
X1114340Y515300D03*
X1124606Y518157D03*
X1101181D03*
X1131299D03*
X1107874D03*
X1151168Y493467D03*
X1134645Y513114D03*
X1151168Y496167D03*
X1137992Y498487D03*
X1144385D03*
X1119440Y550714D03*
Y553314D03*
X1104141Y530949D03*
X1098040Y536723D03*
X1098160Y533809D03*
X1119416Y547900D03*
X1119466Y536750D03*
X1119453Y528936D03*
X1098300Y553100D03*
X1114340Y547898D03*
X1107724Y547914D03*
X1101181D03*
X1110520Y553514D03*
X1104177D03*
X1098118Y549843D03*
X1098018Y531156D03*
X1114366Y529150D03*
X1114340Y536999D03*
X1110520Y531100D03*
X1107874Y537049D03*
X1101181Y536999D03*
X1107874Y528899D03*
X1101181D03*
X1110520Y550914D03*
X1104227D03*
X1119440Y571949D03*
X1104227Y588714D03*
X1114340Y588300D03*
X1097343Y588394D03*
X1119440Y555914D03*
X1114316Y555700D03*
X1119416Y585700D03*
X1119466Y574550D03*
X1119453Y566736D03*
X1104141Y568749D03*
X1097899Y574773D03*
X1101181Y585714D03*
X1097834Y569200D03*
X1107724Y585714D03*
X1107874Y574849D03*
X1110520Y568900D03*
X1101181Y574799D03*
X1114340D03*
Y585698D03*
X1114366Y566950D03*
X1107874Y555957D03*
X1110520Y572500D03*
X1107874Y566699D03*
X1101181Y555957D03*
X1104141Y572500D03*
X1101181Y566699D03*
X1156252Y534149D03*
X1151152Y534399D03*
X1156252Y531540D03*
X1134645Y550914D03*
X1127952D03*
X1147331D03*
X1141038D03*
X1156252Y550714D03*
Y553314D03*
X1140988Y553514D03*
X1151152Y547898D03*
X1156228Y547900D03*
X1137992Y547914D03*
X1144535D03*
X1127952Y553614D03*
X1131299Y547914D03*
X1124606D03*
X1131299Y537049D03*
X1124606D03*
X1127952Y530949D03*
X1151178Y529150D03*
X1151152Y536999D03*
X1147331Y531100D03*
X1156278Y536750D03*
X1156265Y528936D03*
X1134645Y530949D03*
X1140952D03*
X1137992Y536999D03*
X1144685Y537049D03*
X1147331Y553614D03*
X1134645D03*
X1147331Y534700D03*
X1144685Y528899D03*
X1140952Y534700D03*
X1137992Y528899D03*
X1156252Y569340D03*
X1134645Y588714D03*
X1127952D03*
X1147331D03*
X1141038D03*
X1156252Y588514D03*
X1151152Y588300D03*
X1156252Y555914D03*
X1151128Y555700D03*
X1156265Y566736D03*
X1151178Y566950D03*
X1134645Y568749D03*
X1137992Y585714D03*
X1144535D03*
X1140952Y568749D03*
X1137992Y574799D03*
X1144685Y574849D03*
X1151152Y585698D03*
Y574799D03*
X1147331Y568900D03*
X1156228Y585700D03*
X1156278Y574550D03*
X1131299Y585714D03*
X1124606D03*
X1131299Y574849D03*
X1127952Y568749D03*
X1124606Y574849D03*
X1131299Y555957D03*
X1134645Y572900D03*
X1131299Y566699D03*
X1124606Y555957D03*
X1127952Y572900D03*
X1124606Y566699D03*
X1144685D03*
X1110520Y588714D03*
X1119440Y588514D03*
Y534149D03*
X1114366Y531750D03*
X1127952Y535100D03*
X1104141Y534700D03*
X1131299Y528899D03*
X1110520Y534700D03*
X1151152Y550500D03*
Y553100D03*
X1151178Y569550D03*
X1137992Y555957D03*
X1147331Y572500D03*
X1144685Y555957D03*
X1114340Y553100D03*
Y550500D03*
X1114366Y569550D03*
X1119440Y531540D03*
Y569340D03*
X1151178Y531750D03*
X1124606Y528899D03*
X1137992Y566699D03*
X1156252Y571949D03*
X1114340Y534399D03*
X1134645Y535100D03*
X1151152Y572199D03*
X1140952Y572500D03*
X1114340Y572199D03*
X1137992Y612599D03*
X1144685Y612649D03*
X1151152Y612599D03*
X1124606Y612649D03*
X1131299D03*
X1097374Y612659D03*
X1114340Y612599D03*
X1107874Y612649D03*
X1101181Y612599D03*
Y593757D03*
X1104141Y610300D03*
X1101181Y604499D03*
X1114340Y590900D03*
Y609999D03*
X1097352Y607220D03*
X1110520Y606700D03*
X1119453Y604536D03*
X1119466Y612350D03*
X1119440Y593714D03*
X1104177Y591314D03*
X1110520D03*
X1114316Y593500D03*
X1098300Y590900D03*
X1114366Y604750D03*
X1104141Y606549D03*
X1134645Y610700D03*
X1131299Y593757D03*
Y604499D03*
X1124606Y593757D03*
X1127952Y610700D03*
X1124606Y604499D03*
X1147700Y611200D03*
X1144685Y593757D03*
Y604499D03*
X1137992Y593757D03*
X1141332Y611668D03*
X1137992Y604499D03*
X1151178Y607350D03*
X1151152Y590900D03*
Y609999D03*
X1156252Y607140D03*
Y591114D03*
X1156265Y604536D03*
X1147331Y606700D03*
X1134645Y606549D03*
X1140952D03*
X1156278Y612350D03*
X1134645Y591414D03*
X1140988Y591314D03*
X1151128Y593500D03*
X1147331Y591414D03*
X1156252Y593714D03*
X1151178Y604750D03*
X1127952Y606549D03*
Y591414D03*
X1107874Y604499D03*
X1119440Y609749D03*
Y591114D03*
Y607140D03*
X1107874Y593757D03*
X1110520Y610300D03*
X1114366Y607350D03*
X1156252Y609749D03*
X1161417Y9114D03*
X1168110D03*
X1174803D03*
X1171456Y-3700D03*
X1168110Y-9901D03*
X1164763Y-3700D03*
X1161417Y-9901D03*
X1168110Y27899D03*
X1161417D03*
X1177763Y33700D03*
X1174803Y27899D03*
X1171456Y-7851D03*
X1164763D03*
X1177763D03*
X1168110Y-1751D03*
X1161417D03*
X1174803Y-1801D03*
X1168110Y17157D03*
X1171456Y12114D03*
X1161417Y17157D03*
X1164763Y12114D03*
X1171456Y14814D03*
X1164763Y29949D03*
X1171456D03*
X1164763Y14814D03*
X1177799Y14714D03*
X1177763Y29949D03*
X1181496Y-1751D03*
X1181346Y9114D03*
X1187963Y9098D03*
X1204921Y9114D03*
X1198228D03*
X1188011Y-9700D03*
X1193076Y-9864D03*
X1184142Y-7700D03*
X1193111Y-2000D03*
X1187963Y-1801D03*
X1201574Y-7851D03*
X1204921Y-1751D03*
X1198228D03*
X1218307D03*
X1211614Y-1801D03*
X1214574Y-7851D03*
X1208267D03*
X1218157Y9114D03*
X1211614D03*
X1204921Y27899D03*
X1198228D03*
X1218307D03*
X1214574Y33700D03*
X1211614Y27899D03*
X1187989Y30750D03*
X1193063Y33149D03*
X1187963Y33399D03*
X1193063Y30540D03*
X1193023Y9300D03*
X1184142Y30100D03*
Y14814D03*
X1188023Y28100D03*
X1187923Y16900D03*
X1193063Y17114D03*
X1193076Y27936D03*
X1201574Y14814D03*
Y29949D03*
X1208267Y14814D03*
Y29949D03*
X1214600Y14714D03*
X1214574Y29949D03*
X1184142Y33700D03*
X1181496Y27899D03*
X1184142Y12114D03*
X1204921Y17157D03*
X1198228D03*
X1201574Y12114D03*
X1187963Y14300D03*
X1193063Y14514D03*
X1187963Y11700D03*
X1193063Y11914D03*
X1184142Y-4100D03*
X1204921Y-9901D03*
X1201574Y-3700D03*
X1198228Y-9901D03*
X1187989Y-7050D03*
X1193063Y-7260D03*
X1187963Y-4401D03*
X1193063Y-4651D03*
X1208267Y-3700D03*
X1218307Y-9901D03*
X1214574Y-4100D03*
X1211614Y-9901D03*
X1208267Y12114D03*
X1218307Y17157D03*
X1211614D03*
X1214660Y12114D03*
X1174803Y-9901D03*
X1177763Y-4100D03*
X1181496Y-9901D03*
X1177849Y12114D03*
X1174803Y17157D03*
X1181496D03*
X1171456Y34100D03*
X1168110Y54957D03*
X1171456Y49914D03*
X1161417Y54957D03*
X1164763Y34100D03*
Y49914D03*
X1174803Y54957D03*
X1177849Y49914D03*
X1161417Y36049D03*
X1164763Y52614D03*
X1168110Y36049D03*
Y46914D03*
X1161417D03*
X1174803D03*
X1171456Y52614D03*
X1174803Y35999D03*
X1177763Y67749D03*
X1171456D03*
X1164763D03*
X1168110Y65699D03*
X1161417D03*
X1174803D03*
X1177799Y90314D03*
X1174803Y84714D03*
X1168110D03*
Y73849D03*
X1161417D03*
X1174803Y73799D03*
X1171456Y71900D03*
X1168110Y92757D03*
X1171456Y87714D03*
X1164763Y71900D03*
X1161417Y92757D03*
X1164763Y87714D03*
X1177763Y71500D03*
X1174803Y92757D03*
X1177849Y87714D03*
X1161417Y84714D03*
X1164763Y90414D03*
X1171456D03*
X1204921Y54957D03*
X1208267Y34100D03*
Y49914D03*
X1198228Y54957D03*
X1201574Y34100D03*
Y49914D03*
X1218307Y54957D03*
X1211614D03*
X1214660Y49914D03*
X1187963Y52100D03*
X1193063Y49714D03*
X1187963Y49500D03*
X1193063Y52314D03*
X1181346Y46914D03*
X1181496Y36049D03*
X1184142Y52614D03*
X1193012Y47000D03*
X1187963Y46898D03*
Y35999D03*
X1187912Y54700D03*
X1187989Y65950D03*
X1193076Y65736D03*
X1193063Y54914D03*
X1193023Y35800D03*
X1204921Y36049D03*
X1198228D03*
Y46914D03*
X1204921D03*
X1201574Y52614D03*
X1184142Y67900D03*
X1201574Y67749D03*
X1218307Y36049D03*
X1211614Y35999D03*
X1214960Y52864D03*
X1211614Y46914D03*
X1218157D03*
X1208267Y52614D03*
X1211614Y73799D03*
X1218307Y73849D03*
X1208267Y90414D03*
X1218157Y84714D03*
X1211614D03*
X1181496Y92757D03*
X1184142Y71500D03*
Y87714D03*
X1208267Y71900D03*
X1204921Y92757D03*
X1208267Y87714D03*
X1201574Y71900D03*
X1198228Y92757D03*
X1201574Y87714D03*
X1218307Y92757D03*
X1214574Y71500D03*
X1211614Y92757D03*
X1214874Y87374D03*
X1187963Y89900D03*
X1193063Y70949D03*
Y87514D03*
X1187963Y71199D03*
Y87300D03*
X1214574Y67749D03*
X1208267D03*
X1181496Y65699D03*
X1204921D03*
X1198228D03*
X1218307D03*
X1211614D03*
X1187989Y68550D03*
X1193063Y68340D03*
X1181496Y54957D03*
X1184142Y49914D03*
X1193063Y90114D03*
X1181346Y84714D03*
X1181496Y73849D03*
X1184142Y90414D03*
X1193039Y84700D03*
X1193063Y92714D03*
X1187939Y92500D03*
X1187963Y84698D03*
Y73799D03*
X1193089Y73550D03*
X1198228Y73849D03*
X1204921D03*
X1198228Y84714D03*
X1204921D03*
X1201574Y90414D03*
X1177799Y109914D03*
X1161632Y104314D03*
X1167925Y112357D03*
X1170721Y106964D03*
X1161632Y112357D03*
X1164428Y106964D03*
X1174742Y112357D03*
X1177849Y107314D03*
X1170721Y109564D03*
X1164428D03*
X1168075Y104314D03*
X1174742D03*
X1208267Y110014D03*
X1181496Y112357D03*
X1184142Y106964D03*
X1204921Y112357D03*
X1208267Y107314D03*
X1198228Y112357D03*
X1201574Y107314D03*
X1187963Y110514D03*
X1193063Y107655D03*
X1187989Y107865D03*
X1193089Y110264D03*
X1181346Y104314D03*
X1187963Y113114D03*
X1193089Y112865D03*
X1184142Y109564D03*
X1193076Y105051D03*
X1187989Y105265D03*
X1201574Y110014D03*
X1198228Y104314D03*
X1204921D03*
X1210070Y195300D03*
X1191619Y212296D03*
X1167960Y214247D03*
X1164580Y208397D03*
X1181479Y214247D03*
X1194999Y218147D03*
X1174719Y214247D03*
X1161200D03*
Y206446D03*
X1167960Y206447D03*
Y218147D03*
X1171339Y216196D03*
X1178099Y204496D03*
X1174719Y202547D03*
X1171339Y208397D03*
X1174719Y218147D03*
Y206447D03*
X1178099Y208397D03*
Y216196D03*
X1161200Y210346D03*
Y218147D03*
X1209033Y183907D03*
X1210000Y192500D03*
X1181479Y206447D03*
X1188239Y210346D03*
Y206447D03*
X1201759Y218147D03*
X1205759Y206682D03*
X1197492Y201356D03*
X1198379Y212296D03*
X1194999Y210346D03*
X1184859Y204496D03*
X1188239Y214247D03*
X1181479Y218147D03*
X1191619Y208397D03*
X1188239Y202247D03*
X1181479Y202547D03*
X1218868Y214869D03*
X1218000Y218100D03*
X1198379Y216196D03*
X1188239Y218147D03*
X1184859Y212296D03*
X1181479Y210346D03*
X1184859Y216196D03*
X1174719Y210346D03*
X1164580Y212296D03*
X1184859Y208397D03*
X1178099Y212296D03*
X1194999Y214247D03*
X1191619Y216196D03*
X1171339Y212296D03*
X1167960Y210346D03*
X1164580Y216196D03*
Y274696D03*
X1167960Y280547D03*
X1171339Y262996D03*
X1174719Y264947D03*
X1171339Y278596D03*
X1161200Y276646D03*
Y280547D03*
X1167960Y268847D03*
X1188239D03*
X1205139Y278596D03*
X1184859Y227896D03*
X1198379Y223996D03*
X1188239Y245447D03*
X1194999Y229847D03*
X1178099Y231797D03*
X1171339Y227896D03*
X1174719Y222047D03*
X1208519Y253247D03*
X1205139Y262996D03*
X1181479Y280547D03*
X1191619Y235696D03*
X1164580Y231797D03*
X1205139Y270796D03*
X1198379Y274696D03*
X1201759Y253247D03*
X1194999Y261047D03*
X1188239Y253247D03*
X1181479Y245447D03*
X1212199Y227896D03*
X1184859Y220096D03*
X1205139Y223996D03*
X1161200Y237647D03*
X1205139Y243496D03*
Y235696D03*
Y255196D03*
X1208519Y229847D03*
X1164580Y235696D03*
X1167960Y229847D03*
X1164580Y223996D03*
Y227896D03*
Y239596D03*
X1171339Y251296D03*
X1167960Y222047D03*
X1164580Y220096D03*
X1167960Y233746D03*
X1161200Y222047D03*
X1167960Y249347D03*
Y241547D03*
Y245447D03*
Y237647D03*
X1171339Y239596D03*
Y243496D03*
X1174719Y249347D03*
X1178099Y247396D03*
X1161200Y241547D03*
X1164580Y247396D03*
X1161200Y249347D03*
X1171339Y247396D03*
X1178099Y243496D03*
X1171339Y235696D03*
Y220096D03*
Y231797D03*
X1178099Y227896D03*
Y235696D03*
Y220096D03*
X1174719Y237647D03*
X1167960Y257147D03*
Y253247D03*
X1174719D03*
X1164580Y270796D03*
X1171339Y274696D03*
X1174719Y280547D03*
X1171339Y266896D03*
X1164580Y278596D03*
X1159578Y265117D03*
X1171339Y259096D03*
X1178099Y274696D03*
X1161200Y268847D03*
X1164580Y255196D03*
X1161200Y272747D03*
X1159410Y259720D03*
X1178099Y270796D03*
Y278596D03*
X1162300Y264947D03*
X1178099Y255196D03*
X1161200Y253247D03*
X1174719Y268847D03*
Y276646D03*
X1167960D03*
Y264947D03*
X1181479Y222047D03*
X1188239D03*
X1191619Y239596D03*
X1188239Y225947D03*
X1184859Y235696D03*
X1188239Y237647D03*
X1184859Y247396D03*
X1188239Y249347D03*
X1201759Y229847D03*
Y225947D03*
Y233746D03*
X1198379Y235696D03*
Y243496D03*
X1201759Y241547D03*
Y249347D03*
X1198379Y239596D03*
X1194999Y225947D03*
Y222047D03*
Y233746D03*
X1184859Y239596D03*
Y251296D03*
X1212199D03*
Y243496D03*
X1208519Y233746D03*
X1215700Y223600D03*
X1181479Y249347D03*
Y237647D03*
Y241547D03*
X1184859Y223996D03*
X1201759Y237647D03*
X1198379Y227896D03*
X1205139Y231797D03*
X1201759Y245447D03*
X1194999Y237647D03*
X1198379Y251296D03*
X1194999Y264947D03*
Y268847D03*
Y272747D03*
Y280547D03*
X1188239Y257147D03*
X1208519Y272747D03*
X1208819Y280547D03*
X1181479Y264947D03*
X1184859Y255196D03*
X1191619Y270796D03*
X1198379Y262996D03*
X1194999Y276646D03*
X1198379Y270796D03*
X1181479Y257147D03*
Y261047D03*
Y268847D03*
Y276646D03*
X1212199Y274696D03*
X1217200Y270500D03*
X1213808Y264800D03*
X1208519Y264947D03*
X1184859Y259096D03*
X1191619Y274696D03*
X1205139D03*
X1198379Y278596D03*
X1201759Y261047D03*
X1198379Y255196D03*
X1201759Y257147D03*
X1174719Y272747D03*
X1164580Y251296D03*
X1167960Y261047D03*
X1159390Y262460D03*
X1161200Y225947D03*
X1181479D03*
Y233746D03*
Y229847D03*
X1184859Y270796D03*
X1191619Y278596D03*
X1205139Y259096D03*
X1216234Y268055D03*
X1212199Y223996D03*
Y231797D03*
X1205139Y239596D03*
X1208519Y237647D03*
X1205139Y220096D03*
X1191619D03*
X1184859Y243496D03*
X1194999Y241547D03*
Y245447D03*
Y253247D03*
X1191619Y251296D03*
Y231797D03*
X1188239Y233746D03*
Y229847D03*
X1174719Y225947D03*
X1171339Y223996D03*
X1161200Y229847D03*
X1201759Y222047D03*
X1198379Y220096D03*
X1174719Y233746D03*
X1167960Y225947D03*
X1174719Y229847D03*
X1188239Y264947D03*
Y272747D03*
X1208519Y241547D03*
X1205139Y251296D03*
X1208519Y257147D03*
X1201759Y264947D03*
X1191619Y255196D03*
X1198379Y259096D03*
X1191619Y262996D03*
X1188239Y261047D03*
X1191619Y266896D03*
X1184859Y274696D03*
X1205139Y266896D03*
X1208519Y268847D03*
X1201759D03*
Y276646D03*
X1184859Y231797D03*
X1208519Y225947D03*
X1191619Y227896D03*
X1174719Y257147D03*
X1178099Y259096D03*
X1161200Y245447D03*
X1174719Y261047D03*
X1167960Y272747D03*
X1171339Y255196D03*
X1181479Y272747D03*
X1201759D03*
Y280547D03*
X1208519Y249347D03*
X1194999Y257147D03*
X1198379Y247396D03*
X1184859Y278596D03*
X1188239Y276646D03*
Y280547D03*
X1198379Y231797D03*
X1205139Y227896D03*
X1191619Y259096D03*
X1194999Y249347D03*
X1184859Y262996D03*
X1161200Y233746D03*
X1191619Y243496D03*
X1188239Y241547D03*
X1214732Y243496D03*
X1212199Y239596D03*
X1217476Y243482D03*
X1216234Y265555D03*
X1171339Y282496D03*
X1167960Y284447D03*
X1164580Y282496D03*
X1184859Y298096D03*
X1191619Y313696D03*
X1188239Y300047D03*
X1191619Y340996D03*
X1188239Y331247D03*
Y327347D03*
X1194999Y311747D03*
X1184859Y305896D03*
X1188239Y296147D03*
X1181479D03*
X1191619Y325396D03*
X1188239Y307847D03*
X1208819Y284447D03*
X1174719Y323446D03*
X1161200Y288347D03*
Y292247D03*
X1201759D03*
X1171339Y340996D03*
X1174719Y300047D03*
Y284447D03*
X1164580Y294196D03*
Y290296D03*
Y286396D03*
X1161200Y284447D03*
X1178099Y294196D03*
Y298096D03*
Y286396D03*
X1164580Y301996D03*
X1171339D03*
X1161200Y307847D03*
X1174719Y292247D03*
Y288347D03*
X1171339Y286396D03*
Y290296D03*
X1167960Y300047D03*
X1164580Y298096D03*
X1167960Y296147D03*
Y292247D03*
Y288347D03*
X1161200Y296147D03*
X1178099Y290296D03*
X1161200Y311747D03*
Y300047D03*
Y303947D03*
X1174719D03*
X1167960D03*
X1178099Y309797D03*
X1171339Y305896D03*
X1164580Y309797D03*
Y305896D03*
X1167960Y307847D03*
Y311747D03*
X1171339Y309797D03*
X1178099Y301996D03*
X1174719Y311747D03*
Y307847D03*
X1178099Y305896D03*
X1171339Y298096D03*
Y294196D03*
X1174719Y296147D03*
X1161200Y335147D03*
Y339047D03*
X1164580Y329296D03*
Y333196D03*
Y337096D03*
X1167960Y339047D03*
Y327347D03*
X1161200Y331247D03*
Y327347D03*
X1178099Y337096D03*
Y317596D03*
X1164580Y321496D03*
Y317596D03*
X1161200Y323446D03*
Y319547D03*
Y315647D03*
X1167960Y323446D03*
Y315647D03*
Y319547D03*
X1174719Y315647D03*
X1171339Y317596D03*
X1164580Y325396D03*
X1171339D03*
X1174719Y335147D03*
Y339047D03*
X1164580Y340996D03*
X1167960Y331247D03*
X1171339Y321496D03*
X1178099Y313696D03*
X1171339D03*
X1164580D03*
X1205500Y309797D03*
X1198379D03*
X1194999Y288347D03*
Y292247D03*
Y296147D03*
Y300047D03*
Y307847D03*
Y303947D03*
X1191619Y298096D03*
X1198379Y282496D03*
X1181479Y300047D03*
Y288347D03*
Y292247D03*
Y311747D03*
Y307847D03*
Y303947D03*
X1188239Y288347D03*
Y284447D03*
Y292247D03*
X1184859Y294196D03*
Y290296D03*
X1191619Y294196D03*
X1184859Y309797D03*
X1188239Y311747D03*
X1184859Y301996D03*
X1201759Y284447D03*
Y288347D03*
X1205439Y298096D03*
X1198379Y286396D03*
X1205439Y305896D03*
X1194999Y335147D03*
Y331247D03*
X1212200Y333196D03*
X1208519Y339047D03*
X1208826Y319544D03*
X1184859Y325396D03*
Y333196D03*
X1198379Y337096D03*
Y329296D03*
X1181479Y327347D03*
Y319547D03*
Y335147D03*
X1198379Y313696D03*
X1188239Y319547D03*
X1184859Y321496D03*
X1188239Y339047D03*
Y335147D03*
X1184859Y329296D03*
X1191619Y321496D03*
X1198379Y325396D03*
Y340996D03*
X1201759Y323446D03*
X1205139Y333196D03*
X1194999Y319547D03*
Y315647D03*
X1181479Y339047D03*
X1178099Y340996D03*
X1205139D03*
X1201759Y339047D03*
X1198379Y333196D03*
X1201759Y335147D03*
Y331247D03*
X1184859Y337096D03*
X1191619Y309797D03*
X1188239Y303947D03*
X1194999Y327347D03*
X1184859Y317596D03*
X1191619D03*
Y305896D03*
Y301996D03*
X1184859Y340996D03*
X1194999Y339047D03*
X1191619Y333196D03*
Y329296D03*
X1188239Y323446D03*
X1184859Y313696D03*
X1188239Y315647D03*
X1198379Y290296D03*
Y294196D03*
X1205439Y286596D03*
X1181479Y284447D03*
X1205439Y294196D03*
X1191619Y282496D03*
Y290296D03*
X1205439D03*
X1191619Y286396D03*
X1178099Y282496D03*
X1205139D03*
X1184859D03*
X1194999Y284447D03*
X1184859Y286396D03*
X1178099Y352696D03*
X1164580Y376096D03*
X1194999Y350747D03*
X1198379Y348796D03*
X1184859Y379996D03*
X1188239Y350747D03*
X1191619Y356596D03*
X1184859Y372197D03*
X1181479Y366347D03*
Y362447D03*
X1188239D03*
Y358547D03*
Y354647D03*
X1198379Y383896D03*
X1191619Y379996D03*
X1184859Y376096D03*
X1198379D03*
X1171339Y391696D03*
X1191619Y344896D03*
X1178099Y376096D03*
X1171339Y395596D03*
X1174719Y389747D03*
X1171339Y383896D03*
X1161200Y389747D03*
X1164580Y395597D03*
X1178099Y387796D03*
X1167960Y346847D03*
X1164580Y360496D03*
X1161200Y366347D03*
X1167960Y354647D03*
X1161200D03*
X1164580Y368296D03*
X1181479Y378047D03*
X1188239Y374146D03*
X1184859Y368296D03*
Y364396D03*
X1181479Y358547D03*
X1184859Y360496D03*
X1167960Y370247D03*
X1164580Y372197D03*
X1171339Y356596D03*
Y360496D03*
X1164580Y356596D03*
X1167960Y342947D03*
X1171339Y348796D03*
X1174719Y354647D03*
Y342947D03*
X1161200Y370247D03*
X1171339Y372197D03*
X1167960Y362447D03*
X1178099Y364396D03*
X1174719Y346847D03*
X1178099Y348796D03*
Y344896D03*
X1167960Y358547D03*
X1171339Y344896D03*
X1174719Y350747D03*
X1167960Y366347D03*
X1171339Y368296D03*
Y399496D03*
X1164580Y403396D03*
X1178099D03*
X1167960Y389747D03*
X1161200Y397546D03*
X1167960Y397547D03*
X1161200Y374146D03*
X1178099Y391696D03*
X1174719Y397546D03*
X1164580Y399496D03*
X1174719Y393647D03*
X1161200Y378047D03*
X1164580Y379996D03*
X1174719Y381947D03*
X1194999Y346847D03*
Y354647D03*
X1209219Y370247D03*
X1212199Y356597D03*
Y344896D03*
Y352696D03*
X1188239Y370247D03*
X1191619Y372197D03*
Y364396D03*
Y352696D03*
X1194999Y342947D03*
X1181479Y346847D03*
X1188239Y366347D03*
X1194999D03*
X1191619Y348796D03*
X1184859Y356596D03*
X1191619Y360496D03*
X1201759Y350747D03*
X1205139Y360496D03*
X1181479Y374146D03*
Y389747D03*
X1209769Y374146D03*
X1184859Y383896D03*
X1188239Y393647D03*
X1201759Y389747D03*
X1197258Y397546D03*
X1194999Y385847D03*
X1188239Y378047D03*
X1201759D03*
X1208819Y393647D03*
Y381897D03*
X1181479Y385847D03*
X1188239Y381947D03*
X1208819Y385847D03*
X1181479Y393647D03*
X1184859Y399496D03*
X1178099Y395596D03*
X1174719Y401447D03*
X1198379Y356596D03*
Y360496D03*
X1181479Y370247D03*
X1174719D03*
X1178099Y360496D03*
X1191619Y383896D03*
X1167960Y381947D03*
X1181479Y342947D03*
X1201759Y346847D03*
X1198379Y344896D03*
X1201759Y342947D03*
X1184859Y387796D03*
X1188239Y385847D03*
Y389747D03*
X1194999Y370247D03*
X1184859Y391696D03*
Y395596D03*
X1181479Y397546D03*
X1178099Y399496D03*
X1171339Y403396D03*
X1198379Y352696D03*
X1201759Y358547D03*
X1194999Y362447D03*
X1198379Y372197D03*
Y364396D03*
X1167960Y401447D03*
X1194999Y374146D03*
X1171339Y364396D03*
X1201759Y374146D03*
X1194999Y378047D03*
X1178099Y372197D03*
X1171339Y376096D03*
X1167960Y374146D03*
X1171339Y379996D03*
X1164580Y383896D03*
X1161200Y381947D03*
X1181479Y350747D03*
Y354647D03*
X1174719Y358547D03*
Y362447D03*
Y366347D03*
X1178099Y356596D03*
X1184859Y348796D03*
X1174719Y374146D03*
Y378047D03*
X1167960D03*
X1188239Y346847D03*
Y342947D03*
X1181479Y381947D03*
X1167960Y385847D03*
X1161200D03*
X1164580Y387796D03*
X1174719Y385847D03*
X1178099Y383896D03*
Y379996D03*
X1161200Y393647D03*
X1184859Y352696D03*
X1198379Y379996D03*
X1194999Y381947D03*
X1167960Y393647D03*
X1184859Y344896D03*
X1171339Y387796D03*
X1197100Y408200D03*
X1198029Y405411D03*
X1195555Y405773D03*
X1192200Y409550D03*
X1185989Y407800D03*
X1181479Y405347D03*
X1174719D03*
X1167960D03*
X1161417Y518157D03*
X1174803D03*
X1177849Y513114D03*
X1180400Y495787D03*
X1167500Y495800D03*
X1174203Y495787D03*
X1161320Y495800D03*
X1170656Y491144D03*
X1164363Y491044D03*
X1177849Y490944D03*
X1170656Y493844D03*
X1164363Y493744D03*
X1177799Y493544D03*
X1168110Y510114D03*
X1164763Y515814D03*
X1161417Y510114D03*
X1177799Y515714D03*
X1171456Y515814D03*
X1174803Y510114D03*
X1168110Y518157D03*
X1171456Y513114D03*
X1208267Y493444D03*
X1200974Y490744D03*
X1193063Y490909D03*
X1187978Y490609D03*
X1184142Y490794D03*
Y493394D03*
X1200974Y493344D03*
X1193063Y493509D03*
X1208267Y496144D03*
X1187978Y495909D03*
X1193063Y496209D03*
X1181346Y510114D03*
X1204400Y495887D03*
X1198100Y495800D03*
X1208267Y515814D03*
X1211614Y510114D03*
X1218157D03*
X1187963Y510098D03*
X1204921Y510114D03*
X1198228D03*
X1201574Y515814D03*
X1184142D03*
X1187939Y517900D03*
X1193039Y510100D03*
X1193063Y518114D03*
X1187978Y498609D03*
X1193063Y498909D03*
X1181496Y518157D03*
X1184142Y513114D03*
X1204921Y518157D03*
X1208267Y513114D03*
X1198228Y518157D03*
X1201574Y513114D03*
X1211614Y518157D03*
X1214874Y512774D03*
X1187963Y515300D03*
X1193063Y512914D03*
X1187963Y512700D03*
X1193063Y515514D03*
X1204400Y498487D03*
X1198100Y498400D03*
X1187978Y493209D03*
X1180400Y498387D03*
X1174203D03*
X1161417Y498487D03*
X1167510D03*
X1218307Y518157D03*
X1164763Y513114D03*
Y535100D03*
X1177763Y534700D03*
X1174803Y528899D03*
X1171456Y550914D03*
X1164763D03*
X1177849D03*
X1161417Y547914D03*
X1168110D03*
X1174803D03*
X1177799Y553514D03*
X1177763Y530949D03*
X1168110Y537049D03*
X1164763Y530949D03*
X1161417Y537049D03*
X1171456Y530949D03*
X1174803Y536999D03*
X1164763Y553614D03*
X1171456D03*
Y535100D03*
X1168110Y528899D03*
X1161417Y566699D03*
X1174803D03*
X1171456Y588714D03*
X1164763D03*
X1177849D03*
X1174803Y574799D03*
X1161417Y574849D03*
X1171456Y568749D03*
X1168110Y585714D03*
X1161417D03*
X1168110Y574849D03*
X1164763Y568749D03*
X1174803Y585714D03*
X1177763Y568749D03*
X1184142Y550914D03*
X1208267D03*
X1201574D03*
X1214874Y550574D03*
X1187963Y553100D03*
X1193063Y550714D03*
Y553314D03*
X1181496Y537049D03*
X1181346Y547914D03*
X1211614Y536999D03*
X1214574Y530949D03*
X1184142Y531100D03*
X1193076Y528936D03*
X1198228Y547914D03*
X1204921D03*
X1201574Y553614D03*
Y530949D03*
X1204921Y537049D03*
X1198228D03*
X1193039Y547900D03*
X1187963Y547898D03*
X1184142Y553614D03*
X1193089Y536750D03*
X1187989Y529150D03*
X1187963Y536999D03*
X1218307Y537049D03*
X1211614Y547914D03*
X1208267Y553614D03*
Y530949D03*
X1218157Y547914D03*
X1184142Y534700D03*
X1181496Y528899D03*
X1208267Y535100D03*
X1204921Y528899D03*
X1201574Y535100D03*
X1198228Y528899D03*
X1218307D03*
X1214574Y534700D03*
X1211614Y528899D03*
X1187989Y531750D03*
X1193063Y534149D03*
X1187963Y534399D03*
X1193063Y531540D03*
X1201574Y588714D03*
X1214660D03*
X1193063Y588514D03*
X1187963Y588300D03*
X1181346Y585714D03*
X1181496Y574849D03*
X1193063Y555914D03*
X1187939Y555700D03*
X1218157Y585714D03*
X1218307Y574849D03*
X1208267Y568749D03*
X1214574D03*
X1211614Y574799D03*
Y585714D03*
X1184142Y568900D03*
X1187989Y566950D03*
X1193076Y566736D03*
X1193039Y585700D03*
X1187963Y585698D03*
X1193089Y574550D03*
X1187963Y574799D03*
X1198228Y585714D03*
Y574849D03*
X1204921Y585714D03*
Y574849D03*
X1201574Y568749D03*
X1181496Y566699D03*
X1204921D03*
X1198228D03*
X1218307Y555957D03*
Y566699D03*
X1211614Y555957D03*
X1214574Y572500D03*
X1211614Y566699D03*
X1187989Y569550D03*
X1193063Y571949D03*
Y569340D03*
X1184142Y588714D03*
X1208267D03*
X1204921Y555957D03*
X1198228D03*
X1187963Y550500D03*
X1184142Y572500D03*
X1201574Y572900D03*
X1187963Y572199D03*
X1208267Y572900D03*
X1181496Y555957D03*
X1174803D03*
X1161417D03*
X1171456Y572900D03*
X1168110Y555957D03*
Y566699D03*
X1177763Y572500D03*
X1164763Y572900D03*
X1161417Y528899D03*
X1181496Y612649D03*
X1218307D03*
X1211614Y612599D03*
X1187963D03*
X1204921Y612649D03*
X1198228D03*
X1168110D03*
X1161417D03*
X1174803Y612599D03*
X1168110Y593757D03*
X1171456Y610700D03*
X1168110Y604499D03*
X1161417Y593757D03*
Y604499D03*
X1174803Y593757D03*
X1177763Y610300D03*
X1174803Y604499D03*
X1171456Y606549D03*
X1164763D03*
Y591414D03*
X1171456D03*
X1177799Y591314D03*
X1177763Y606549D03*
X1204921Y604499D03*
X1198228Y593757D03*
X1201574Y610700D03*
X1198228Y604499D03*
X1218307Y593757D03*
Y604499D03*
X1211614Y593757D03*
X1214574Y610300D03*
X1211614Y604499D03*
X1187963Y590900D03*
X1187989Y607350D03*
X1193063Y609749D03*
X1187963Y609999D03*
X1193063Y591114D03*
Y607140D03*
X1208267Y591414D03*
X1214574Y606549D03*
X1208267D03*
X1187939Y593500D03*
X1184142Y591414D03*
X1193063Y593714D03*
X1187989Y604750D03*
X1193076Y604536D03*
X1193089Y612350D03*
X1184142Y606700D03*
X1201574Y591414D03*
Y606549D03*
X1181496Y593757D03*
X1184142Y610300D03*
X1181496Y604499D03*
X1208267Y610700D03*
X1204921Y593757D03*
X1164763Y610700D03*
X1238385Y29949D03*
Y14814D03*
X1245078Y29949D03*
Y14814D03*
X1251771Y16999D03*
X1248425Y27899D03*
X1269700Y13078D03*
X1267960Y28494D03*
X1241732Y27899D03*
X1251771D03*
X1248425Y17057D03*
X1258464Y27899D03*
X1261811D03*
Y16999D03*
X1258464D03*
X1265157Y27899D03*
Y16999D03*
X1241732Y-1751D03*
X1238385Y-7851D03*
X1241732Y9114D03*
X1248425Y-1751D03*
Y-9901D03*
X1251771D03*
X1245078Y-7851D03*
X1248425Y9157D03*
X1269800Y-5822D03*
X1265157Y9157D03*
X1261000Y9100D03*
X1258464Y9157D03*
X1251771D03*
Y-1743D03*
X1261811Y-9901D03*
X1258464D03*
X1261811Y-1743D03*
X1265157D03*
X1258464D03*
X1265157Y-9901D03*
X1276346Y-10250D03*
X1278900Y-14800D03*
X1235039Y9114D03*
X1224774Y9098D03*
X1224822Y-9700D03*
X1229887Y-9864D03*
X1224774Y-1801D03*
X1235039Y-1751D03*
X1229922Y-2000D03*
X1220953Y-7700D03*
Y33700D03*
X1235039Y27899D03*
X1224800Y30750D03*
X1229874Y30540D03*
X1224774Y33399D03*
X1229874Y33149D03*
X1229800Y9300D03*
X1224790Y16900D03*
X1229874Y17114D03*
X1229887Y27936D03*
X1220953Y30100D03*
X1224800Y28100D03*
X1220953Y14814D03*
Y-4100D03*
X1245078Y-3700D03*
X1241732Y-9901D03*
X1238385Y-3700D03*
X1235039Y-9901D03*
X1224800Y-7050D03*
X1229874Y-7260D03*
X1224774Y-4401D03*
X1229874Y-4651D03*
X1255118Y-9901D03*
Y-1743D03*
X1220953Y12114D03*
X1241732Y17157D03*
X1245078Y12114D03*
X1235039Y17157D03*
X1238385Y12114D03*
X1224774Y14300D03*
X1229874Y14514D03*
X1224774Y11700D03*
X1229874Y11914D03*
X1255118Y27899D03*
Y16999D03*
Y9157D03*
X1241732Y36049D03*
Y46914D03*
X1238385Y52614D03*
Y67749D03*
X1245078Y52614D03*
X1251771Y65699D03*
X1248425D03*
Y36049D03*
Y46957D03*
X1245078Y67749D03*
X1267976Y73676D03*
X1268022Y54443D03*
X1241732Y65699D03*
Y54957D03*
X1245078Y34100D03*
Y49914D03*
X1238385Y34100D03*
Y49914D03*
X1251771Y36057D03*
Y54799D03*
X1248425Y54857D03*
X1251771Y46957D03*
X1258464D03*
Y36057D03*
Y54799D03*
X1261811Y46957D03*
Y54799D03*
X1265157Y36057D03*
X1261811D03*
X1265157Y46957D03*
X1261811Y65699D03*
X1258464D03*
X1265157D03*
X1267959Y47245D03*
X1268111Y58040D03*
X1241732Y92757D03*
X1245078Y71900D03*
Y87714D03*
X1238385Y71900D03*
Y87714D03*
X1251771Y84757D03*
X1248425Y92657D03*
X1265157Y73857D03*
X1261811D03*
X1258464D03*
X1261811Y84757D03*
X1258464D03*
X1265157D03*
X1251771Y73857D03*
X1261811Y92599D03*
X1258464D03*
X1241732Y84714D03*
Y73849D03*
X1238385Y90414D03*
X1251771Y92599D03*
X1245078Y90414D03*
X1248425Y84757D03*
Y73849D03*
X1268581Y92706D03*
X1220953Y49914D03*
X1235039Y54957D03*
X1224774Y52100D03*
X1229874Y52314D03*
X1224774Y49500D03*
X1229874Y49714D03*
X1224774Y84698D03*
X1224750Y92500D03*
X1224774Y73799D03*
X1235039Y84714D03*
Y73849D03*
X1220953Y71500D03*
Y87714D03*
X1235039Y92757D03*
X1224774Y89900D03*
X1229874Y70949D03*
Y87514D03*
X1224774Y71199D03*
Y87300D03*
X1229800Y35750D03*
X1229874Y54914D03*
X1235039Y46914D03*
Y36049D03*
X1224774Y46898D03*
X1220953Y52614D03*
X1224774Y35999D03*
X1229887Y65736D03*
X1224800Y65950D03*
X1220953Y67900D03*
X1235039Y65699D03*
X1224800Y68550D03*
X1229874Y68340D03*
Y90114D03*
X1229900Y73550D03*
X1229850Y84700D03*
X1229874Y92714D03*
X1220953Y90414D03*
X1255118Y65699D03*
Y54799D03*
Y36057D03*
Y46957D03*
X1265157Y54799D03*
X1255118Y92599D03*
Y84757D03*
Y73857D03*
X1265157Y92599D03*
X1240927Y154932D03*
X1243948Y154916D03*
X1251344Y127925D03*
X1277100Y122670D03*
X1264550Y114670D03*
X1277100Y114800D03*
X1261030Y105350D03*
X1268900Y122500D03*
X1270350Y98300D03*
X1277600Y106200D03*
X1268576Y117788D03*
X1275470Y99390D03*
X1266200Y122500D03*
X1254024Y128013D03*
X1246251Y130066D03*
X1257800Y110900D03*
X1260500Y117500D03*
X1247326Y122802D03*
X1254300Y105200D03*
X1277660Y109450D03*
X1277230Y117570D03*
X1278030Y148510D03*
X1237704Y148423D03*
X1269810Y154398D03*
X1249025Y130460D03*
X1263798Y133493D03*
X1278000Y145780D03*
X1268236Y141938D03*
X1272100Y141603D03*
X1265828Y140568D03*
X1237400Y103100D03*
X1268600Y104700D03*
X1266646Y150540D03*
X1257850Y116950D03*
Y113850D03*
X1255400Y108000D03*
X1259950Y144650D03*
X1264700Y154800D03*
X1240022Y141773D03*
X1261546Y150584D03*
X1264146D03*
X1268500Y102100D03*
X1271500D03*
X1240000Y129500D03*
X1271500Y122500D03*
X1271490Y104700D03*
X1221767Y175858D03*
X1233902Y173337D03*
X1240309Y161900D03*
X1267050Y169800D03*
X1241381Y172040D03*
X1246655Y176395D03*
X1244410Y173150D03*
X1246910D03*
X1242800Y175200D03*
X1263080Y191320D03*
X1260140Y191670D03*
X1263300Y169450D03*
X1241712Y187710D03*
X1259200Y168350D03*
X1252800Y176000D03*
X1255200D03*
X1267800Y161800D03*
X1271400Y161900D03*
X1260510Y206840D03*
X1267220Y203600D03*
X1267218Y207495D03*
X1258810Y204840D03*
X1263728Y211444D03*
X1262250Y201227D03*
X1265718Y201459D03*
X1258482Y201495D03*
X1257770Y199150D03*
X1260260Y199862D03*
X1264180Y199510D03*
X1240500Y218200D03*
X1240452Y208240D03*
Y215740D03*
Y213240D03*
Y210740D03*
X1243196Y207002D03*
X1242800Y204150D03*
X1244380Y202160D03*
X1255310Y193850D03*
X1252930Y193270D03*
X1263040Y193930D03*
X1259360Y193950D03*
X1257210Y192340D03*
X1268986Y205727D03*
X1269254Y197923D03*
X1270930Y200220D03*
X1268930Y201820D03*
X1272522Y202191D03*
X1270754Y203959D03*
X1267486Y199691D03*
X1262018Y197959D03*
X1265786Y197691D03*
X1259518Y197459D03*
X1263950Y203227D03*
X1260620Y203130D03*
X1255982Y200995D03*
X1255833Y197423D03*
X1256810Y203340D03*
X1262182Y204995D03*
X1265420Y205400D03*
X1250235Y199342D03*
X1251940Y197530D03*
X1247803Y198486D03*
X1254065Y199191D03*
X1252330Y201030D03*
X1254310Y202840D03*
X1250625Y202804D03*
X1248290Y201720D03*
X1246620Y203570D03*
X1246090Y200330D03*
X1245014Y205405D03*
X1251089Y194810D03*
X1249571Y196718D03*
X1253521Y195666D03*
X1267554Y195923D03*
X1261220Y195650D03*
X1263804Y196318D03*
X1265570Y194510D03*
X1257601Y195655D03*
X1262080Y209140D03*
X1265450Y209263D03*
X1263680Y207160D03*
X1229780Y181980D03*
Y178980D03*
X1232780Y181980D03*
X1226914Y184708D03*
X1232780Y178980D03*
X1226780D03*
Y181980D03*
X1226785Y210403D03*
X1221300Y205400D03*
X1226500Y199800D03*
X1226867Y207904D03*
X1220167Y194407D03*
X1227200Y215543D03*
X1220702Y216708D03*
X1226785Y213003D03*
X1221300Y208000D03*
X1226500Y202400D03*
X1243300Y223100D03*
X1268404Y246304D03*
X1277504Y250346D03*
X1275154Y236296D03*
X1279950Y229338D03*
X1276628Y234270D03*
X1272761Y240220D03*
X1278183Y231886D03*
X1274100Y255300D03*
X1275577Y253123D03*
X1251395Y226373D03*
X1253791Y226228D03*
X1248672Y226494D03*
X1252221Y228668D03*
X1245300Y224800D03*
X1220017Y220323D03*
X1220194Y243384D03*
X1223100Y258600D03*
X1223508Y262600D03*
X1270478Y243490D03*
X1279393Y247602D03*
X1225908Y259300D03*
Y261800D03*
X1243399Y398339D03*
X1249230Y402022D03*
X1246010Y400110D03*
X1262700Y461804D03*
X1259800Y463300D03*
X1255530Y474770D03*
X1277978Y491571D03*
X1258140Y474540D03*
X1271571Y479000D03*
X1271662Y487326D03*
X1271640Y474420D03*
X1271647Y482500D03*
X1269050Y486650D03*
X1269600Y480800D03*
X1272830Y471660D03*
X1257720Y493060D03*
X1255388Y483557D03*
X1256130Y467820D03*
X1265157Y510157D03*
X1261811Y517999D03*
X1258464Y510157D03*
Y517999D03*
X1261811Y510157D03*
X1248425Y518057D03*
X1251771Y510157D03*
X1262843Y497553D03*
X1277800Y497108D03*
X1280595Y496439D03*
X1266162Y496404D03*
X1269006Y496016D03*
X1241732Y510114D03*
X1238385Y515814D03*
X1269000Y514700D03*
X1245078Y515814D03*
X1251771Y517999D03*
X1248425Y510157D03*
X1241732Y518157D03*
X1245078Y513114D03*
X1238385D03*
X1278573Y519596D03*
X1235039Y510114D03*
X1220953Y515814D03*
X1229874Y518114D03*
X1229850Y510100D03*
X1224750Y517900D03*
X1224774Y510098D03*
X1220953Y513114D03*
X1235039Y518157D03*
X1224774Y515300D03*
X1229874Y512914D03*
X1224774Y512700D03*
X1229874Y515514D03*
X1274576Y510235D03*
X1267584Y499694D03*
X1271105Y498516D03*
X1271300Y510600D03*
X1269209Y501777D03*
X1255120Y510158D03*
Y518000D03*
X1248474Y488913D03*
X1249193Y491308D03*
X1265157Y517999D03*
X1262900Y466504D03*
X1256320Y490660D03*
X1258126Y469540D03*
X1256350Y486080D03*
X1255120Y574834D03*
X1265157Y547957D03*
X1261811D03*
X1258464D03*
X1251771D03*
X1265157Y537057D03*
X1261811D03*
X1258464Y528899D03*
X1251771Y537057D03*
X1258464D03*
X1261811Y528899D03*
X1265157Y528876D03*
X1277200Y539100D03*
X1277137Y547393D03*
X1279318Y545212D03*
X1241732Y547914D03*
Y537049D03*
X1238385Y530949D03*
Y553614D03*
X1269800Y532978D03*
X1251771Y528899D03*
X1248425Y537049D03*
Y528899D03*
X1245078Y553614D03*
Y530949D03*
X1248425Y547957D03*
X1245078Y535100D03*
X1241732Y528899D03*
X1238385Y535100D03*
X1245078Y550914D03*
X1238385D03*
X1241732Y574849D03*
Y585714D03*
X1238385Y568749D03*
X1268500Y555800D03*
X1267900Y574300D03*
X1248425Y585757D03*
Y574849D03*
Y566699D03*
X1245078Y568749D03*
X1241732Y555957D03*
X1245078Y572900D03*
X1241732Y566699D03*
X1238385Y572900D03*
X1245078Y588714D03*
X1238385D03*
X1265157Y585757D03*
X1261811D03*
X1258464D03*
X1251771D03*
X1261811Y555799D03*
X1258464D03*
X1251771D03*
X1248425Y555857D03*
X1251771Y566699D03*
Y574857D03*
X1265157D03*
X1261811D03*
X1258464D03*
X1261811Y566699D03*
X1258464D03*
X1273200Y582200D03*
X1265157Y566676D03*
Y555799D03*
X1220953Y550914D03*
X1229874Y550714D03*
X1224774Y550500D03*
X1229874Y553314D03*
X1220953Y531100D03*
X1229887Y528936D03*
X1229900Y536750D03*
X1224800Y529150D03*
X1224774Y536999D03*
X1235039Y537049D03*
Y547914D03*
X1229850Y547900D03*
X1224774Y547898D03*
X1220953Y553614D03*
X1235039Y528899D03*
X1224800Y531750D03*
X1229874Y534149D03*
X1224774Y534399D03*
X1229874Y531540D03*
X1220953Y588714D03*
X1229874Y588514D03*
X1224774Y588300D03*
X1229874Y555914D03*
X1224750Y555700D03*
X1220953Y568900D03*
X1229900Y574550D03*
X1224774Y574799D03*
X1229850Y585700D03*
X1224774Y585698D03*
X1229887Y566736D03*
X1224800Y566950D03*
X1235039Y585714D03*
Y574849D03*
X1220953Y572500D03*
X1235039Y555957D03*
Y566699D03*
X1229874Y571949D03*
X1224774Y572199D03*
X1229874Y569340D03*
X1255120Y537034D03*
Y555144D03*
X1224774Y553100D03*
X1224800Y569550D03*
X1220953Y534700D03*
X1265157Y604476D03*
Y593599D03*
X1241732Y612649D03*
X1238385Y606549D03*
Y591414D03*
X1263800Y606800D03*
X1267800Y593600D03*
X1248425Y612649D03*
X1251771Y604499D03*
X1248425D03*
X1245078Y606549D03*
X1251771Y593599D03*
X1245078Y591414D03*
X1270400Y593600D03*
X1241732Y593757D03*
X1245078Y610700D03*
X1241732Y604499D03*
X1238385Y610700D03*
X1258464Y593599D03*
X1261811D03*
X1248425Y593657D03*
X1251771Y612657D03*
X1258464Y604499D03*
X1261811D03*
X1265157Y612657D03*
X1261811D03*
X1258464D03*
X1224774Y612599D03*
X1235039Y612649D03*
X1220953Y610300D03*
X1235039Y593757D03*
Y604499D03*
X1224774Y590900D03*
X1224800Y607350D03*
X1229874Y609749D03*
X1224774Y609999D03*
X1229874Y591114D03*
Y607140D03*
X1220953Y591414D03*
X1229874Y593714D03*
X1224750Y593500D03*
X1224800Y604750D03*
X1229887Y604536D03*
X1220953Y606700D03*
X1229900Y612350D03*
X1255120Y612634D03*
Y593600D03*
X1301279Y10058D03*
X1304079D03*
X1306879D03*
X1301200Y12610D03*
X1306800D03*
X1303774Y-18842D03*
X1299549Y-18619D03*
X1287700Y-16700D03*
X1292692Y1008D03*
X1299369Y-15680D03*
X1293600Y-17000D03*
X1293816Y-13533D03*
X1282252Y-14747D03*
X1284859Y-14524D03*
X1301200Y15200D03*
X1301100Y2700D03*
X1316300Y-14800D03*
X1320800Y-16900D03*
X1307900Y-14700D03*
X1309500Y-16800D03*
X1323600Y-16900D03*
X1322000Y-14800D03*
X1324800D03*
X1326000Y-12700D03*
X1323600Y-12600D03*
X1327600Y-14800D03*
Y4700D03*
X1326400Y2600D03*
X1324800Y4700D03*
X1322000D03*
X1323600Y2600D03*
X1306700Y2700D03*
X1309500D03*
X1307900Y4800D03*
X1320800Y2600D03*
X1316300Y4700D03*
X1317900Y2600D03*
X1319200Y4700D03*
X1313500Y4800D03*
X1315004Y2567D03*
X1326400Y-16900D03*
X1302300Y4800D03*
X1303900Y2700D03*
X1310700Y4800D03*
X1312300Y2700D03*
X1305100Y4800D03*
X1322532Y9822D03*
X1325332D03*
X1306700Y-16800D03*
X1328800Y-12700D03*
X1312300Y-16800D03*
X1310700Y-14700D03*
X1315004Y-16933D03*
X1313500Y-14700D03*
X1319200Y-14800D03*
X1317900Y-16900D03*
X1321452Y31803D03*
X1304000Y15200D03*
X1328085Y9865D03*
X1322483Y12834D03*
X1328045Y15831D03*
X1325308Y15734D03*
X1322508D03*
X1328123Y12730D03*
X1306800Y15200D03*
X1328987Y2525D03*
X1313942Y30714D03*
X1309760Y30691D03*
X1316300Y31911D03*
X1318700Y31943D03*
X1311809Y32096D03*
X1325383Y12634D03*
X1304940Y32350D03*
X1304000Y12610D03*
X1336500Y81100D03*
X1320000Y85500D03*
X1327168Y61483D03*
X1296935Y51335D03*
X1296908Y36900D03*
X1296928Y48700D03*
X1295581Y94320D03*
X1298422Y74000D03*
X1298754Y83233D03*
X1301219Y89141D03*
X1301000Y62000D03*
X1323500Y68000D03*
X1318341Y60000D03*
X1321841Y63000D03*
X1304000Y62000D03*
X1308983Y93814D03*
X1304500Y40066D03*
X1324127Y50827D03*
X1327452Y55544D03*
X1327500Y51547D03*
X1310600Y41500D03*
X1308100D03*
X1323400Y41439D03*
X1326000D03*
X1326058Y43956D03*
X1323400Y43839D03*
X1318341Y63000D03*
X1341400Y46100D03*
X1309700Y83300D03*
X1317195Y87098D03*
X1311559Y91431D03*
X1311551Y93952D03*
X1304685Y78827D03*
X1336850Y76450D03*
X1317300Y89600D03*
X1330300Y83500D03*
X1336900Y89896D03*
X1323500Y75000D03*
Y71500D03*
X1308400Y79600D03*
X1317300Y84600D03*
X1327500Y68000D03*
X1327467Y70786D03*
X1327500Y65300D03*
X1327900Y142918D03*
X1310175Y154696D03*
X1286116Y118932D03*
Y115932D03*
X1295581Y97320D03*
X1293700Y121800D03*
X1288381Y97320D03*
X1291381D03*
X1295240Y149830D03*
X1295172Y153670D03*
X1291735Y150061D03*
X1291772Y153694D03*
X1293335Y148177D03*
X1293543Y151756D03*
X1287790Y156575D03*
X1295700Y144450D03*
X1286000Y134500D03*
Y139500D03*
Y137000D03*
X1298400Y144500D03*
X1288500Y137000D03*
Y139500D03*
Y134500D03*
X1286000Y132000D03*
X1288500D03*
X1308972Y96742D03*
X1338500Y96000D03*
X1302526Y119102D03*
X1302504Y116700D03*
Y111700D03*
Y114300D03*
X1325125Y100001D03*
X1322628Y100134D03*
X1323800Y104250D03*
X1326800D03*
Y107250D03*
X1323800D03*
X1326600Y123450D03*
X1323600D03*
X1326600Y126450D03*
X1323600D03*
X1340100Y145000D03*
X1301770Y101300D03*
X1310098Y150040D03*
X1335100Y155000D03*
Y145000D03*
X1330100Y150000D03*
X1340100D03*
Y155000D03*
X1315100Y145000D03*
X1335100Y150000D03*
X1330100Y145000D03*
Y155000D03*
X1323026Y133323D03*
X1326026D03*
X1306900Y131744D03*
X1301900Y124400D03*
X1320500Y145000D03*
X1295500Y159970D03*
X1299907Y159808D03*
X1330100Y165000D03*
Y170000D03*
X1340100Y165000D03*
Y170000D03*
X1335100D03*
Y165000D03*
X1320100D03*
X1325100D03*
X1320100Y170000D03*
X1325100D03*
X1310061Y165235D03*
X1305171Y164767D03*
X1330100Y160000D03*
X1340100D03*
X1306363Y169928D03*
X1335100Y160000D03*
X1323030Y216531D03*
X1329324Y208951D03*
X1338224Y209051D03*
X1334724D03*
X1326474Y216500D03*
X1331824Y209051D03*
X1324938Y209251D03*
X1322500D03*
X1320390Y216824D03*
X1333074Y216500D03*
X1336074D03*
X1300300Y169900D03*
X1303838Y169922D03*
X1330074Y216500D03*
X1283720Y223870D03*
X1288800Y233900D03*
X1300444Y267919D03*
X1336900Y232118D03*
X1325900D03*
X1314900D03*
X1342400D03*
X1331400D03*
X1320400D03*
X1309462Y240229D03*
X1320400Y234959D03*
X1325900D03*
X1314900D03*
X1336900D03*
X1331400D03*
X1342400D03*
X1334113Y273115D03*
X1340866Y268795D03*
X1327625Y275971D03*
X1330039Y279618D03*
X1308200Y255800D03*
X1310950Y255650D03*
X1315100Y237645D03*
X1325900Y237900D03*
X1342400D03*
X1331400D03*
X1320289Y237671D03*
X1323734Y279663D03*
X1330171Y276035D03*
X1336448Y271755D03*
X1340248D03*
X1333680Y276035D03*
X1327243Y279663D03*
X1336900Y237900D03*
X1319310Y300795D03*
X1299700Y298557D03*
X1299735Y301298D03*
X1336480Y309755D03*
X1336793Y303784D03*
X1342500Y312100D03*
X1316300Y282000D03*
X1325300Y282600D03*
X1314792Y286427D03*
X1314490Y283862D03*
X1335400Y284900D03*
X1334400Y292050D03*
X1337200Y292012D03*
X1336240Y301243D03*
X1341740D03*
X1323688Y290205D03*
X1303866Y292345D03*
X1305558Y294313D03*
X1306290Y298255D03*
X1303380Y309441D03*
X1302768Y296942D03*
X1319297Y296878D03*
X1321600Y294700D03*
X1338700Y284700D03*
X1305873Y309245D03*
X1305950Y306611D03*
X1341920Y309755D03*
X1342480Y303852D03*
X1302203Y314439D03*
X1331720Y334810D03*
X1326300Y341309D03*
X1320900Y321300D03*
X1323750Y319750D03*
X1331650Y317250D03*
X1319906Y338025D03*
X1338500Y319600D03*
X1318751Y282730D03*
X1322260D03*
X1336240Y306760D03*
X1341740D03*
X1319888Y290205D03*
X1341375Y314675D03*
Y319675D03*
X1326014Y347732D03*
X1342570Y368220D03*
X1330100Y350100D03*
X1332600Y349900D03*
X1315496Y361190D03*
X1332613Y346417D03*
X1329757Y346511D03*
X1341954Y360368D03*
X1335250Y344250D03*
X1331770Y399490D03*
X1332650Y374450D03*
X1317788Y402562D03*
Y400062D03*
X1331856Y401995D03*
X1329064Y399556D03*
X1329288Y402062D03*
X1330200Y377300D03*
X1330758Y389785D03*
Y386785D03*
Y383785D03*
X1324872Y380682D03*
X1322054Y380560D03*
X1324872Y383682D03*
X1327800Y383500D03*
X1325000Y377500D03*
X1327600Y377400D03*
X1319300Y378500D03*
X1327700Y380400D03*
X1322100Y377800D03*
X1323288Y402062D03*
X1323064Y399556D03*
X1320423Y399579D03*
X1320288Y402062D03*
X1326288D03*
X1326064Y399556D03*
X1332600Y377200D03*
X1332748Y380503D03*
X1330190Y380406D03*
X1336886Y351113D03*
X1339597Y349756D03*
X1335100Y427500D03*
X1329419Y464337D03*
X1323815Y463543D03*
X1318054Y460507D03*
X1285769Y440062D03*
X1341528Y463528D03*
X1321172Y464474D03*
X1288671Y445338D03*
X1326626Y464400D03*
X1296468Y437500D03*
X1300100Y442500D03*
X1301000Y460900D03*
X1300438Y433001D03*
X1300315Y427902D03*
X1305100Y432500D03*
X1320100Y427500D03*
Y432500D03*
X1325100Y427500D03*
Y432500D03*
X1305181Y427834D03*
X1310100Y427500D03*
Y432500D03*
X1315100Y427500D03*
Y432500D03*
X1340100Y427500D03*
X1330100Y432500D03*
Y427500D03*
X1340100Y432500D03*
X1335100D03*
X1319320Y418900D03*
X1334889Y421400D03*
X1332236Y419004D03*
X1329400Y404524D03*
X1329736Y419004D03*
X1329889Y421400D03*
X1332389D03*
X1331973Y404580D03*
X1322370Y421400D03*
X1324889Y421470D03*
X1320400Y404524D03*
X1326400D03*
X1323400D03*
X1324736Y419074D03*
X1322217Y419004D03*
X1327236Y419030D03*
X1327389Y421426D03*
X1334967Y419001D03*
X1325100Y457500D03*
Y452500D03*
X1320100Y457500D03*
Y452500D03*
X1315100D03*
X1310100D03*
X1315100Y457500D03*
X1305100D03*
Y452500D03*
X1310100Y457500D03*
X1330100D03*
Y452500D03*
X1335100Y457500D03*
Y452500D03*
Y447500D03*
Y442500D03*
X1330100D03*
X1305100D03*
X1310100D03*
X1320100D03*
X1315100D03*
X1325100D03*
X1340100Y457500D03*
Y452500D03*
Y447500D03*
Y442500D03*
X1304200Y462030D03*
X1316820Y421400D03*
Y418900D03*
X1286831Y443058D03*
X1337100Y499300D03*
X1319738Y477497D03*
X1322360Y472592D03*
X1322260Y477492D03*
X1326877Y469279D03*
X1319699Y472327D03*
X1297878Y493150D03*
X1295240Y493359D03*
X1290500Y480200D03*
Y482700D03*
X1299450Y484950D03*
X1295960Y519450D03*
Y516450D03*
Y513450D03*
X1295880Y510810D03*
X1298460Y513450D03*
Y516450D03*
Y519450D03*
X1298380Y510810D03*
X1301000Y466500D03*
X1301240Y476228D03*
X1304200Y466600D03*
X1320300Y498300D03*
X1335100Y507700D03*
X1332500Y509100D03*
X1339600Y515800D03*
X1341050Y498275D03*
X1334300Y499300D03*
X1340986Y511187D03*
X1313700Y515200D03*
Y517800D03*
X1309870Y499254D03*
X1319300Y525450D03*
X1321800D03*
X1311772Y501000D03*
X1319075D03*
X1316675Y500983D03*
X1314272Y501000D03*
X1329419Y469337D03*
X1287770Y501897D03*
X1339900Y518900D03*
X1308500Y540784D03*
X1305500Y542500D03*
X1295660Y527700D03*
X1298460Y536700D03*
Y530700D03*
Y533700D03*
Y527700D03*
X1295660Y536700D03*
Y530700D03*
Y533700D03*
X1285400Y561000D03*
X1282600Y581000D03*
Y583600D03*
X1295090Y579360D03*
X1293290Y581160D03*
X1290900Y563300D03*
X1288100Y562000D03*
X1300000Y552400D03*
Y558400D03*
Y555400D03*
X1343100Y566300D03*
X1340700D03*
X1338000D03*
X1340526Y563337D03*
X1343026D03*
X1338026D03*
X1333026D03*
X1335526D03*
Y566237D03*
X1318500Y539900D03*
X1327956Y545655D03*
X1317500Y552400D03*
X1320500D03*
X1323500D03*
X1324707Y545493D03*
X1316100Y543400D03*
X1321800Y532750D03*
X1319300Y532650D03*
X1321800Y527850D03*
X1319300D03*
Y530250D03*
X1321800D03*
X1317500Y555400D03*
X1320500D03*
X1323500D03*
X1303000Y576000D03*
Y579000D03*
Y571400D03*
Y568900D03*
Y565900D03*
Y563400D03*
X1306000Y579000D03*
X1323774Y563145D03*
Y566145D03*
X1309000Y565900D03*
Y563400D03*
Y571400D03*
X1306000Y568900D03*
X1309000D03*
X1306000Y576000D03*
X1324000Y568900D03*
X1306000Y571400D03*
X1321000D03*
X1324000D03*
X1321000Y568900D03*
X1318000D03*
X1312000D03*
X1318000Y571400D03*
X1315000D03*
Y568900D03*
X1312000Y571400D03*
X1320500Y558400D03*
X1317500D03*
X1312000Y563400D03*
Y565900D03*
X1315000Y563400D03*
Y565900D03*
X1323500Y558400D03*
X1318000Y563400D03*
Y565900D03*
X1321000Y563400D03*
Y565900D03*
X1306000D03*
Y563400D03*
X1333026Y566237D03*
X1292190Y576952D03*
X1290292Y578962D03*
X1298100Y598300D03*
Y595800D03*
Y590000D03*
Y592500D03*
X1296295Y615596D03*
X1311876Y619501D03*
X1314476D03*
X1307600Y620100D03*
X1301384Y618119D03*
X1306600Y610000D03*
X1306556Y607558D03*
X1324200Y610100D03*
Y600100D03*
Y597600D03*
X1321100Y598500D03*
Y601000D03*
X1315100Y598500D03*
Y601000D03*
X1312100Y598500D03*
X1309100D03*
Y601000D03*
X1312100D03*
X1318100Y598500D03*
Y601000D03*
X1324200Y602700D03*
Y605100D03*
Y607500D03*
X1402600Y10000D03*
X1400100D03*
X1357400Y-19800D03*
X1360400Y10600D03*
X1350654Y-18411D03*
X1348154Y-15911D03*
Y-18411D03*
X1357600Y5140D03*
X1345518Y-18476D03*
X1353154Y-18411D03*
X1376094Y4406D03*
X1380008Y-3805D03*
X1366789Y5776D03*
X1375676Y7630D03*
X1385608Y-17485D03*
X1388294Y-5675D03*
X1389523Y4966D03*
X1380678Y-422D03*
X1380300Y2944D03*
X1374100Y-16900D03*
X1376719Y-16802D03*
X1382151Y-5545D03*
X1369389Y5776D03*
X1380950Y30232D03*
X1376842Y15185D03*
X1374431Y15170D03*
X1381642Y25898D03*
X1400616Y13795D03*
X1379200Y27000D03*
X1355950Y-16507D03*
X1359450Y-7D03*
X1355950D03*
X1357489Y-1924D03*
X1359450Y2493D03*
X1355950D03*
X1357489Y-14424D03*
Y-10524D03*
Y-6124D03*
X1355889Y-8524D03*
X1355847Y-12275D03*
X1355989Y-3924D03*
X1356261Y32017D03*
X1356300Y20100D03*
X1356376Y24167D03*
X1356200Y28200D03*
X1357900Y30200D03*
X1357800Y26100D03*
X1357803Y22200D03*
X1356261Y15517D03*
X1357700Y17800D03*
X1359761Y32317D03*
X1371650Y-907D03*
X1371589Y-3424D03*
Y-5924D03*
X1371900Y28600D03*
X1371598Y-11633D03*
X1371632Y-9191D03*
X1371653Y-16654D03*
X1371605Y-14069D03*
X1371941Y22617D03*
X1371950Y20200D03*
X1371900Y17800D03*
Y15400D03*
Y26100D03*
Y31100D03*
X1380219Y5581D03*
X1369408Y50479D03*
X1351908Y40402D03*
X1362448Y43413D03*
X1375412Y92182D03*
X1378464Y91979D03*
X1371500Y63200D03*
X1375500Y76000D03*
X1397500Y51000D03*
X1365855Y46972D03*
X1359800Y37300D03*
X1357300D03*
X1361634Y95519D03*
X1347000Y87500D03*
X1343500D03*
X1360700Y86550D03*
X1351500Y83000D03*
X1344000D03*
X1402700Y51100D03*
X1381817Y46484D03*
X1388627Y35032D03*
X1380500Y54500D03*
X1380900Y59820D03*
X1372400Y37785D03*
X1376989Y46971D03*
X1397550Y68059D03*
X1395050D03*
X1397050Y58559D03*
X1392050D03*
X1394550D03*
X1397050Y55559D03*
X1394550D03*
X1392050D03*
X1397539Y65098D03*
X1394939D03*
X1392339D03*
X1369700Y37800D03*
X1377009Y39753D03*
X1367100Y37800D03*
X1389138Y58499D03*
X1395000Y78800D03*
X1397400D03*
X1392584Y78798D03*
X1395000Y76200D03*
X1392584D03*
X1397400D03*
X1367700Y86450D03*
X1403746Y91680D03*
X1370100Y82500D03*
X1366100D03*
X1364700Y86550D03*
X1389068Y78556D03*
X1389100Y74600D03*
X1359500Y83000D03*
X1355500D03*
X1350830Y60730D03*
X1356261Y34517D03*
X1356950Y54370D03*
X1356760Y66660D03*
X1357000Y60500D03*
X1359761Y34817D03*
X1350800Y66600D03*
X1351190Y54710D03*
X1363170Y54280D03*
X1362900Y60500D03*
X1363040Y66660D03*
X1362674Y46058D03*
X1356230Y126500D03*
X1359230D03*
X1360730Y129000D03*
X1362230Y126500D03*
X1355100Y155000D03*
Y145000D03*
Y150000D03*
X1360100Y155000D03*
Y145000D03*
Y150000D03*
X1345000Y104500D03*
X1361634Y97919D03*
X1345100Y150000D03*
X1350100Y155000D03*
Y150000D03*
Y145000D03*
X1345100D03*
Y155000D03*
X1404200Y119200D03*
X1398600Y116500D03*
X1371500Y101000D03*
X1374808Y99366D03*
X1388100Y108500D03*
X1377308Y106866D03*
Y104366D03*
Y101866D03*
X1374808Y106866D03*
Y104366D03*
Y101866D03*
X1381359Y108496D03*
X1384600Y108500D03*
X1394298Y108548D03*
X1394310Y111506D03*
X1391359Y108496D03*
X1400300Y121500D03*
X1396780Y119080D03*
X1401200Y124300D03*
X1399400Y126400D03*
X1394700Y122950D03*
X1391700D03*
Y125950D03*
X1394700D03*
Y128950D03*
X1391700D03*
X1397994Y103350D03*
X1397952Y105998D03*
X1395326Y100913D03*
Y103413D03*
X1395347Y106040D03*
X1386700Y125450D03*
Y128450D03*
X1383700Y125450D03*
Y128450D03*
X1380700Y125450D03*
Y128450D03*
X1376100Y116100D03*
X1376669Y121763D03*
Y118763D03*
X1376100Y124950D03*
X1373850Y114450D03*
X1369730Y129000D03*
X1363730D03*
X1366730D03*
X1373850Y117450D03*
X1368230Y126500D03*
X1373850Y123450D03*
X1365230Y126500D03*
X1397193Y112602D03*
X1394253Y116989D03*
X1401300Y149600D03*
X1385100Y155000D03*
X1375100D03*
X1365100D03*
X1380100D03*
Y145000D03*
X1385100D03*
X1380100Y150000D03*
X1385100D03*
X1365100Y145000D03*
Y150000D03*
X1375100D03*
X1370100Y155000D03*
Y145000D03*
X1375100D03*
X1370100Y150000D03*
X1402500Y116300D03*
X1352200Y104950D03*
Y108400D03*
X1357700D03*
Y104950D03*
X1350100Y170000D03*
X1360100Y160000D03*
X1355100D03*
Y170000D03*
X1360100D03*
X1355100Y165000D03*
X1360100D03*
X1345100D03*
X1350100D03*
X1345100Y170000D03*
Y160000D03*
X1350100D03*
X1344462Y209272D03*
X1365100Y170000D03*
Y165000D03*
X1370100D03*
X1375100Y170000D03*
X1370100D03*
X1375100Y165000D03*
X1380100Y170000D03*
X1402020Y165561D03*
X1399100Y166900D03*
X1390100Y160000D03*
X1370100D03*
X1390100Y170000D03*
X1385100Y160000D03*
Y165000D03*
Y170000D03*
X1365100Y160000D03*
X1375100D03*
X1390100Y165000D03*
X1403400Y204766D03*
X1384671Y214832D03*
X1367789Y209216D03*
X1396933Y215763D03*
X1359500Y209200D03*
X1356926Y209100D03*
X1362000Y209300D03*
X1402870Y207918D03*
X1353569Y208960D03*
X1348569D03*
X1397211Y226041D03*
X1402400Y223600D03*
X1399852Y252353D03*
X1383753Y265548D03*
X1397400Y234959D03*
X1391900D03*
X1386400D03*
X1399978Y233775D03*
X1400066Y236274D03*
X1398600Y228700D03*
X1401565Y229435D03*
X1399600Y223600D03*
X1358900Y232118D03*
X1347900D03*
X1353400D03*
X1358900Y234959D03*
X1353400D03*
X1347900D03*
X1349500Y265500D03*
X1359100Y265600D03*
X1345050Y272350D03*
X1380900Y232118D03*
X1369900D03*
X1397400D03*
X1386400D03*
X1375400D03*
X1364400D03*
X1388518Y230789D03*
X1380900Y234959D03*
X1369900D03*
X1364400D03*
X1375400Y235100D03*
X1369100Y265500D03*
X1374864Y265629D03*
X1397400Y237900D03*
X1375400D03*
X1364400D03*
X1353400D03*
X1394881Y226997D03*
X1377522Y265600D03*
X1366312Y265525D03*
X1352468Y265695D03*
X1343668Y268095D03*
X1381031Y265600D03*
X1347468Y268095D03*
X1356268Y265695D03*
X1362803Y265525D03*
X1391900Y237900D03*
X1380900D03*
X1369900D03*
X1358900D03*
X1347900D03*
X1391900Y232118D03*
X1386400Y237900D03*
X1347892Y299741D03*
X1369320Y301219D03*
X1358514Y300815D03*
X1392135Y302051D03*
X1380601Y301465D03*
X1364260Y331619D03*
X1388450Y331250D03*
X1392400Y330800D03*
X1398062Y315743D03*
X1403100Y321350D03*
X1383639Y315274D03*
X1389600Y315200D03*
X1384024Y320225D03*
X1386048Y310310D03*
X1386265Y304310D03*
X1389600Y320100D03*
X1397640Y310631D03*
X1397880Y304640D03*
X1392380D03*
X1392340Y310625D03*
X1403260Y310623D03*
X1403300Y304640D03*
X1388208Y341489D03*
X1400400Y335400D03*
X1348080Y309825D03*
X1353142Y309761D03*
X1358792Y309760D03*
X1358800Y303700D03*
X1353359Y303767D03*
X1353672Y299605D03*
X1345700Y285300D03*
X1348190Y303810D03*
X1355300Y321675D03*
X1359200Y322200D03*
X1346550Y322350D03*
X1350650Y315050D03*
X1357452Y319395D03*
X1369540Y310125D03*
X1374900Y310130D03*
X1397635Y302051D03*
X1386101Y301465D03*
X1374820Y301219D03*
X1364014Y300815D03*
X1368200Y284000D03*
X1365246Y285931D03*
X1381100Y304360D03*
X1380910Y310300D03*
X1364044Y309691D03*
X1364213Y303694D03*
X1375040Y304135D03*
X1369540D03*
X1371000Y322400D03*
X1363059Y314514D03*
X1368947Y313993D03*
X1355800Y285000D03*
X1352400D03*
X1359000Y284900D03*
X1367200Y321600D03*
X1363700D03*
X1400558Y316357D03*
X1404286Y281729D03*
X1403037Y307630D03*
X1360294Y315025D03*
X1371090Y315395D03*
X1380904Y315947D03*
X1392226Y315658D03*
X1349134Y321145D03*
X1402092Y284022D03*
X1398347Y284023D03*
X1398926Y281582D03*
X1392135Y307630D03*
X1380548Y307310D03*
X1369340Y307130D03*
X1358544Y306690D03*
X1347642Y306760D03*
X1397635Y307630D03*
X1386048Y307310D03*
X1374840Y307130D03*
X1364044Y306690D03*
X1353142Y306760D03*
X1392226Y319458D03*
X1349134Y317436D03*
X1400558Y320157D03*
X1380904Y319747D03*
X1371090Y319195D03*
X1360294Y318825D03*
X1358500Y338400D03*
X1370200D03*
X1364300Y338300D03*
X1403037Y302046D03*
X1392144Y364617D03*
X1389450Y372250D03*
X1384700Y359700D03*
X1392500Y344600D03*
X1392805Y360466D03*
X1388500Y350864D03*
X1391200Y386300D03*
X1384531Y382957D03*
X1394760Y394720D03*
X1394370Y384230D03*
X1394260Y351170D03*
X1389500Y360500D03*
X1388300Y346200D03*
X1384300Y398900D03*
X1386800D03*
X1384252Y401343D03*
X1386752D03*
X1380900Y383164D03*
X1371600Y368700D03*
X1362510Y360717D03*
X1354024Y398985D03*
X1352338Y404153D03*
X1351379Y399227D03*
X1352239Y401593D03*
X1359600Y360800D03*
X1356466Y360680D03*
X1344731Y359567D03*
X1358512Y371792D03*
X1360450Y402100D03*
X1359360Y398810D03*
X1357880Y403760D03*
X1356560Y398910D03*
X1362250Y399160D03*
X1354681Y401444D03*
X1354982Y404154D03*
X1357542Y401381D03*
X1378200Y346900D03*
X1374344Y371431D03*
X1380200Y370400D03*
X1376979Y370536D03*
X1364856Y366666D03*
X1382017Y367584D03*
X1380800Y392300D03*
X1372007Y396668D03*
X1380200Y373100D03*
X1377103Y373428D03*
X1374300Y402053D03*
X1376800D03*
X1381752Y401343D03*
X1379252D03*
X1381800Y398900D03*
X1378207Y394568D03*
X1369407Y396668D03*
X1363250Y401700D03*
X1371200Y402100D03*
X1381500Y396200D03*
X1375201Y396303D03*
X1365731Y360698D03*
X1358500Y374500D03*
X1360200Y377400D03*
X1358655Y379352D03*
X1362068Y393385D03*
X1360300Y381100D03*
X1360200Y384700D03*
Y389000D03*
X1358700Y386700D03*
X1358568Y390885D03*
Y393385D03*
X1358600Y382800D03*
X1362068Y390885D03*
X1374300Y377885D03*
Y381485D03*
X1374268Y374285D03*
Y389985D03*
X1374207Y384968D03*
Y387468D03*
X1391845Y348325D03*
X1370300Y350200D03*
X1358300Y344200D03*
X1358400Y350100D03*
X1370200Y343900D03*
X1364100Y350200D03*
X1395375Y453561D03*
X1385100Y427500D03*
Y442500D03*
Y437500D03*
X1385416Y410502D03*
X1404558Y416575D03*
X1402725Y408136D03*
X1402520Y413246D03*
X1388085Y410479D03*
X1403998Y429775D03*
X1404558Y421575D03*
X1398275Y453561D03*
X1397975Y457561D03*
X1403998Y434775D03*
X1395725Y417193D03*
X1393900Y415000D03*
X1396900D03*
Y412500D03*
X1393900D03*
X1385100Y452500D03*
Y447500D03*
X1389900Y427400D03*
X1385100Y432500D03*
X1395100Y427500D03*
Y432500D03*
X1389900Y447400D03*
X1344090Y463630D03*
X1346739Y463615D03*
X1382849Y410471D03*
X1380449Y410479D03*
X1358990Y411040D03*
X1358910Y408480D03*
X1358980Y406060D03*
X1355100Y427500D03*
Y432500D03*
X1361558Y410527D03*
X1349800Y458200D03*
X1350100Y447500D03*
Y452500D03*
X1360100Y447500D03*
Y452500D03*
Y457500D03*
X1345100Y442500D03*
X1350100D03*
X1345100Y437500D03*
X1350100D03*
X1355100D03*
Y442500D03*
X1362560Y463478D03*
X1369034Y458075D03*
X1365100Y432500D03*
Y427500D03*
X1369907Y410513D03*
X1372535Y410512D03*
X1375239Y410590D03*
X1377928Y410451D03*
X1366984Y410481D03*
X1364403Y410496D03*
X1370100Y447500D03*
X1365100Y437500D03*
X1380100Y442500D03*
Y437500D03*
X1370100D03*
X1375100D03*
Y452500D03*
X1370100D03*
X1380100Y447500D03*
X1370100Y442500D03*
X1365100Y452500D03*
X1379857Y458108D03*
X1365100Y442500D03*
X1375100D03*
X1380100Y452500D03*
X1365100Y447500D03*
X1402775Y453561D03*
X1395375Y457561D03*
X1390100Y457500D03*
X1395100Y447500D03*
X1401398Y429775D03*
Y434775D03*
X1402775Y457561D03*
X1388900Y525230D03*
X1395581Y525357D03*
X1383600Y482504D03*
X1386041Y493723D03*
X1383519Y487445D03*
X1390330Y516690D03*
X1385033Y516848D03*
X1387568Y516892D03*
X1388865Y519788D03*
X1388850Y522266D03*
X1386033Y498811D03*
X1403027Y520231D03*
X1402950Y510650D03*
X1400445Y510159D03*
X1395242Y520301D03*
X1383859Y519931D03*
X1386359D03*
X1396035Y514863D03*
X1386241Y487323D03*
Y482623D03*
X1388719Y498745D03*
X1383263Y493673D03*
X1347546Y476897D03*
X1350500Y475100D03*
X1354462Y474141D03*
X1347196Y472941D03*
X1355800Y508500D03*
X1344761Y498282D03*
X1344073Y508263D03*
X1363800Y481600D03*
X1363662Y486636D03*
X1365741Y492723D03*
X1382578Y516805D03*
X1377492Y516892D03*
X1369757Y517465D03*
X1365719Y497545D03*
X1373345Y519940D03*
X1381095D03*
X1376109Y519931D03*
X1378609D03*
X1368441Y497523D03*
X1366309Y486618D03*
X1366341Y481823D03*
X1360741Y486523D03*
X1381041Y482575D03*
X1362841Y492823D03*
X1380741Y487489D03*
X1352490Y515470D03*
X1346870Y515450D03*
X1352590Y519170D03*
X1346970Y519150D03*
X1388741Y493623D03*
X1383241Y498595D03*
X1368441Y492723D03*
X1362880Y497556D03*
X1360863Y481673D03*
X1396158Y537595D03*
X1401777Y557632D03*
X1385033Y544267D03*
X1390623Y574986D03*
X1400830Y564090D03*
X1400288Y570099D03*
X1404420Y576330D03*
X1400980Y587086D03*
X1397980D03*
X1399721Y537509D03*
X1386800Y535600D03*
Y541500D03*
Y538500D03*
X1384310Y538540D03*
Y535540D03*
Y541540D03*
X1385316Y574705D03*
X1387986Y574960D03*
X1390595Y549328D03*
X1387907Y544286D03*
X1404519Y560280D03*
Y557380D03*
X1361600Y559400D03*
X1358529Y537492D03*
X1361163Y540052D03*
X1358518Y540073D03*
X1356018D03*
X1356029Y537492D03*
X1363674Y537471D03*
X1355548Y559959D03*
X1361926Y584037D03*
Y586537D03*
X1359100Y586200D03*
X1357400Y588400D03*
X1360100D03*
X1344613Y556376D03*
Y561376D03*
Y558876D03*
X1347700Y554100D03*
X1353520Y537480D03*
X1344613Y553876D03*
X1361174Y537471D03*
X1358439Y559959D03*
X1375479Y540117D03*
X1375500Y537717D03*
X1366265Y537437D03*
X1363663Y540052D03*
X1363568Y550589D03*
X1380521Y535276D03*
X1378021D03*
X1375621Y535254D03*
X1371265Y537437D03*
X1368765D03*
X1366459Y550589D03*
X1377979Y537717D03*
Y540117D03*
X1380479Y537717D03*
X1368596Y539889D03*
X1371096D03*
X1366096D03*
X1380479Y540117D03*
X1382331Y543818D03*
X1382032Y560143D03*
X1376070Y559760D03*
X1382200Y562700D03*
X1379000Y561500D03*
X1373700Y584656D03*
X1379053Y581864D03*
X1371100Y584656D03*
X1376800Y584328D03*
X1364426Y586637D03*
Y584137D03*
X1382500Y575400D03*
Y579100D03*
X1365028Y547954D03*
X1362528D03*
X1360500Y570900D03*
Y574700D03*
X1360261Y578873D03*
X1360247Y567390D03*
X1360261Y562373D03*
Y581373D03*
X1362000Y576700D03*
Y572800D03*
X1362100Y569100D03*
X1362000Y565600D03*
X1375961Y569473D03*
X1376000Y565700D03*
X1375961Y562273D03*
X1363761Y581373D03*
X1375961Y577973D03*
X1376000Y575456D03*
Y572956D03*
X1390462Y541800D03*
X1400216Y560128D03*
X1387050Y615350D03*
X1392500Y592000D03*
X1384744Y605689D03*
X1385000Y602700D03*
X1386921Y620689D03*
X1390851D03*
X1400980Y589586D03*
X1395060Y590630D03*
X1373838Y616161D03*
X1380890Y615820D03*
X1371100Y615756D03*
X1376556D03*
X1357726Y591037D03*
X1360226D03*
X1382586Y609602D03*
X1382605Y612102D03*
X1375600Y589700D03*
X1382100Y592800D03*
X1382000Y589500D03*
X1382200Y606300D03*
X1363761Y612573D03*
X1360261D03*
X1360200Y597800D03*
X1361600Y599900D03*
X1361500Y595700D03*
X1360100Y610100D03*
X1360200Y606300D03*
Y602000D03*
X1361900Y608200D03*
X1361500Y604200D03*
X1360261Y593573D03*
X1375961Y600673D03*
X1375861Y597073D03*
X1375961Y593473D03*
X1363761Y610073D03*
X1375961Y609173D03*
X1375900Y604156D03*
Y606656D03*
X1405100Y10000D03*
X1413721Y13139D03*
X1416871D03*
X1454991Y5589D03*
X1454715Y2784D03*
X1450508Y2756D03*
X1410600Y9100D03*
X1410571Y13170D03*
X1420019Y13466D03*
X1448367Y13533D03*
X1438918D03*
X1429469Y13466D03*
X1457814D03*
X1436131Y5248D03*
X1432661Y5220D03*
X1449991Y5589D03*
X1436025Y7756D03*
X1427442Y11563D03*
X1431025Y7756D03*
X1422442Y11563D03*
X1465237D03*
X1460237D03*
X1446340D03*
X1441340D03*
X1420337Y45477D03*
X1416837D03*
X1411546Y43116D03*
X1406546D03*
X1406674Y46120D03*
X1411254Y46018D03*
X1412250Y65359D03*
X1407150Y58859D03*
X1410150D03*
X1407150Y52859D03*
X1410150D03*
X1409250Y65359D03*
X1407150Y55859D03*
X1410150D03*
X1413721Y36749D03*
X1412250Y68359D03*
X1409250D03*
X1407964Y79700D03*
X1407960Y93800D03*
X1407300Y77300D03*
X1410200Y77400D03*
X1405149Y93679D03*
X1406746Y91680D03*
X1406264Y82000D03*
X1409264D03*
X1404964Y79700D03*
X1409150Y71259D03*
X1412150D03*
X1425081Y48412D03*
X1442067Y34830D03*
X1423170Y36635D03*
X1432619Y34830D03*
X1451516D03*
X1460965D03*
X1453809Y94639D03*
X1453700Y83750D03*
X1455889Y73700D03*
X1453221Y73750D03*
X1450973Y112225D03*
X1452648Y103788D03*
X1451198Y143761D03*
X1451590Y138750D03*
X1451021Y151626D03*
X1438348Y155908D03*
X1451228Y141261D03*
X1451233Y146405D03*
X1451273Y148905D03*
X1422196Y218052D03*
X1446331Y197285D03*
X1458569Y192143D03*
X1449847Y202322D03*
X1439000Y208500D03*
X1442251Y180818D03*
X1408247Y206270D03*
X1418300Y199900D03*
X1451386Y173499D03*
X1451366Y165296D03*
X1451365Y170318D03*
Y176014D03*
X1450532Y178372D03*
X1454070Y163360D03*
X1454660Y166200D03*
X1440150Y175550D03*
X1440124Y166180D03*
X1451427Y167818D03*
X1447999Y205645D03*
X1458908Y187699D03*
X1444850Y242730D03*
X1433362Y280744D03*
X1412579Y268273D03*
X1433362Y278244D03*
X1426658Y274252D03*
X1455600Y254826D03*
X1439700Y253100D03*
X1434800Y248900D03*
X1435655Y246550D03*
X1441750Y236800D03*
X1434300Y251600D03*
X1437400Y244150D03*
X1464150Y235550D03*
X1462700Y221700D03*
X1464200Y231400D03*
X1407274Y245652D03*
X1410979Y270473D03*
X1451850Y262200D03*
X1461348Y244350D03*
X1454350Y262200D03*
X1466006Y265300D03*
X1465063Y253544D03*
X1464700Y256100D03*
X1447154Y251710D03*
X1462704Y254470D03*
X1422281Y221479D03*
X1454056Y266169D03*
X1466404Y245350D03*
X1454000Y259700D03*
X1437800Y258300D03*
X1452200Y254500D03*
X1452728Y243306D03*
X1458800Y254882D03*
X1433700Y254200D03*
X1458318Y243000D03*
X1426905Y267045D03*
X1448500Y257700D03*
X1430365Y262624D03*
X1433057Y257388D03*
X1438500Y255400D03*
X1459548Y221731D03*
X1410800Y316100D03*
X1408580Y310632D03*
X1408760Y304637D03*
X1408376Y339882D03*
X1408250Y333000D03*
X1408348Y336436D03*
X1410550Y320800D03*
X1410489Y337988D03*
X1443500Y327900D03*
X1416000Y332900D03*
Y338100D03*
X1444311Y324366D03*
X1419343Y310652D03*
X1416000Y335500D03*
X1419283Y304570D03*
X1413983Y304645D03*
X1413943Y310628D03*
X1419220Y301983D03*
X1408537Y302046D03*
X1419333Y307598D03*
X1413387Y316233D03*
X1405392Y284022D03*
X1413720Y307634D03*
X1408537Y307630D03*
X1413387Y320033D03*
X1413720Y301983D03*
X1464400Y382720D03*
X1448050Y374950D03*
X1464273Y397648D03*
X1463200Y362200D03*
X1463870Y367869D03*
X1453900Y353350D03*
X1463617Y357259D03*
X1413400Y361300D03*
X1456000Y360700D03*
X1463942Y359742D03*
X1464400Y390800D03*
X1450400Y354300D03*
X1460400Y353000D03*
X1459111Y356353D03*
X1447685Y352025D03*
X1453251Y356676D03*
X1461016Y359965D03*
X1417656Y367547D03*
X1420101Y396236D03*
X1418138Y386361D03*
X1415000Y399000D03*
X1412220Y388360D03*
X1417217Y379129D03*
X1417349Y382137D03*
X1417773Y374107D03*
X1464124Y353776D03*
X1465500Y395400D03*
X1456750Y381850D03*
X1459033Y395334D03*
X1446700Y387900D03*
X1437897Y402315D03*
X1443100Y368950D03*
X1464361Y385275D03*
X1415500Y353200D03*
X1445510Y350327D03*
X1415450Y350550D03*
X1456981Y384569D03*
X1445100Y374900D03*
X1452699Y404060D03*
X1439934Y403730D03*
X1444400Y371600D03*
X1465048Y402370D03*
X1420515Y373585D03*
Y368585D03*
X1456900Y387600D03*
X1408225Y438233D03*
X1411900Y429775D03*
X1405375Y453561D03*
X1405608Y456761D03*
X1411900Y434775D03*
X1408225Y441000D03*
X1435479Y423107D03*
X1439350Y406900D03*
X1459200Y459800D03*
Y454100D03*
X1459000Y449997D03*
X1451400Y454100D03*
Y459800D03*
X1445000Y437000D03*
X1429000Y437059D03*
X1444800Y442500D03*
X1444500Y448000D03*
X1429100Y453400D03*
X1429000Y448000D03*
Y442600D03*
X1448800Y427800D03*
X1459478Y432851D03*
X1462131D03*
X1458300Y442675D03*
X1412484Y440748D03*
X1412375Y443545D03*
X1412447Y416368D03*
X1412545Y421974D03*
X1413300Y454400D03*
X1413075Y457561D03*
X1448800Y416500D03*
X1464300Y404900D03*
X1439000Y423000D03*
X1464600Y428000D03*
X1459300Y430000D03*
X1464525Y420014D03*
X1464731Y432942D03*
X1445100Y431500D03*
X1459200Y465500D03*
X1451400D03*
X1461800Y454100D03*
X1464200Y449997D03*
X1439813Y409422D03*
X1439651Y412466D03*
X1466382Y406773D03*
X1442830Y406472D03*
X1443252Y409029D03*
X1405423Y413281D03*
X1407158Y421575D03*
X1454000Y459800D03*
X1405423Y408281D03*
X1407158Y416575D03*
X1414982Y417040D03*
X1409300Y429775D03*
X1410475Y457561D03*
X1415146Y421946D03*
X1409300Y434775D03*
X1464400Y465500D03*
X1456600D03*
X1461800Y459800D03*
X1454000Y454100D03*
X1414107Y447267D03*
X1461600Y449997D03*
X1464400Y454100D03*
X1461800Y465500D03*
X1454000D03*
X1410475Y453561D03*
X1456600Y454100D03*
X1464400Y459800D03*
X1456600D03*
X1408753Y527518D03*
X1405950Y510650D03*
X1407884Y512751D03*
X1461713Y515196D03*
X1460661Y484891D03*
X1459213Y515196D03*
X1461267Y489790D03*
X1456602Y485864D03*
X1452188Y487223D03*
X1456590Y488976D03*
X1418241Y489523D03*
X1418441Y482523D03*
X1441842Y482924D03*
X1442041Y494423D03*
X1415541Y489523D03*
X1416100Y483500D03*
X1415800Y477500D03*
Y495200D03*
X1420200Y520500D03*
X1447749Y485395D03*
X1439314Y477723D03*
X1439400Y483600D03*
X1439341Y489323D03*
X1453700Y501600D03*
X1458357Y523271D03*
X1461100Y523600D03*
X1439400Y494700D03*
X1431690Y521530D03*
X1449568Y487276D03*
X1417800Y521500D03*
X1414800Y521400D03*
X1458060Y495020D03*
X1458935Y512470D03*
X1428500Y521000D03*
X1438390Y527175D03*
X1436396Y477691D03*
X1413041Y477423D03*
X1412941Y489523D03*
X1464553Y508872D03*
X1436441Y489323D03*
X1412741Y494223D03*
X1436541Y494423D03*
X1436600Y482900D03*
X1413193Y482532D03*
X1418341Y494423D03*
Y477323D03*
X1442141Y477623D03*
X1442041Y489223D03*
X1409693Y560343D03*
X1412093D03*
X1410850Y564210D03*
X1410340Y570370D03*
X1410486Y529792D03*
X1407019Y557380D03*
X1412019D03*
X1409519D03*
X1406993Y560343D03*
X1447852Y575687D03*
X1445800Y574300D03*
X1445750Y539000D03*
X1461500Y540000D03*
X1439861Y540497D03*
X1461653Y580762D03*
X1461707Y583162D03*
X1461878Y585556D03*
X1441252Y548631D03*
X1422509Y576823D03*
X1419809Y570723D03*
X1422509Y573823D03*
X1419809Y573723D03*
Y576723D03*
X1422509Y570823D03*
X1417252Y573470D03*
X1414743Y573363D03*
X1414851Y576624D03*
X1414744Y570801D03*
X1417182Y570711D03*
X1417288Y576624D03*
X1451150Y569900D03*
Y573200D03*
X1436160Y561200D03*
X1458629Y531604D03*
X1461500Y531500D03*
X1433100Y581770D03*
X1430570Y580890D03*
X1432590Y584550D03*
X1427500Y581100D03*
X1441409Y561117D03*
X1447022Y546578D03*
X1449922Y546664D03*
X1425243Y562260D03*
X1418402Y562624D03*
X1465700Y570500D03*
X1441805Y570887D03*
X1443797Y572482D03*
X1422500Y579800D03*
X1414800D03*
X1461930Y587956D03*
X1415173Y586332D03*
X1412673D03*
X1422920Y586250D03*
X1417920D03*
X1420420D03*
X1438799Y542785D03*
X1439123Y545294D03*
X1409500Y538000D03*
X1420500Y549800D03*
X1420400Y538000D03*
X1462039Y590354D03*
X1445145Y605727D03*
X1442525Y597279D03*
X1443654Y594749D03*
X1456277Y603454D03*
X1453628Y603368D03*
X1450720Y606067D03*
X1448071Y605981D03*
X1443473Y599944D03*
X1453451Y606114D03*
X1456100Y606200D03*
X1460200D03*
X1462155Y592761D03*
X1465334Y618564D03*
X1451314Y623298D03*
X1458000Y623400D03*
X1455000D03*
X1461000D03*
X1442200D03*
X1445200D03*
X1448200D03*
X1463419Y606912D03*
X1506300Y-6600D03*
X1498800Y-12676D03*
X1477100Y2400D03*
X1524800Y3500D03*
X1527700Y6963D03*
X1504400Y20300D03*
X1513700Y7082D03*
X1520700Y7100D03*
X1511900Y3500D03*
X1481600Y5300D03*
X1506900Y3500D03*
X1509400D03*
X1522600Y-6500D03*
X1514400Y3500D03*
X1520100D03*
X1469388Y5589D03*
X1469807Y2967D03*
X1474388Y5589D03*
X1473674Y2953D03*
X1476712Y13466D03*
X1467264Y13533D03*
X1485242Y4589D03*
X1496660Y-10252D03*
X1516900Y3500D03*
X1501900Y-9124D03*
X1492900Y4000D03*
X1489600D03*
X1521900Y27500D03*
X1509500Y31900D03*
X1495611Y13466D03*
X1486162Y13500D03*
X1524154Y28918D03*
X1521092Y21665D03*
X1527600Y3500D03*
X1493770Y6909D03*
X1484135Y11563D03*
X1488770Y6909D03*
X1479135Y11563D03*
X1470862Y38209D03*
X1470414Y34830D03*
X1479863D03*
X1497711Y34427D03*
X1489311Y34830D03*
X1490057Y85165D03*
X1490821Y73750D03*
X1524557Y88336D03*
X1520314Y78880D03*
X1517162Y78784D03*
X1519599Y86117D03*
X1491164Y82923D03*
X1519580Y81313D03*
X1499613Y84046D03*
X1515294Y91306D03*
X1523563Y93565D03*
X1511700Y84600D03*
X1499875Y86681D03*
X1526744Y93265D03*
X1513335Y92921D03*
X1524744Y133656D03*
X1513935Y120143D03*
Y108332D03*
X1513013Y96546D03*
X1514600Y126650D03*
X1482455Y124222D03*
X1474717Y110370D03*
X1473096Y120999D03*
X1468755Y128478D03*
X1482300Y118400D03*
X1468590Y131200D03*
X1475200Y142600D03*
X1476761Y152725D03*
X1469747Y148276D03*
X1483093Y130796D03*
X1489053Y103325D03*
X1489780Y105820D03*
X1524284Y112773D03*
X1511800Y127050D03*
X1513879Y113349D03*
X1518514Y130991D03*
X1526513Y120769D03*
Y103958D03*
X1526728Y124168D03*
X1518438Y100926D03*
X1490178Y112315D03*
X1518376Y111499D03*
X1523950Y104050D03*
X1523889Y99033D03*
X1523557Y116165D03*
X1523813Y120546D03*
X1523756Y108762D03*
X1501603Y108500D03*
X1499618Y124520D03*
X1497699Y112140D03*
X1511634Y121195D03*
X1511635Y114535D03*
X1511650Y109400D03*
Y103400D03*
X1511651Y98675D03*
X1500775Y98101D03*
X1501700Y103300D03*
X1513023Y140630D03*
X1511664Y133603D03*
X1488350Y149450D03*
X1523719Y149488D03*
X1488800Y145000D03*
X1502000Y147500D03*
X1492013Y155610D03*
X1495848Y150600D03*
X1496150Y148115D03*
X1511660Y138510D03*
X1513136Y157081D03*
X1515358Y151743D03*
X1513500Y153800D03*
X1500643Y154819D03*
X1496038Y154229D03*
X1503466Y142486D03*
X1510184Y142614D03*
X1505673Y146346D03*
X1490900Y146600D03*
X1500455Y110933D03*
X1496658Y115088D03*
X1472500Y123700D03*
X1473100Y131900D03*
X1473200Y118300D03*
X1514425Y134180D03*
X1524900Y139100D03*
X1484113Y128513D03*
X1500700Y127250D03*
X1498705Y99522D03*
X1483366Y120746D03*
X1493069Y152834D03*
X1473354Y153246D03*
X1485210Y134837D03*
X1513935Y104532D03*
Y116343D03*
X1500703Y158233D03*
X1507524Y218600D03*
X1510800Y193330D03*
X1512500Y199837D03*
X1492136Y199125D03*
X1479000Y207225D03*
X1512700Y205100D03*
X1497237Y217281D03*
X1519243Y191627D03*
X1513900Y218000D03*
X1478611Y209695D03*
X1478089Y182650D03*
X1511100Y186275D03*
X1499800Y199300D03*
X1491196Y218527D03*
X1523400Y217900D03*
X1483523Y181100D03*
X1517328Y186208D03*
X1475401Y210017D03*
X1515060Y192443D03*
X1487716Y218650D03*
X1470382Y188372D03*
X1472758Y216495D03*
X1510638Y166240D03*
X1468700Y163100D03*
X1476761Y157400D03*
X1471388Y173700D03*
X1496713Y174853D03*
X1527500Y167726D03*
X1502192Y164871D03*
X1494783Y177907D03*
X1493200Y162700D03*
X1488300Y161700D03*
X1497493Y162078D03*
X1492469Y179387D03*
X1494939Y159500D03*
X1492500Y176887D03*
X1489088Y176680D03*
X1488900Y172576D03*
X1489015Y179832D03*
X1516616Y205537D03*
X1512525Y208944D03*
X1516598Y203037D03*
X1516872Y208863D03*
X1504706Y164871D03*
X1488300Y158300D03*
X1477388Y172988D03*
X1473888Y173721D03*
X1474883Y182275D03*
X1492597Y172636D03*
X1474439Y207621D03*
X1527657Y278700D03*
X1470950Y252846D03*
X1469004Y246287D03*
X1467040Y260357D03*
X1470556Y256900D03*
X1468450Y252900D03*
X1472200Y243000D03*
X1469150Y242931D03*
X1479500Y238500D03*
X1499559Y231173D03*
X1498022Y221900D03*
X1498685Y224715D03*
X1491700Y241661D03*
X1478500Y252000D03*
X1479000Y254500D03*
X1477397Y256657D03*
X1484000Y257500D03*
X1496812Y273718D03*
X1491265Y226492D03*
X1519300Y245196D03*
X1491438Y221137D03*
X1523580Y237960D03*
X1509814Y247215D03*
X1509800Y244676D03*
X1503842Y245678D03*
X1499070Y255934D03*
X1499472Y250370D03*
X1504772Y259229D03*
X1507003Y272249D03*
X1504461Y274426D03*
X1521962Y278650D03*
X1526150Y234300D03*
X1479700Y224801D03*
X1482004Y222483D03*
X1497082Y277987D03*
X1474096Y256706D03*
X1483457Y244568D03*
X1495682Y255861D03*
X1493199Y255507D03*
X1484700Y251800D03*
X1487500Y244500D03*
X1495696Y258361D03*
X1492697Y267303D03*
X1475004Y246287D03*
X1492753Y273724D03*
X1499681Y279910D03*
X1512790Y240099D03*
X1516549Y234278D03*
X1486926Y247834D03*
X1491407Y258353D03*
X1523470Y242580D03*
X1470950Y229669D03*
X1471604Y246287D03*
X1516613Y240656D03*
X1498478Y233675D03*
X1520413Y239498D03*
X1482400Y248000D03*
X1474520Y251740D03*
X1525650Y248700D03*
X1500840Y319870D03*
X1517115Y330005D03*
X1470276Y330774D03*
X1468399Y324930D03*
X1470257Y321929D03*
X1466970Y320235D03*
X1472500Y341074D03*
X1526722Y295400D03*
X1501583Y339389D03*
X1521817Y330937D03*
X1526000Y341000D03*
X1517600Y320940D03*
X1487426Y330100D03*
X1514050Y327490D03*
X1526936Y307015D03*
X1473231Y320250D03*
X1516138Y310749D03*
X1487858Y340412D03*
X1484100Y330115D03*
X1499829Y341250D03*
X1482550Y333600D03*
X1482585Y340856D03*
X1493240Y325828D03*
X1520766Y341000D03*
X1505000Y340990D03*
X1484620Y339152D03*
X1510851Y340113D03*
X1513796Y330680D03*
X1497997Y338546D03*
X1504370Y330970D03*
X1518060Y317520D03*
X1525677Y311835D03*
X1510584Y330640D03*
X1492540Y328250D03*
X1516301Y313244D03*
X1527537Y330048D03*
X1525051Y329553D03*
X1487904Y337500D03*
X1482386Y336926D03*
X1483506Y326061D03*
X1514100Y321792D03*
X1514067Y315626D03*
X1493290Y287984D03*
X1526900Y292866D03*
X1496900Y293900D03*
X1493268Y293943D03*
X1496600Y281400D03*
X1493700Y281476D03*
X1508650Y287500D03*
X1496628Y288440D03*
X1499987Y288487D03*
X1518006Y286706D03*
X1501550Y293750D03*
X1514722Y293257D03*
X1515482Y280800D03*
X1512300Y280847D03*
X1511900Y287500D03*
X1472450Y337500D03*
X1472500Y334800D03*
X1471562Y325531D03*
X1487000Y333300D03*
X1523935Y318901D03*
X1497179Y306372D03*
X1499723Y300106D03*
X1505923Y309510D03*
X1505935Y306674D03*
X1508455Y313041D03*
X1503538Y318068D03*
X1495810Y341200D03*
X1495445Y338724D03*
X1496400Y336376D03*
X1512182Y293317D03*
X1524575Y387654D03*
X1503878Y364717D03*
X1487525Y384274D03*
X1505075Y394414D03*
X1501175Y387654D03*
X1505075Y401174D03*
X1501175D03*
X1522625Y391034D03*
X1495325Y397794D03*
X1499225D03*
X1493375Y401174D03*
X1489475D03*
X1507025Y384274D03*
X1501175Y380894D03*
X1522625Y397794D03*
X1507025Y377514D03*
X1518725Y384274D03*
X1510925Y397794D03*
X1483868Y390233D03*
X1516775Y394414D03*
X1510925Y377514D03*
X1512875Y380894D03*
X1518725Y377514D03*
X1522625Y384274D03*
X1510925Y391034D03*
X1512875Y387654D03*
X1510925Y384274D03*
X1489475Y380894D03*
X1493375D03*
X1487525Y397794D03*
Y377514D03*
X1498183Y365405D03*
X1505075Y387654D03*
X1499225Y377514D03*
X1473255Y372654D03*
X1507200Y356000D03*
X1502970Y350610D03*
X1520675Y394414D03*
X1470100Y392350D03*
X1472940Y384030D03*
X1467597Y363000D03*
X1470800Y395200D03*
X1469000Y345850D03*
X1472550Y397500D03*
X1470800Y402250D03*
X1472680Y380630D03*
X1473083Y393770D03*
X1489475Y387654D03*
X1514265Y355542D03*
X1495325Y391034D03*
X1493375Y387654D03*
X1495325Y377514D03*
X1524575Y394414D03*
X1520313Y357069D03*
X1520429Y354379D03*
X1525561Y350253D03*
X1498309Y360005D03*
X1511000Y350627D03*
X1481000Y350000D03*
X1478607Y359082D03*
X1498246Y352305D03*
X1478612Y361670D03*
X1498246Y354905D03*
X1507154Y353100D03*
X1524746Y356717D03*
Y354217D03*
X1516775Y380894D03*
X1526659Y397500D03*
X1524575Y380894D03*
X1522476Y361907D03*
X1522625Y377514D03*
X1483172Y351806D03*
X1474500Y365500D03*
X1478500D03*
X1483500D03*
X1482000Y395098D03*
Y399035D03*
Y383287D03*
Y387224D03*
X1473255Y376254D03*
X1528146Y349842D03*
X1519626Y365817D03*
X1488394Y365466D03*
X1497275Y401174D03*
X1508975D03*
X1483950Y401650D03*
X1491425Y391034D03*
X1503125Y377514D03*
X1491425D03*
X1507200Y358700D03*
X1498246Y357505D03*
X1518725Y397794D03*
Y391034D03*
X1512875Y401174D03*
Y394414D03*
X1514925Y358844D03*
X1489838Y350011D03*
X1484600Y394100D03*
X1483740Y359550D03*
X1524746Y359217D03*
X1495325Y384274D03*
X1483664Y362914D03*
X1520675Y401174D03*
X1516775D03*
X1515328Y363389D03*
X1516775Y387654D03*
X1478163Y354940D03*
X1483867Y356753D03*
X1526525Y377514D03*
X1514825D03*
X1526525Y384274D03*
Y391034D03*
X1514825Y384274D03*
X1520675Y387654D03*
Y380894D03*
X1514825Y391034D03*
X1508975Y387654D03*
Y380894D03*
X1503125Y384274D03*
Y391034D03*
X1497275Y380894D03*
X1491425Y384274D03*
X1497275Y387654D03*
Y394414D03*
X1491425Y397794D03*
X1503125D03*
X1508975Y394414D03*
X1514825Y397794D03*
X1524575Y401174D03*
X1507025Y391034D03*
X1489915Y352637D03*
X1498246Y362705D03*
X1501175Y394414D03*
X1499225Y391034D03*
Y384274D03*
X1493375Y394414D03*
X1489475D03*
X1488479Y362967D03*
Y360367D03*
X1496000Y350000D03*
X1488479Y357767D03*
X1466873Y397648D03*
X1469873D03*
X1468048Y402370D03*
X1505075Y380894D03*
X1517367Y349964D03*
X1505075Y463826D03*
X1515500Y448250D03*
X1507025Y404554D03*
X1499225D03*
Y440166D03*
X1522625Y404554D03*
X1491425Y418074D03*
X1487525D03*
X1499225Y446926D03*
Y453686D03*
X1520675Y463826D03*
X1512875D03*
X1508975D03*
X1501175Y421454D03*
X1495325Y418074D03*
X1493375Y443546D03*
X1489475Y414694D03*
X1493375D03*
X1489475Y407934D03*
X1493375D03*
Y421454D03*
X1489475D03*
X1493375Y428214D03*
Y436786D03*
X1499225Y460446D03*
X1489475Y457066D03*
X1487525Y460446D03*
X1472449Y439421D03*
X1467000Y454100D03*
Y459800D03*
X1466800Y449997D03*
X1470262Y420711D03*
X1467355Y432919D03*
X1469931Y432842D03*
X1467401Y411557D03*
X1471900Y406900D03*
X1472530Y432731D03*
X1472400Y428063D03*
X1472800Y420689D03*
X1467000Y465500D03*
X1524575Y463826D03*
X1491425Y411314D03*
X1487525D03*
X1518675Y451425D03*
X1516775Y457066D03*
X1512954Y407653D03*
X1524575Y407624D03*
X1518650Y416750D03*
X1499225Y411314D03*
X1501175Y407934D03*
X1515500Y413600D03*
X1528100Y413700D03*
X1512350Y410450D03*
X1521800Y419900D03*
X1501200Y450600D03*
X1505714Y448145D03*
X1501175Y443546D03*
X1503125Y446926D03*
X1505075Y457066D03*
X1524575D03*
X1524950Y445100D03*
Y448250D03*
X1521800Y445100D03*
X1528147Y454546D03*
X1509200Y410450D03*
X1485250Y408017D03*
X1497200Y421200D03*
X1505715Y441368D03*
X1506059Y429249D03*
X1505459Y421107D03*
X1503128Y419892D03*
X1512350Y423050D03*
X1518650Y426200D03*
Y423050D03*
X1515500Y426200D03*
X1482000Y418720D03*
Y406909D03*
Y410846D03*
Y414783D03*
Y422658D03*
Y426595D03*
X1483400Y438100D03*
X1482603Y442418D03*
X1482000Y462028D03*
X1483115Y454379D03*
X1483200Y450455D03*
X1482500Y434600D03*
X1503125Y404554D03*
X1509200Y413600D03*
X1510925Y404554D03*
X1497275Y414694D03*
X1503125Y424834D03*
X1497275Y428214D03*
X1495325Y424834D03*
X1503125Y433406D03*
X1491425D03*
X1495325D03*
X1524950Y419900D03*
X1518650D03*
X1483818Y430597D03*
X1528100Y410550D03*
X1501219Y416596D03*
X1487525Y404554D03*
X1526525D03*
X1515500Y416750D03*
X1518700Y406500D03*
X1491425Y404554D03*
X1495325Y411314D03*
X1512350Y445100D03*
X1509200D03*
Y454550D03*
X1491425Y446926D03*
X1515500Y423050D03*
X1524950Y426200D03*
Y423050D03*
X1509200Y416750D03*
X1512350D03*
X1505605Y423604D03*
X1509200Y423050D03*
Y419900D03*
X1515500D03*
X1512350D03*
Y426200D03*
X1509200D03*
X1515500Y429350D03*
X1518650D03*
X1509200D03*
X1512350D03*
X1518650Y438800D03*
X1515500D03*
X1512350D03*
X1505392Y437133D03*
X1509200Y438800D03*
Y441950D03*
X1512350D03*
X1515500D03*
X1524950Y438800D03*
X1509200Y435650D03*
X1518650D03*
X1515500D03*
X1512350D03*
X1524950D03*
Y429350D03*
X1505462Y434630D03*
X1505075Y407934D03*
X1524950Y413600D03*
X1497273Y407610D03*
X1512400Y454500D03*
X1503125Y440166D03*
X1501175Y436786D03*
X1495325Y440166D03*
X1497275Y436786D03*
X1510925Y460446D03*
X1505442Y443900D03*
X1507025Y460446D03*
X1503125Y453786D03*
Y460446D03*
X1501175Y457066D03*
X1487525Y453686D03*
X1497275Y457066D03*
Y450306D03*
X1495325Y446926D03*
Y453686D03*
X1497275Y443546D03*
X1501175Y463826D03*
X1493375D03*
X1515500Y445100D03*
X1514825Y460446D03*
X1520675Y457066D03*
X1518725Y460446D03*
X1521800Y441950D03*
Y448250D03*
X1526525Y460446D03*
X1522625D03*
X1524950Y441950D03*
X1485300Y443484D03*
X1483375Y458375D03*
X1525000Y416750D03*
X1516700Y409900D03*
X1518650Y413600D03*
X1501175Y428214D03*
X1499225Y424834D03*
X1516775Y463826D03*
X1487525Y440166D03*
X1491425D03*
X1489475Y443546D03*
X1487500Y424600D03*
X1491400D03*
X1470106Y412152D03*
X1472688Y412055D03*
X1467290Y428013D03*
X1469900D03*
X1469400Y449997D03*
X1472000D03*
X1469382Y406773D03*
X1493375Y450306D03*
X1489475Y428214D03*
Y436786D03*
X1491425Y460446D03*
X1489475Y450306D03*
X1491425Y453686D03*
X1493375Y457066D03*
X1495325Y460446D03*
X1497275Y463826D03*
X1485030Y463690D03*
X1489475Y463826D03*
X1508975Y457066D03*
X1515389Y451400D03*
X1521800D03*
X1518650Y448250D03*
X1487525Y480726D03*
X1520675Y470586D03*
X1510925Y467206D03*
X1507025D03*
X1520675Y477346D03*
X1514825Y467206D03*
X1512875Y470586D03*
X1491425Y480726D03*
X1495325Y473966D03*
X1491425Y487486D03*
X1499225Y467206D03*
X1520675Y484106D03*
X1524575Y477346D03*
X1512875D03*
X1526525Y480726D03*
X1524575Y484106D03*
X1522625Y480726D03*
X1516775Y477346D03*
X1470643Y495299D03*
X1473140Y525407D03*
X1482200Y477800D03*
X1482958Y486118D03*
X1485100Y469900D03*
X1482000Y481713D03*
Y469902D03*
X1476800Y498900D03*
X1482300D03*
X1476800Y507300D03*
X1481700Y524200D03*
X1473800Y495800D03*
X1499225Y480726D03*
X1508975Y477346D03*
X1510925Y480726D03*
X1508975Y470586D03*
X1510925Y473966D03*
X1505075Y470586D03*
X1501175D03*
X1503125Y467206D03*
X1507025Y487486D03*
X1487525Y473966D03*
X1491425D03*
X1489475Y470586D03*
X1490100Y489700D03*
X1487525Y487486D03*
X1489475Y484106D03*
X1516775D03*
X1514825Y480726D03*
Y473966D03*
X1516775Y470586D03*
X1518725Y487486D03*
Y480726D03*
Y473966D03*
Y467206D03*
X1522625D03*
Y473966D03*
Y487486D03*
X1526525D03*
Y473966D03*
Y467206D03*
X1514825Y487486D03*
X1511752Y498780D03*
X1490929Y507104D03*
X1506060Y508180D03*
X1501490Y504988D03*
X1501934Y513047D03*
X1505743Y516117D03*
X1511215Y507781D03*
X1512400Y519020D03*
X1493930Y522800D03*
X1488410Y517810D03*
X1497267Y505323D03*
X1496174Y514221D03*
X1509000Y498750D03*
X1488500Y498900D03*
X1526500Y498671D03*
Y506400D03*
X1485300Y498962D03*
X1483804Y509928D03*
X1484200Y524200D03*
X1524575Y470586D03*
X1484200Y515700D03*
X1481700D03*
X1475316Y527194D03*
X1472250Y485100D03*
X1472500Y509810D03*
X1501175Y477346D03*
X1493375D03*
X1505075Y484106D03*
X1501175D03*
X1497275Y470586D03*
X1495325Y467206D03*
X1526500Y503800D03*
Y501300D03*
X1507025Y480726D03*
X1495325D03*
X1503125D03*
X1508975Y484106D03*
X1507025Y473966D03*
X1503125D03*
X1493375Y470586D03*
X1499225Y487486D03*
X1497275Y484106D03*
X1493375D03*
X1499225Y473966D03*
X1495325Y487486D03*
X1512875Y484106D03*
X1510925Y487486D03*
X1497275Y477346D03*
X1489475D03*
X1491425Y467206D03*
X1505075Y477346D03*
X1511126Y503038D03*
X1500655Y516122D03*
X1488293Y508000D03*
X1481975Y507975D03*
X1474400Y517200D03*
X1508626Y503038D03*
X1506985Y510645D03*
X1510005Y518155D03*
X1498277Y508239D03*
X1490100Y520000D03*
X1485693Y508000D03*
X1479375Y507975D03*
X1507405Y518155D03*
X1498055Y516122D03*
X1509585Y510645D03*
X1500877Y508239D03*
X1492700Y520000D03*
X1468101Y573963D03*
X1468649Y570012D03*
X1481200Y531200D03*
X1483700D03*
X1527698Y578870D03*
X1474776Y572315D03*
X1491776Y573571D03*
X1479893Y572315D03*
X1482293D03*
X1477493D03*
X1487093D03*
X1489493D03*
X1484693D03*
X1518000Y562330D03*
X1510740Y557860D03*
X1494422Y574000D03*
X1481400Y539700D03*
X1494200Y530600D03*
X1497106Y531368D03*
X1511388Y531045D03*
X1503200Y530500D03*
X1505600D03*
X1508772Y530416D03*
X1514118Y530411D03*
X1483900Y539700D03*
X1525500Y582674D03*
Y580184D03*
X1525837Y574700D03*
X1523416Y573949D03*
X1527822Y576130D03*
X1525500Y577684D03*
X1499900Y574000D03*
X1496900D03*
X1489380Y546030D03*
X1478700Y533700D03*
X1469701Y599554D03*
X1469301Y607790D03*
X1467839Y618964D03*
X1469200Y610739D03*
X1470356Y618000D03*
X1470353Y592128D03*
X1469767Y596353D03*
X1480975Y620100D03*
X1516400Y619800D03*
X1504700Y608500D03*
X1500445Y619956D03*
X1492750Y615903D03*
X1494100Y613280D03*
X1497800Y610000D03*
X1497097Y613043D03*
X1483279Y619100D03*
X1505679Y620111D03*
X1511204Y620056D03*
X1475883Y619217D03*
X1503008Y620018D03*
X1472412Y596032D03*
Y599532D03*
X1479029Y596132D03*
X1477129Y597656D03*
X1474912Y596032D03*
X1480760Y611602D03*
X1485429Y597571D03*
X1491412Y596032D03*
X1489229Y597571D03*
X1487329Y596032D03*
X1512500Y598639D03*
X1510450Y597300D03*
X1507950D03*
X1510450Y600800D03*
X1508031Y599922D03*
X1524800Y598778D03*
X1522900Y597300D03*
X1526950D03*
X1518800Y597200D03*
X1520813Y598508D03*
X1516800Y598639D03*
X1514500Y597300D03*
X1527050Y613000D03*
X1523450Y612900D03*
X1519850Y613000D03*
X1487912Y611632D03*
X1491512Y611732D03*
X1484312D03*
X1511350Y613000D03*
X1513867Y612939D03*
X1516367D03*
X1475812Y611732D03*
X1474912Y599532D03*
X1478329Y611671D03*
X1483104Y596072D03*
X1481229Y597571D03*
X1472932Y619131D03*
X1504700Y611100D03*
X1518900Y619800D03*
X1508550Y619810D03*
X1513700Y619900D03*
X1478500Y619300D03*
X1549334Y23856D03*
X1538520Y11911D03*
X1584447Y-6702D03*
X1584000Y-16100D03*
X1581947Y-6702D03*
X1530800Y3500D03*
X1534000D03*
X1546800Y3400D03*
X1580398Y5400D03*
X1586500Y-16100D03*
X1580398Y-600D03*
X1579447Y-6702D03*
X1549800Y3400D03*
X1554800D03*
X1560500D03*
X1569000D03*
X1566000D03*
X1567498Y12506D03*
X1577048D03*
X1586998Y11355D03*
X1589623Y24528D03*
X1570200Y12900D03*
X1579773Y13257D03*
X1589259Y10241D03*
X1545111Y24172D03*
X1540000Y3400D03*
X1541400Y12500D03*
X1528384Y28040D03*
X1552300Y3400D03*
X1558000D03*
X1544882Y-6900D03*
X1549600Y-10800D03*
X1551309Y12792D03*
X1560700Y13000D03*
X1551834Y23856D03*
X1554434D03*
X1548698Y12506D03*
X1558148Y12306D03*
X1589500Y-600D03*
X1571500Y-1406D03*
X1573048Y12506D03*
X1581998Y11355D03*
X1554148Y12306D03*
X1563498Y12506D03*
X1544698D03*
X1588962Y75926D03*
X1575959Y84198D03*
X1584748Y70840D03*
X1572586Y95639D03*
X1587359Y84348D03*
X1579807Y75841D03*
X1582407D03*
X1570511Y75396D03*
X1573076Y75328D03*
X1573060Y84120D03*
X1589900Y84422D03*
X1583621Y87213D03*
X1588700Y94288D03*
X1573473Y37216D03*
X1582923D03*
X1587734Y70974D03*
X1583374Y81319D03*
X1575018Y71213D03*
X1579100Y69000D03*
X1574780Y90992D03*
X1535300Y78490D03*
X1562850Y73642D03*
X1541520Y79387D03*
X1538870Y78980D03*
X1532800Y78590D03*
X1562575Y76231D03*
X1556810Y71760D03*
X1542179Y39695D03*
X1545572Y38188D03*
X1541988Y90207D03*
Y92707D03*
X1541670Y87760D03*
X1554573Y37216D03*
X1564023D03*
X1544180Y91660D03*
X1546370Y84180D03*
X1545250Y88360D03*
X1556200Y94800D03*
X1529449Y137408D03*
X1557981Y141470D03*
X1572395Y110754D03*
X1574000Y149500D03*
Y152100D03*
X1572634Y98546D03*
X1576506Y143416D03*
X1574197Y127915D03*
X1588000Y100500D03*
X1588500Y106788D03*
X1567968Y136682D03*
X1567981Y139607D03*
X1579310Y128604D03*
X1576606Y104392D03*
X1579290Y131104D03*
X1573153Y103721D03*
X1577770Y149519D03*
X1577950Y152600D03*
X1589622Y112876D03*
X1577700Y155353D03*
Y140149D03*
X1567520Y133354D03*
X1589200Y121800D03*
X1589880Y134851D03*
X1582500Y109900D03*
X1587620Y135921D03*
X1580275Y101041D03*
X1578000Y113000D03*
X1585500Y101000D03*
X1553353Y124209D03*
X1553500Y157000D03*
X1552171Y133000D03*
X1555000Y139000D03*
X1549000Y115571D03*
X1542000Y126246D03*
X1549187Y104713D03*
X1542100Y119200D03*
X1542900Y121700D03*
X1531700Y155600D03*
X1541421Y106742D03*
X1541800Y99700D03*
X1541900Y97300D03*
X1541413Y155259D03*
X1541434Y139871D03*
X1531678Y135284D03*
X1541390Y136498D03*
X1558136Y100877D03*
X1554627D03*
X1553500Y121000D03*
X1548955Y101358D03*
X1558189Y107067D03*
X1554800Y129100D03*
Y98200D03*
X1558100D03*
X1558383Y121500D03*
X1554945Y133400D03*
X1531726Y123800D03*
X1563108Y126423D03*
X1541351Y151900D03*
X1558100Y138025D03*
Y133526D03*
Y124427D03*
Y128926D03*
X1531985Y147000D03*
X1532923Y144518D03*
X1542685Y133321D03*
X1555676Y123283D03*
X1573121Y120649D03*
X1583600Y207495D03*
X1566486Y181270D03*
X1583874Y217746D03*
X1582249Y191716D03*
X1587549Y192000D03*
X1566858Y175192D03*
X1570294Y167384D03*
X1572817Y169910D03*
X1568488Y164058D03*
X1571501Y180031D03*
X1553500Y165400D03*
X1557787Y192236D03*
X1561925Y192675D03*
X1558000Y205100D03*
X1557979Y188844D03*
X1535000Y207200D03*
X1535425Y188016D03*
X1535399Y190920D03*
X1552063Y202031D03*
X1549693Y196707D03*
X1548178Y190880D03*
X1545910Y199977D03*
X1546000Y197400D03*
X1543100Y184128D03*
X1533132Y158068D03*
X1531565Y176645D03*
X1537298Y162703D03*
X1535065Y164300D03*
X1561538Y174649D03*
X1545023Y161675D03*
X1562150Y160700D03*
X1557634Y175948D03*
X1562079Y163580D03*
X1552051Y172053D03*
X1567000Y259560D03*
X1568120Y251710D03*
X1574560Y237660D03*
X1571876Y255800D03*
X1570272Y234889D03*
X1572730Y235931D03*
X1586950Y251267D03*
X1570318Y238116D03*
X1572700Y239400D03*
X1568365Y247761D03*
X1589592Y252472D03*
X1582699Y252646D03*
X1579867Y265445D03*
X1530200Y257200D03*
X1531935Y224160D03*
X1533596Y273504D03*
X1532237Y247801D03*
X1528460Y244371D03*
X1537972Y236000D03*
X1542690Y236050D03*
X1541325Y245090D03*
X1547869Y243356D03*
X1547375Y245850D03*
X1542751Y240477D03*
X1563157Y258164D03*
X1561104Y234255D03*
X1563440Y250955D03*
X1559577Y236300D03*
X1558700Y252000D03*
X1574900Y240900D03*
X1547000Y263500D03*
Y269400D03*
X1541000Y263500D03*
Y269500D03*
X1544000Y266500D03*
X1584568Y281339D03*
X1589476Y322953D03*
X1565235Y303734D03*
X1578630Y293430D03*
X1572336Y287063D03*
X1578790Y290920D03*
X1581077Y284825D03*
X1578577Y284799D03*
X1565000Y290500D03*
X1571293Y284755D03*
X1573790Y284895D03*
X1580365Y341293D03*
X1577486Y307621D03*
X1566000Y341000D03*
X1587800Y308200D03*
X1580150Y329483D03*
X1581090Y338795D03*
X1569211Y331542D03*
Y334142D03*
X1569926Y308064D03*
X1566910Y315117D03*
X1581940Y295820D03*
X1588551Y341410D03*
X1583794Y338767D03*
X1581834Y318591D03*
X1583500Y303120D03*
Y300560D03*
X1573950Y338050D03*
X1585479Y316610D03*
X1582859Y341112D03*
X1570574Y341776D03*
X1528250Y311900D03*
X1530033Y340799D03*
X1533228Y325000D03*
X1529734Y319714D03*
X1532850Y303950D03*
X1530500Y287700D03*
X1537500Y292800D03*
X1533914Y286073D03*
X1533838Y288706D03*
X1554932Y332171D03*
X1560024Y331800D03*
X1564427Y311083D03*
X1548334Y325497D03*
X1548273Y313227D03*
X1543864Y311399D03*
X1551250Y320303D03*
X1547398Y333823D03*
X1554775Y295328D03*
X1560024Y329200D03*
X1536027Y305048D03*
X1534833Y309798D03*
X1539400Y320200D03*
X1544904Y334008D03*
X1557250Y315410D03*
X1551404Y309376D03*
X1560400Y307683D03*
X1550619Y303087D03*
X1559997Y310317D03*
X1534400Y296029D03*
X1564411Y315210D03*
X1538450Y314300D03*
X1543700Y322600D03*
X1563000Y341000D03*
X1538206Y303741D03*
X1542200Y324600D03*
X1548024Y322145D03*
X1548000Y331361D03*
X1546612Y287812D03*
X1559500Y290300D03*
X1559800Y285300D03*
X1548199Y285830D03*
X1552900Y281700D03*
X1554800Y290600D03*
X1548100Y342200D03*
X1538406Y330157D03*
X1554800Y341100D03*
X1557550D03*
X1547882Y318942D03*
X1550800Y296200D03*
X1549000Y316600D03*
X1540175Y387654D03*
X1551875D03*
X1565525Y397794D03*
X1528475Y401174D03*
Y387654D03*
Y394414D03*
X1530425Y377514D03*
X1534325Y384274D03*
Y397794D03*
Y377514D03*
X1542300Y376717D03*
X1551875Y394414D03*
X1540175Y380894D03*
Y401174D03*
X1536275D03*
X1540175Y394414D03*
X1563575Y387654D03*
X1551875Y401174D03*
X1559675Y380894D03*
X1563575D03*
X1565525Y384274D03*
X1586400Y392900D03*
X1567475Y380894D03*
Y387654D03*
X1582420Y377830D03*
X1582350Y374567D03*
X1582124Y381164D03*
X1573000Y391161D03*
X1571366Y401154D03*
X1582000Y396250D03*
X1567475Y394414D03*
X1570672Y362134D03*
X1567121Y365817D03*
X1576380Y362890D03*
X1582500Y369600D03*
X1573521Y365500D03*
X1571375Y394414D03*
X1565525Y377514D03*
X1567121Y363217D03*
X1566922Y359681D03*
X1567475Y401174D03*
X1576074Y359600D03*
X1582600Y389300D03*
X1571450Y359650D03*
X1565525Y391034D03*
X1570289Y384368D03*
X1585150Y397400D03*
X1571585Y382230D03*
X1586500Y354900D03*
X1589100Y358400D03*
X1569425Y391034D03*
Y397794D03*
X1587683Y397414D03*
X1571375Y387654D03*
X1569584Y378002D03*
X1581822Y365770D03*
X1587968Y403368D03*
X1530425Y384274D03*
X1533719Y362783D03*
X1533790Y360283D03*
X1528475Y380894D03*
X1529829Y362655D03*
X1530425Y391034D03*
Y397794D03*
X1532375Y401174D03*
Y380894D03*
Y387654D03*
Y394414D03*
X1533589Y366361D03*
X1532367Y356530D03*
X1553825Y391034D03*
X1546025D03*
X1563575Y394414D03*
X1557725Y397794D03*
X1550639Y350200D03*
X1563575Y401174D03*
X1538200Y364700D03*
X1553825Y397794D03*
X1546025D03*
X1538500Y359363D03*
X1552500Y358500D03*
X1557725Y377514D03*
X1538397Y361861D03*
X1538478Y350694D03*
Y353294D03*
Y355894D03*
X1559675Y401174D03*
X1542125Y397794D03*
X1558950Y363050D03*
X1547975Y394414D03*
X1542932Y355740D03*
X1547975Y387654D03*
X1536275D03*
Y380894D03*
X1534325Y391034D03*
X1559675Y387654D03*
Y394414D03*
X1551875Y380894D03*
X1557725Y391034D03*
X1536275Y394414D03*
X1558980Y360130D03*
X1538225Y377514D03*
Y384274D03*
X1544075Y380894D03*
Y387654D03*
X1538225Y391034D03*
Y397794D03*
X1544075Y394414D03*
X1558996Y365817D03*
X1555775Y394414D03*
X1549925Y397794D03*
X1561625D03*
X1555775Y401174D03*
X1549925Y377514D03*
X1561625D03*
Y391034D03*
Y384274D03*
X1549925Y391034D03*
Y384274D03*
X1555775Y387654D03*
Y380894D03*
X1560500Y350000D03*
X1557534Y353400D03*
X1553825Y377514D03*
X1543300Y360900D03*
X1543528Y352446D03*
X1546182Y355446D03*
X1543528Y349946D03*
X1543300Y363400D03*
X1550417Y362607D03*
X1586500Y358400D03*
X1587684Y362653D03*
X1565525Y460446D03*
X1567475Y414694D03*
Y443546D03*
Y463826D03*
X1565525Y453686D03*
Y418074D03*
X1571375Y421454D03*
X1569425Y418074D03*
X1565525Y424834D03*
X1571375Y414694D03*
Y407934D03*
X1565525Y446926D03*
X1528475Y463826D03*
X1559675D03*
X1542125Y460446D03*
X1536275Y463826D03*
X1555775Y407934D03*
X1561625Y411314D03*
Y440166D03*
X1551875Y443546D03*
X1557725Y460446D03*
X1553825D03*
X1563575Y450306D03*
X1546025Y460446D03*
X1563575Y463826D03*
X1557725Y440166D03*
Y418074D03*
X1563575Y421454D03*
X1580370Y462090D03*
X1584200Y462610D03*
X1557725Y424834D03*
X1569425Y440166D03*
X1587559Y423835D03*
X1567475Y436786D03*
X1588870Y440546D03*
X1571375Y443546D03*
X1588632Y452151D03*
X1587550Y456550D03*
X1585920Y452368D03*
X1587573Y445300D03*
X1587000Y411976D03*
X1571375Y436786D03*
X1589500Y412035D03*
X1583208Y404941D03*
X1569425Y446926D03*
X1584233Y427947D03*
X1565525Y411314D03*
X1583773Y436137D03*
X1585560Y421324D03*
X1581939Y426594D03*
X1583208Y452185D03*
X1569425Y453686D03*
X1589396Y425674D03*
X1567475Y450306D03*
X1565525Y440166D03*
X1571375Y457066D03*
X1567475D03*
X1569425Y460446D03*
X1582200Y456200D03*
X1565525Y431594D03*
X1569425D03*
Y404554D03*
X1583208Y412815D03*
X1584975Y460210D03*
X1587475D03*
X1582200Y460310D03*
X1569425Y424834D03*
Y411314D03*
X1567475Y407934D03*
X1582300Y446100D03*
X1571390Y464480D03*
X1587238Y432593D03*
X1583208Y416752D03*
X1567475Y421454D03*
X1532375Y463826D03*
Y407934D03*
X1531250Y445100D03*
Y448250D03*
X1528475Y457066D03*
X1532349Y455200D03*
X1531250Y419900D03*
Y451400D03*
Y426200D03*
Y429350D03*
Y423050D03*
Y438800D03*
Y435650D03*
Y441950D03*
X1530425Y460446D03*
X1528475Y407934D03*
X1551875D03*
Y414694D03*
X1563575Y407934D03*
X1559675Y414694D03*
X1546025Y404554D03*
X1561625Y424834D03*
X1551990Y421158D03*
X1551875Y428214D03*
X1561625Y431594D03*
X1563575Y428214D03*
X1555775Y443546D03*
Y436786D03*
X1563575Y457066D03*
X1549938Y453714D03*
X1547975Y457066D03*
X1549925Y446926D03*
X1557725D03*
X1561625Y460446D03*
X1555775Y457066D03*
X1551875D03*
X1557725Y453686D03*
X1559675Y443546D03*
Y436786D03*
X1547975Y463826D03*
X1551875D03*
X1555775D03*
X1538225Y460446D03*
X1559675Y407934D03*
X1561625Y446926D03*
X1543850Y416750D03*
Y413600D03*
X1540700Y416750D03*
X1534400D03*
X1537550D03*
X1551875Y450306D03*
X1534400Y413500D03*
X1549950Y404490D03*
X1544075Y463826D03*
X1537550Y413600D03*
X1536275Y407934D03*
X1540175D03*
X1540700Y413600D03*
X1543850Y445100D03*
Y451400D03*
X1549926Y411312D03*
X1553825Y411314D03*
X1544150Y409900D03*
X1553825Y446926D03*
Y440166D03*
X1555775Y414694D03*
X1561625Y418074D03*
X1540700Y445100D03*
X1537550Y448250D03*
X1534400D03*
X1540700D03*
X1537550Y445100D03*
X1534400D03*
X1540700Y435650D03*
X1547754Y430351D03*
X1547755Y423570D03*
X1547754Y427884D03*
X1553825Y453686D03*
X1547000Y435650D03*
X1549925Y431594D03*
X1547755Y421138D03*
X1549925Y440166D03*
X1543950Y438800D03*
X1543850Y441950D03*
X1549964Y424753D03*
X1551875Y436786D03*
X1540653Y454588D03*
X1540700Y423050D03*
X1537550Y429350D03*
X1540700D03*
X1534400Y426200D03*
X1537550D03*
X1540700D03*
X1534400Y429350D03*
Y423050D03*
X1537550D03*
X1534400Y438800D03*
Y435650D03*
X1549925Y460446D03*
X1559595Y450631D03*
X1547000Y416750D03*
X1557725Y404554D03*
X1563575Y414694D03*
X1559675Y457066D03*
X1534400Y419900D03*
X1540700D03*
X1543850Y429350D03*
Y426200D03*
X1537550Y419900D03*
X1534325Y404554D03*
X1538225D03*
X1542125D03*
X1540700Y410450D03*
X1534400Y451400D03*
Y441950D03*
X1537550D03*
X1534325Y460446D03*
X1537550Y451400D03*
X1544075Y457066D03*
X1540175D03*
X1540700Y451400D03*
Y441950D03*
X1540175Y463826D03*
X1543850Y435650D03*
X1537550D03*
Y438800D03*
X1540700D03*
X1536300Y455200D03*
X1553825Y418074D03*
X1559675Y421454D03*
X1555775D03*
X1567475Y477346D03*
X1565525Y473966D03*
X1569425Y467206D03*
X1565525D03*
X1571545Y482842D03*
X1571375Y477346D03*
X1530425Y467206D03*
X1561625D03*
X1563575Y470586D03*
X1561625Y473966D03*
X1551875Y470586D03*
X1549925Y467206D03*
X1559675Y470586D03*
X1557725Y467206D03*
X1547975Y484106D03*
X1551875D03*
X1549925Y480726D03*
X1559675Y477346D03*
X1563575Y484106D03*
X1561625Y480726D03*
X1536275Y477346D03*
X1559675Y484106D03*
X1530425Y480726D03*
Y487486D03*
X1557725D03*
X1561625D03*
X1534325Y473966D03*
X1582644Y495077D03*
X1568600Y494500D03*
X1565210Y509160D03*
X1567817Y499735D03*
X1569425Y473966D03*
X1571375Y470586D03*
X1565525Y480726D03*
X1570062Y487039D03*
X1587970Y472370D03*
X1587433Y490425D03*
X1567475Y470586D03*
X1584970Y472370D03*
X1589025Y495975D03*
X1568400Y503300D03*
X1567475Y484106D03*
X1565525Y487486D03*
X1569425Y480726D03*
X1531685Y499540D03*
Y502040D03*
X1532375Y470586D03*
X1530425Y473966D03*
X1528475Y470586D03*
Y477346D03*
X1534180Y498580D03*
X1534039Y502906D03*
X1531580Y510790D03*
X1534020Y511930D03*
X1533595Y505530D03*
Y509030D03*
X1534325Y467206D03*
X1538225D03*
X1542125D03*
X1540175Y470586D03*
X1555510Y501975D03*
Y499475D03*
X1555438Y507217D03*
Y509717D03*
X1565000Y506329D03*
Y503329D03*
X1534325Y487486D03*
X1536275Y484106D03*
X1544075Y470586D03*
X1542125Y473966D03*
X1540175Y477346D03*
X1536275Y470586D03*
X1544075Y477346D03*
X1538225Y473966D03*
X1542475Y504400D03*
X1542425Y512200D03*
X1546025Y467206D03*
X1553825Y487486D03*
Y480726D03*
X1557725D03*
X1549925Y473966D03*
X1547975Y470586D03*
X1553825Y473966D03*
Y467206D03*
X1555775Y470586D03*
X1557725Y473966D03*
X1555775Y477346D03*
Y484106D03*
X1549925Y487486D03*
X1546025Y480726D03*
X1548300Y499000D03*
X1564600Y500414D03*
X1555424Y504609D03*
X1555832Y512288D03*
X1548300Y506600D03*
X1544075Y484106D03*
X1542125Y480726D03*
X1538225Y487486D03*
X1546025D03*
X1540175Y484106D03*
X1542125Y487486D03*
X1551875Y477346D03*
X1548300Y504000D03*
X1563575Y477346D03*
X1542475Y507000D03*
Y499400D03*
X1548300Y509200D03*
X1538225Y480726D03*
X1534325D03*
X1528475Y484106D03*
X1532375D03*
Y477346D03*
X1547975D03*
X1546025Y473966D03*
X1548300Y501500D03*
X1542475Y501900D03*
Y509600D03*
X1548300Y511800D03*
X1565389Y585721D03*
X1581730Y537170D03*
X1587610Y579550D03*
X1580360Y565524D03*
X1580400Y568000D03*
X1580300Y563000D03*
Y560500D03*
X1566000Y575820D03*
X1565940Y573120D03*
X1565800Y570600D03*
X1565600Y568100D03*
Y565700D03*
X1529944Y574725D03*
X1529894Y577342D03*
X1532354Y577283D03*
X1532642Y579853D03*
X1529600Y582300D03*
X1532400D03*
X1529942Y579853D03*
X1563800Y564100D03*
X1561300Y564000D03*
X1558800Y563900D03*
X1563448Y566766D03*
X1563432Y569340D03*
X1545200Y585724D03*
X1542600D03*
X1550990Y586588D03*
X1554358Y587258D03*
X1589604Y585896D03*
X1581704D03*
X1586700Y620100D03*
X1587679Y596867D03*
X1585179Y596902D03*
X1579900Y606050D03*
X1587504Y605496D03*
Y607996D03*
X1573260Y601600D03*
X1570660Y601563D03*
X1566520Y623382D03*
X1569495Y623365D03*
X1572950Y593950D03*
X1573500Y619500D03*
X1529067Y615784D03*
X1529697Y613384D03*
X1532270Y610764D03*
X1532160Y613408D03*
X1546075Y618145D03*
X1544050Y615296D03*
X1534968Y597268D03*
X1535565Y591658D03*
X1560747Y623576D03*
X1557575Y623559D03*
X1541162Y607903D03*
X1543697Y606719D03*
X1563827Y621376D03*
X1554800Y620910D03*
X1537711Y613397D03*
X1538679Y615641D03*
X1534928Y610532D03*
X1538337Y601097D03*
X1534948Y613302D03*
X1545000Y591100D03*
X1540477Y620308D03*
X1540700Y613700D03*
X1552198Y623479D03*
X1553000Y591100D03*
X1541384Y601262D03*
X1581704Y590196D03*
X1589604D03*
X1558800Y599300D03*
X1560400Y611600D03*
X1564300Y599400D03*
X1564400Y605500D03*
X1561700Y602200D03*
X1552400Y607600D03*
X1554900Y607100D03*
X1556200Y602400D03*
X1554400Y599300D03*
X1564300Y611500D03*
X1577000Y619500D03*
X1545407Y604713D03*
X1555600Y591100D03*
X1595004Y-17346D03*
X1598602Y3437D03*
X1605500Y-3600D03*
X1592453Y8502D03*
X1610004Y-17346D03*
X1623900Y4600D03*
X1605004Y-17346D03*
X1600004D03*
X1602504D03*
X1608500Y-3600D03*
X1592829Y24460D03*
X1597800Y24300D03*
X1646200Y5300D03*
X1646400Y13400D03*
X1637482Y21623D03*
X1638550Y7200D03*
X1597700Y9000D03*
X1595848Y11406D03*
X1617000Y9500D03*
X1617500Y-14500D03*
X1601650Y24160D03*
X1597504Y-17346D03*
X1615000Y12000D03*
X1634200Y9700D03*
X1627500Y11700D03*
X1608123Y13302D03*
X1619100Y6500D03*
X1626400Y4600D03*
X1606700D03*
X1636500D03*
X1607504Y-17346D03*
X1601102Y-600D03*
X1590431Y-6702D03*
X1598602Y-600D03*
X1591848Y11406D03*
X1648748Y6325D03*
X1638865Y11105D03*
X1629148Y6825D03*
X1619798Y10755D03*
X1643865Y11105D03*
X1634148Y6825D03*
X1624798Y10755D03*
X1600898Y11355D03*
X1609833Y5425D03*
X1605898Y11355D03*
X1614833Y5425D03*
X1592715Y70817D03*
X1591600Y75700D03*
X1593000Y78140D03*
X1591270Y93940D03*
X1592200Y37700D03*
X1590464Y77962D03*
X1637700Y67400D03*
X1640900Y66900D03*
X1650876Y65237D03*
X1648276Y65221D03*
X1651250Y36750D03*
X1639623Y38100D03*
X1649073Y38200D03*
X1649900Y78600D03*
X1620050Y35550D03*
X1608500Y72688D03*
X1615115Y70786D03*
X1612000Y70984D03*
X1635337Y73500D03*
X1619000Y38500D03*
X1599000Y61500D03*
X1620900Y81300D03*
X1632000Y73500D03*
X1627489Y74960D03*
X1630386Y41448D03*
X1651298Y39462D03*
X1641848D03*
X1632398Y39862D03*
X1602000Y84500D03*
X1596900D03*
X1620733Y74847D03*
X1623200Y75800D03*
X1606797Y64949D03*
X1608452Y62890D03*
X1599500Y75000D03*
X1606579Y86726D03*
X1599500Y84500D03*
X1614169Y95004D03*
X1617347Y94581D03*
X1597867Y93900D03*
X1614997Y84403D03*
X1596050Y75400D03*
X1606730Y84230D03*
X1632000Y83000D03*
X1625451Y84288D03*
X1605184Y61044D03*
X1610450Y37300D03*
X1627380Y36652D03*
X1630121Y37609D03*
X1595943Y71522D03*
X1603138Y65890D03*
X1602840Y37382D03*
X1635900Y83000D03*
X1625075Y80182D03*
X1610853Y63861D03*
X1622635Y39900D03*
X1646848Y39462D03*
X1637398Y39862D03*
X1627715Y39934D03*
X1613741Y112341D03*
X1593241Y134295D03*
X1628788Y97800D03*
X1593756Y129048D03*
X1590800Y137800D03*
X1593500D03*
X1590949Y97850D03*
X1595335Y98135D03*
X1641600Y96500D03*
X1638500D03*
X1595522Y127278D03*
X1648000Y100597D03*
X1598449Y120760D03*
X1598300Y116477D03*
X1632020Y97871D03*
X1600000Y104243D03*
X1630836Y197560D03*
X1637870Y197577D03*
X1590525Y217033D03*
X1590495Y214525D03*
X1593020Y215129D03*
X1593218Y191776D03*
X1592870Y217900D03*
X1595291Y166423D03*
X1591800Y164900D03*
X1626935Y217775D03*
X1598006Y192421D03*
X1611761Y216250D03*
X1651000Y178628D03*
X1645700Y214050D03*
X1650600Y186300D03*
X1648349Y182276D03*
X1650300Y195251D03*
X1648400Y214100D03*
X1643887Y181841D03*
X1642457Y186948D03*
X1637870Y195077D03*
X1644290Y196383D03*
X1634069Y197454D03*
X1604401Y213500D03*
X1618500Y181680D03*
X1625524Y184531D03*
X1635100Y182800D03*
X1620036Y196186D03*
X1635112Y195181D03*
X1605250Y197250D03*
X1629595Y217725D03*
X1627326Y182759D03*
X1613053Y184949D03*
X1610554Y184877D03*
X1615362Y213507D03*
X1615553Y184908D03*
X1611761Y213507D03*
X1602185Y180709D03*
X1628950Y195344D03*
X1632590D03*
X1635351Y185444D03*
X1619500Y184944D03*
X1622248Y185060D03*
X1644433Y185415D03*
X1641800Y184400D03*
X1614000Y177800D03*
X1598950Y180300D03*
X1595800D03*
X1608056Y184771D03*
X1604222Y268107D03*
X1627177Y260267D03*
X1637281Y254322D03*
X1636684Y279815D03*
X1591865Y237407D03*
X1591174Y225017D03*
X1627024Y253387D03*
X1627043Y256900D03*
X1638216Y246021D03*
X1636684Y274815D03*
X1637269Y264421D03*
X1637281Y260922D03*
X1636914Y270900D03*
X1643106Y233913D03*
X1640871Y235210D03*
X1596600Y246350D03*
X1596300Y250320D03*
X1608489Y252095D03*
X1601870Y270470D03*
X1626124Y225250D03*
X1599270Y246310D03*
X1600810Y266006D03*
X1609051Y243415D03*
X1624798Y241937D03*
X1631300Y280400D03*
X1626291Y273309D03*
X1597201Y238188D03*
X1621164Y223392D03*
X1620250Y254741D03*
X1621164Y225910D03*
X1620240Y257660D03*
X1617498Y273433D03*
X1628624Y225318D03*
X1598028Y256422D03*
X1610290Y265352D03*
X1600552Y261281D03*
X1636684Y277315D03*
X1623447Y273273D03*
X1639413Y310235D03*
X1592110Y322002D03*
X1590176Y331844D03*
X1590212Y315425D03*
X1636800Y287956D03*
X1636922Y302588D03*
X1636861Y305091D03*
X1639040Y316343D03*
X1638086Y319664D03*
X1619897Y338636D03*
Y336136D03*
X1631015Y328350D03*
X1619897Y341136D03*
X1635355Y324228D03*
X1609172Y339630D03*
X1602776Y331304D03*
X1625846Y286154D03*
X1638063Y326504D03*
X1636822Y294946D03*
X1639413Y312735D03*
X1636925Y297444D03*
X1636822Y292446D03*
X1642712Y342347D03*
X1636684Y283141D03*
X1635503Y340146D03*
X1629503D03*
X1630200Y367730D03*
X1630900Y375600D03*
X1622100Y400600D03*
X1603307Y393224D03*
X1591912Y391052D03*
X1590218Y350995D03*
X1642443Y344879D03*
X1638991Y352037D03*
X1640001Y370790D03*
X1650624Y357884D03*
X1650480Y368215D03*
X1642126Y357894D03*
X1642114Y368142D03*
X1601060Y401010D03*
X1599100Y399100D03*
X1610828Y381387D03*
X1596151D03*
X1596168Y375135D03*
X1609761Y372584D03*
X1608146Y380322D03*
Y376171D03*
X1630300Y395300D03*
X1630408Y357603D03*
X1630550Y401300D03*
X1630534Y354900D03*
X1630476Y360103D03*
X1630400Y398700D03*
X1629300Y385400D03*
X1630240Y365099D03*
X1630400Y391800D03*
X1597900Y370000D03*
X1597850Y367329D03*
X1643150Y348692D03*
X1643700Y351667D03*
X1630337Y362600D03*
X1621727Y395374D03*
X1613474Y391105D03*
X1609271Y348166D03*
X1608850Y343835D03*
X1613452Y387098D03*
X1610140Y358350D03*
X1610370Y361890D03*
X1607412Y360895D03*
X1602215Y363981D03*
X1630000Y381400D03*
X1620447Y373926D03*
X1610642Y375135D03*
X1608020Y356500D03*
X1619889Y352841D03*
X1607443Y398649D03*
X1598878Y380344D03*
X1629503Y346146D03*
X1635503Y346046D03*
X1632503Y343146D03*
X1598878Y376346D03*
X1630120Y418887D03*
X1595800Y405900D03*
X1621000Y452000D03*
X1612500Y411800D03*
X1618800Y453400D03*
X1595200Y412700D03*
X1617900Y409900D03*
X1630750Y404800D03*
X1591446Y440472D03*
X1591344Y452134D03*
X1591430Y409440D03*
X1591350Y445300D03*
X1593400Y432200D03*
X1639500Y435700D03*
X1640625Y429460D03*
X1640000Y456900D03*
X1640100Y459700D03*
X1630200Y457175D03*
X1630300Y452100D03*
X1630150Y427663D03*
X1611642Y461877D03*
X1600400Y446100D03*
X1630219Y446000D03*
X1621000Y440500D03*
X1621044Y433364D03*
X1612250Y432500D03*
X1611418Y422971D03*
X1621182Y427091D03*
X1621347Y415297D03*
X1603719Y412000D03*
X1611638Y454809D03*
X1612100Y446000D03*
X1603000Y435500D03*
X1630386Y413942D03*
X1634400Y412900D03*
X1630276Y449517D03*
X1612183Y442623D03*
X1602600Y444287D03*
X1603050Y432523D03*
X1621010Y435870D03*
X1620500Y463727D03*
X1634500Y418500D03*
X1603650Y415469D03*
X1646540Y441240D03*
X1639750Y445477D03*
X1639500Y433200D03*
X1646480Y443880D03*
X1639774Y439486D03*
X1646451Y452590D03*
X1646469Y450090D03*
X1646525Y447590D03*
X1639822Y453140D03*
X1647200Y430450D03*
X1622700Y461900D03*
X1612825Y405438D03*
Y408974D03*
X1596500Y455500D03*
X1615061Y463157D03*
X1603000Y422971D03*
X1630200Y454675D03*
X1621226Y445026D03*
X1612256Y440088D03*
X1611935Y429515D03*
X1623749Y464213D03*
X1604200Y464387D03*
X1612250Y435500D03*
X1650944Y505166D03*
X1648330Y504544D03*
X1594880Y494880D03*
X1592025Y495975D03*
X1641963Y495964D03*
X1639391Y513065D03*
X1642670Y514939D03*
X1649336Y511502D03*
X1641470Y506403D03*
X1644651Y505500D03*
X1649545Y515215D03*
X1645969Y514870D03*
X1646700Y480300D03*
X1639394Y507798D03*
X1642880Y490047D03*
X1640781Y487760D03*
X1617700Y475957D03*
X1614000Y475970D03*
X1623705Y467855D03*
X1619607Y469945D03*
X1616607D03*
X1601557Y479225D03*
X1617300Y519000D03*
X1614900Y498575D03*
X1615100Y481400D03*
X1617600D03*
X1600780Y495416D03*
X1597380D03*
X1630159Y520608D03*
X1612500Y510300D03*
X1615000D03*
X1627032Y510226D03*
X1627068Y512626D03*
X1606200Y487100D03*
X1623814Y471400D03*
X1614000Y469500D03*
X1617700Y489700D03*
X1615200D03*
X1611506Y474768D03*
X1620500Y475000D03*
X1603500Y495300D03*
X1597178Y472226D03*
X1599900Y487100D03*
X1603802Y487205D03*
X1633359Y472859D03*
X1633075Y470174D03*
X1629778Y507294D03*
X1627407Y520318D03*
X1621783Y498617D03*
X1625485Y494188D03*
X1627622Y524928D03*
X1620030Y525066D03*
X1623551Y525015D03*
X1590580Y472370D03*
X1594280D03*
X1637500Y529400D03*
X1644800Y532800D03*
X1636848Y533794D03*
X1649900Y583500D03*
X1638674Y556178D03*
X1599070Y562266D03*
X1596570D03*
X1599120Y564764D03*
X1596620D03*
X1596600Y567250D03*
X1626518Y528029D03*
X1622040Y554827D03*
X1609829Y556599D03*
X1624293Y561747D03*
X1615030Y584260D03*
X1610080Y561367D03*
X1603060Y582920D03*
X1603120Y578020D03*
X1599170Y572780D03*
X1602000Y565700D03*
X1631975Y527700D03*
X1601540Y588793D03*
X1625094Y559200D03*
X1601825Y572325D03*
X1607533Y561644D03*
X1601825Y568325D03*
X1607533Y557644D03*
X1605994Y578500D03*
X1612519Y586004D03*
X1605994Y582500D03*
X1594110Y611510D03*
X1592934Y592396D03*
X1590304Y596896D03*
X1590004Y605496D03*
Y607996D03*
X1590530Y610620D03*
X1590881Y618788D03*
X1593519Y618736D03*
X1644856Y604930D03*
X1640921Y605334D03*
X1601504Y591526D03*
X1617600Y619800D03*
X1619700Y617300D03*
X1622330Y592325D03*
X1603550Y618250D03*
X1600950D03*
X1613721Y592325D03*
X1614700Y597000D03*
X1615862Y605507D03*
X1601489Y602812D03*
X1601270Y597200D03*
X1602150Y610720D03*
X1612519Y590004D03*
X1613349Y603250D03*
X1603919Y596750D03*
X1603869Y608450D03*
X1613349Y599250D03*
X1603869Y604450D03*
X1654800Y13518D03*
X1653100Y11500D03*
X1685948Y10725D03*
X1711863Y13276D03*
X1672427Y9700D03*
X1680033Y-16711D03*
X1666500Y10500D03*
X1688000Y3000D03*
X1676819Y-16779D03*
X1691000Y3000D03*
X1695200Y11317D03*
X1704771Y11261D03*
X1673500Y-16850D03*
X1680034Y2863D03*
X1664200Y5400D03*
X1656600Y6300D03*
X1664823Y13287D03*
X1685500Y3000D03*
X1682985Y2901D03*
X1675800Y4100D03*
X1702421Y13231D03*
X1684902Y13472D03*
X1691541Y13226D03*
X1653748Y6325D03*
X1676428Y11381D03*
X1666979Y6236D03*
X1657369Y10258D03*
X1690948Y10725D03*
X1681428Y11381D03*
X1671979Y6236D03*
X1662373Y10154D03*
X1700200Y11317D03*
X1709771Y11261D03*
X1682396Y74344D03*
X1693900Y73300D03*
X1697300Y73296D03*
X1700710Y73292D03*
X1690500Y73950D03*
X1679900Y74500D03*
X1678000Y81600D03*
X1653000Y77600D03*
X1669000Y92000D03*
X1659000Y88000D03*
X1661900Y92400D03*
X1708610Y85121D03*
X1709184Y88811D03*
X1707268Y77668D03*
X1692300Y56900D03*
X1684248Y56746D03*
X1658600Y44700D03*
X1696655Y77991D03*
X1694155D03*
X1691655D03*
X1689155D03*
X1700300Y94703D03*
X1704824Y90049D03*
X1674749Y87050D03*
X1676428Y74646D03*
X1673800Y75200D03*
X1675500Y81600D03*
X1673000D03*
X1670500D03*
X1678627Y54616D03*
X1672000Y51500D03*
X1712600Y46100D03*
X1669350Y69962D03*
X1664350Y72462D03*
Y69962D03*
X1659196Y70291D03*
X1661563Y72028D03*
X1709600Y45800D03*
X1711000Y55525D03*
X1669500Y51500D03*
X1656600Y73614D03*
X1659100D03*
X1668000Y81600D03*
X1665500D03*
X1695300Y94712D03*
X1697800Y94612D03*
X1692285D03*
X1692573Y85833D03*
X1702513Y79885D03*
X1696870Y86093D03*
X1689250Y86000D03*
X1668009Y37000D03*
X1667000Y51500D03*
X1706500Y37000D03*
X1678000D03*
X1687500D03*
X1660944Y36761D03*
X1696795Y38260D03*
X1708508Y39350D03*
X1699273Y39679D03*
X1679648Y39462D03*
X1670198D03*
X1660748D03*
X1689098D03*
X1658559Y37890D03*
X1659038Y95111D03*
X1659000Y85500D03*
X1670250Y87873D03*
X1667000Y88000D03*
X1663000Y81600D03*
X1677573Y86930D03*
X1677649Y90301D03*
X1675062Y91219D03*
X1656298Y39462D03*
X1712308Y39350D03*
X1703073Y39679D03*
X1694098Y39462D03*
X1684648D03*
X1675198D03*
X1665748D03*
X1654685Y121790D03*
X1664135Y131239D03*
X1657835D03*
X1689368Y98750D03*
X1686876Y98962D03*
X1680139Y99073D03*
X1696907Y99077D03*
X1664500Y99000D03*
X1657835Y156436D03*
X1660400Y98500D03*
X1672200Y112200D03*
X1701455Y153083D03*
X1698927Y153139D03*
X1674800Y103100D03*
X1655209Y181761D03*
X1680370Y185900D03*
X1674019Y175990D03*
X1663566Y213009D03*
X1674455Y169991D03*
X1677605Y169986D03*
X1674455Y172658D03*
X1655031Y184505D03*
X1654015Y217239D03*
X1655978Y207827D03*
X1663400Y179475D03*
X1681352Y196092D03*
X1686183Y191250D03*
X1683484Y190908D03*
X1687950Y186150D03*
X1682950Y184140D03*
X1680450Y183401D03*
X1708350Y175050D03*
X1708250Y164950D03*
X1688046Y174447D03*
X1667356Y213096D03*
X1660440Y200789D03*
X1702400Y193450D03*
X1702450Y190000D03*
X1664321Y195244D03*
X1658082Y195298D03*
X1673800Y201070D03*
X1660800Y181900D03*
X1687550Y213751D03*
X1671556Y208379D03*
X1702500Y187000D03*
X1713000Y185000D03*
X1709900Y187300D03*
X1705666Y198055D03*
X1676750Y206050D03*
X1667140Y182300D03*
X1674912Y183000D03*
X1669849Y193067D03*
X1674066Y196666D03*
X1673530Y209974D03*
X1703610Y161214D03*
X1700836Y161268D03*
X1695734Y164676D03*
X1666345Y241987D03*
X1683729Y242346D03*
X1690565Y251052D03*
X1667667Y257920D03*
X1670140Y257547D03*
X1670822Y254691D03*
X1661186Y245352D03*
X1662000Y250008D03*
X1664324Y248002D03*
X1666329Y245139D03*
X1662956Y243582D03*
X1681760Y245500D03*
X1684509Y245631D03*
X1688451Y249716D03*
X1686113Y250604D03*
X1683615Y250493D03*
X1679100Y276400D03*
X1681116Y238614D03*
X1681632Y233665D03*
X1657498Y279900D03*
Y274700D03*
Y269700D03*
X1657567Y264600D03*
X1657500Y259700D03*
X1657498Y277300D03*
Y267100D03*
X1657949Y257240D03*
X1666968Y260611D03*
X1684300Y233579D03*
X1679100Y278924D03*
Y271300D03*
Y273900D03*
X1653091Y331618D03*
X1652991Y318741D03*
Y323941D03*
Y329059D03*
X1653091Y326500D03*
X1652991Y321341D03*
X1657498Y284900D03*
X1679100Y292000D03*
Y284093D03*
Y294500D03*
Y286593D03*
Y289500D03*
X1657494Y292816D03*
X1679100Y281593D03*
X1657500Y287800D03*
X1657600Y304500D03*
X1679100Y302100D03*
Y304700D03*
Y299500D03*
Y297000D03*
X1664453Y308557D03*
X1654770Y399145D03*
X1652186Y365600D03*
Y360600D03*
X1654809Y401645D03*
X1652186Y354700D03*
Y352100D03*
X1654861Y396637D03*
X1660972Y401447D03*
X1661243Y390364D03*
Y392943D03*
X1660890Y397300D03*
X1660934Y387883D03*
X1664829Y379194D03*
X1664905Y376695D03*
X1667809Y427809D03*
X1667729Y424621D03*
X1668100Y418700D03*
X1678303Y442765D03*
X1667946Y412987D03*
X1681215Y451786D03*
X1673550Y442696D03*
X1684435Y456832D03*
Y459421D03*
X1661470Y456251D03*
X1661522Y453751D03*
X1669076Y438281D03*
X1664762Y438035D03*
X1676304Y449794D03*
X1676287Y447244D03*
X1667588Y434149D03*
X1667649Y430849D03*
X1667462Y440735D03*
X1669962D03*
X1668843Y465060D03*
X1675744Y456200D03*
X1664762Y443735D03*
X1669816Y443953D03*
Y446453D03*
X1673064Y446022D03*
X1679145Y461950D03*
X1673068Y448522D03*
X1669816Y448953D03*
X1661549Y451251D03*
X1681192Y454286D03*
X1668000Y416200D03*
X1673074Y453185D03*
X1675120Y439731D03*
X1681154Y449286D03*
X1655790Y476593D03*
X1651867Y484741D03*
X1651926Y482197D03*
X1671050Y490850D03*
X1687500Y505200D03*
X1672313Y497300D03*
X1687741Y466988D03*
X1705767Y482434D03*
X1698354Y486873D03*
X1687443Y487203D03*
X1681500Y482000D03*
X1699861Y520192D03*
X1697261D03*
X1695658Y486945D03*
X1694410Y499830D03*
X1692120Y501410D03*
X1699900Y512300D03*
X1692443Y487259D03*
X1710594Y519900D03*
X1667674Y467271D03*
X1681650Y510673D03*
X1687606Y500938D03*
X1672265Y473600D03*
X1678001Y473205D03*
X1665047Y467257D03*
X1689943Y487203D03*
X1671050Y483600D03*
Y481000D03*
X1680500Y473325D03*
X1687500Y484000D03*
X1690091Y503995D03*
X1672606Y499820D03*
X1671050Y487000D03*
X1681115Y525218D03*
X1709400Y513000D03*
X1652500Y575600D03*
X1653960Y562930D03*
X1667277Y535221D03*
X1698600Y584800D03*
X1680133Y535489D03*
X1699600Y578100D03*
X1710389Y577787D03*
X1664113Y548380D03*
X1658466D03*
X1661880Y583900D03*
X1686036Y548251D03*
X1677300Y550200D03*
X1680007Y547917D03*
X1669121Y547923D03*
X1708140Y547538D03*
X1697839Y545759D03*
X1709183Y588700D03*
X1700348Y546633D03*
X1680000Y550544D03*
X1658754Y551000D03*
X1669600Y550544D03*
X1685000D03*
X1663754Y551000D03*
X1674600Y550544D03*
X1652669Y582350D03*
Y578350D03*
X1705348Y546633D03*
X1654100Y615790D03*
X1653970Y607340D03*
X1652700Y591300D03*
Y600850D03*
X1662580Y593200D03*
X1661200Y601300D03*
Y607300D03*
X1709950Y592900D03*
X1710000Y595500D03*
Y604500D03*
Y600000D03*
X1701291Y602268D03*
X1699106Y618018D03*
X1658369Y606250D03*
X1652499Y593950D03*
X1660680Y590750D03*
X1714297Y11180D03*
X1756895Y30452D03*
X1723678Y11381D03*
X1756992Y20007D03*
X1763360Y24010D03*
X1730550Y21160D03*
X1721559Y13500D03*
X1730768Y13313D03*
X1763100Y21500D03*
X1768807Y21512D03*
X1753903Y22116D03*
X1749941Y21163D03*
X1741000Y21200D03*
X1741544Y9151D03*
X1752908Y9481D03*
X1744900Y9100D03*
X1755500Y9076D03*
X1759093Y9310D03*
X1761872Y-7220D03*
X1734875Y9238D03*
X1760693Y20045D03*
X1767069Y24010D03*
X1743152Y23197D03*
X1733168Y22312D03*
X1748152Y23197D03*
X1738168Y22312D03*
X1728678Y11381D03*
X1719297Y11180D03*
X1731350Y92140D03*
X1715259Y35602D03*
X1715100Y46100D03*
X1713550Y56000D03*
X1716900Y87900D03*
X1713900D03*
X1750250Y35925D03*
X1753059Y35300D03*
X1750400Y47400D03*
X1745094Y47106D03*
X1732650Y60650D03*
X1735150D03*
Y58150D03*
X1732650D03*
X1757772Y90174D03*
X1757395Y84794D03*
X1760364Y85136D03*
X1720500Y52440D03*
X1748500Y79500D03*
X1757998Y73637D03*
X1775000Y53500D03*
X1720100Y46100D03*
X1742594Y47106D03*
X1748854Y58533D03*
X1746328Y59011D03*
X1717600Y46100D03*
X1755400Y37700D03*
X1736700Y39600D03*
X1727383Y39465D03*
X1717958Y39880D03*
X1752000Y38865D03*
X1724758Y38600D03*
X1720600Y70200D03*
X1733910Y38233D03*
X1757054Y66059D03*
X1758100Y37000D03*
X1749364Y38971D03*
X1743500Y39300D03*
X1768450Y77376D03*
X1765900Y83700D03*
X1754703Y84053D03*
X1771459Y52695D03*
X1733900Y92200D03*
X1725474Y69250D03*
X1766240Y70500D03*
X1760016Y65774D03*
X1771707Y86500D03*
X1746552Y38900D03*
X1767250Y94500D03*
Y89500D03*
X1766333Y59116D03*
X1769250Y70350D03*
X1756895Y34252D03*
X1746550Y35925D03*
X1740598Y39486D03*
X1731183Y39465D03*
X1721758Y39880D03*
X1746491Y95650D03*
X1754600Y109200D03*
X1748425Y119190D03*
X1765015Y119100D03*
X1758100D03*
X1761300D03*
X1767250Y99500D03*
Y104500D03*
X1770850Y109500D03*
X1768886Y156173D03*
X1719250Y179150D03*
X1713596Y175795D03*
X1714189Y159550D03*
X1714528Y190189D03*
X1758650Y158650D03*
X1750189Y159550D03*
X1745689D03*
X1741189D03*
X1727689D03*
X1723189D03*
X1718689D03*
X1732189D03*
X1736689D03*
X1745777Y179574D03*
X1751975Y179374D03*
X1739377D03*
X1733178Y179574D03*
X1758375D03*
X1764673Y179374D03*
X1770973Y179574D03*
X1726700Y179400D03*
X1719000Y190500D03*
X1730400Y195850D03*
X1740900Y198800D03*
X1744000D03*
X1769100Y209700D03*
X1765950Y209600D03*
X1769016Y198872D03*
X1765866Y198772D03*
X1731260Y209600D03*
X1740709D03*
X1756000Y210000D03*
X1753400Y209900D03*
X1743900Y209700D03*
X1728616Y198872D03*
X1753311Y198700D03*
X1756600Y198800D03*
X1731216Y198872D03*
X1719100Y176000D03*
X1749295Y176104D03*
X1723189Y176012D03*
X1733484Y211631D03*
X1746125D03*
X1758725D03*
X1771325D03*
X1738484D03*
X1751125D03*
X1763725D03*
X1727193Y176525D03*
X1744792D03*
X1757390D03*
X1769988D03*
X1732193D03*
X1739792D03*
X1752390D03*
X1764988D03*
X1733563Y196776D03*
X1746082Y196843D03*
X1758668D03*
X1771241Y196841D03*
X1738563Y196776D03*
X1751082Y196843D03*
X1763668D03*
X1763554Y237712D03*
X1762795Y232106D03*
X1772244D03*
X1752554Y237712D03*
X1771451D03*
X1733880Y232810D03*
X1715837Y246178D03*
X1727896Y246175D03*
X1720651Y246141D03*
X1718820Y249032D03*
X1715078Y250231D03*
X1724181Y246159D03*
X1724944Y250324D03*
X1727444D03*
X1771243Y250100D03*
X1729944Y250324D03*
X1768516Y249983D03*
X1768700Y233644D03*
X1739847Y233334D03*
X1736847D03*
X1719080Y232852D03*
X1744603Y232489D03*
X1753347Y232106D03*
X1763300Y250100D03*
X1733900Y237300D03*
X1736400D03*
X1719080Y236152D03*
X1774451Y237712D03*
X1755554D03*
X1760554D03*
X1742398Y234681D03*
X1716037Y444550D03*
X1724590Y444521D03*
X1737150Y450850D03*
X1766100Y447900D03*
X1762992Y447938D03*
X1740963Y448476D03*
X1753543Y448100D03*
X1750393Y448037D03*
X1737795Y448100D03*
X1727620Y444380D03*
X1721990Y444521D03*
X1730996Y442804D03*
X1719317Y441947D03*
X1724369Y441601D03*
X1718587Y444550D03*
X1760767Y450408D03*
X1748169D03*
X1773366D03*
X1755767D03*
X1743169D03*
X1768366D03*
X1714530Y519900D03*
X1716490Y506970D03*
X1722000Y513000D03*
X1742900Y485000D03*
X1734000Y488100D03*
X1755000Y485000D03*
X1748600D03*
X1749396Y493969D03*
X1751868Y494045D03*
X1770325Y490255D03*
X1773500Y472100D03*
X1767300Y472700D03*
X1765325Y490255D03*
X1758500Y493800D03*
X1760900Y472800D03*
X1772459Y467005D03*
X1769309D03*
X1759860D03*
X1756710D03*
X1747262D03*
X1744112D03*
X1734663D03*
X1729200Y519000D03*
X1733830Y502650D03*
X1768900Y521124D03*
X1749090Y513790D03*
X1740400Y496300D03*
X1726600Y519000D03*
X1728700Y502600D03*
X1737300Y500900D03*
X1738180Y503487D03*
X1719089Y472104D03*
X1728700Y470200D03*
X1774200Y512800D03*
X1766100Y521124D03*
X1722347Y471811D03*
X1750800Y516100D03*
X1762715Y521085D03*
X1748125Y496400D03*
X1733639Y500085D03*
X1758575Y496406D03*
X1743125Y496400D03*
X1728639Y500085D03*
X1753575Y496406D03*
X1713600Y513000D03*
X1770325Y487355D03*
X1765325D03*
X1754300Y487855D03*
X1741900Y487755D03*
X1766700Y475655D03*
X1749300Y487855D03*
X1736900Y487755D03*
X1774300Y475055D03*
X1761700Y475655D03*
X1725694Y568814D03*
Y571814D03*
X1767500Y559800D03*
X1738697Y557888D03*
X1738434Y588986D03*
X1736003Y588244D03*
X1772578Y575993D03*
X1756417Y563840D03*
X1754000Y553500D03*
X1746000Y574000D03*
X1724250Y588250D03*
X1756500Y554500D03*
X1743500Y564500D03*
X1759500Y554500D03*
X1718000Y587723D03*
X1756578Y586743D03*
X1767141Y555500D03*
X1730759Y548162D03*
X1733000Y557000D03*
X1722500Y562000D03*
X1742200Y552863D03*
X1749000D03*
X1762595Y576191D03*
X1769000Y576378D03*
X1754897Y578750D03*
X1742381Y585530D03*
X1730814Y568814D03*
X1733000Y560000D03*
X1764300Y570900D03*
X1767455Y571695D03*
X1738216Y548239D03*
X1753807Y548183D03*
X1757478Y548192D03*
X1738498Y554255D03*
X1737958Y560500D03*
X1743200Y567300D03*
X1743100Y561700D03*
X1767000Y563500D03*
X1767529Y566200D03*
X1743000Y574500D03*
X1730774Y579960D03*
X1733368Y579868D03*
X1724899Y584748D03*
X1738088Y551000D03*
X1739500Y586500D03*
X1770719Y573964D03*
X1728245Y585244D03*
X1739179Y592070D03*
X1746052Y614796D03*
X1735000Y621002D03*
X1764912Y618718D03*
X1725133Y614896D03*
X1724092Y618700D03*
X1770600Y600800D03*
X1766400Y599400D03*
X1728341Y614851D03*
X1739211Y596711D03*
X1772158Y610960D03*
X1750399Y603201D03*
X1764823Y613600D03*
X1750739Y618718D03*
X1718008Y592002D03*
X1718037Y597184D03*
X1716950Y603450D03*
X1718037Y594684D03*
X1757319Y606953D03*
X1758550Y604350D03*
X1742509Y595869D03*
X1742381Y591530D03*
X1740270Y594419D03*
X1739714Y604967D03*
X1762062Y592055D03*
X1763500Y599100D03*
X1762062Y589555D03*
X1727843Y597142D03*
X1732443Y592342D03*
Y597142D03*
X1727743Y592342D03*
X1832449Y-8950D03*
X1835500Y-1700D03*
X1835600Y3900D03*
X1804800Y-1500D03*
X1825324Y1000D03*
X1824564Y3441D03*
X1785612Y10729D03*
X1782371Y26832D03*
X1804508Y11858D03*
X1798676Y11726D03*
X1830344Y13397D03*
X1828824Y3699D03*
X1816693Y13331D03*
X1829636Y26680D03*
X1831000Y-16300D03*
X1788421Y8122D03*
X1825870Y21587D03*
X1832900Y10300D03*
X1785366Y8100D03*
X1823300Y21700D03*
X1832842Y13500D03*
X1836700Y-18900D03*
X1819800Y2100D03*
X1813913Y2287D03*
X1816723Y9781D03*
X1808603Y9300D03*
X1823600Y8800D03*
X1809822Y26585D03*
X1807127Y26918D03*
X1795078Y11900D03*
X1790078Y11860D03*
X1804462Y8830D03*
X1799462D03*
X1808100Y21800D03*
X1819800Y35500D03*
X1790700Y34900D03*
X1799774Y34890D03*
X1826414Y35486D03*
X1827100Y81600D03*
X1798454Y82256D03*
X1788216Y59197D03*
X1815637Y54775D03*
X1818396Y54752D03*
X1779750Y36530D03*
X1784341Y64841D03*
X1820457Y39128D03*
X1789356Y38286D03*
X1796100Y68800D03*
X1829580Y38620D03*
X1824130Y39703D03*
X1826900Y40400D03*
X1808444Y37152D03*
X1800000Y80000D03*
X1827000Y87000D03*
X1834300Y41100D03*
X1824240Y83680D03*
X1802119Y56581D03*
X1786341Y63341D03*
X1799438Y44328D03*
X1817186Y39929D03*
X1827000Y94550D03*
X1788200Y93000D03*
Y89000D03*
Y85000D03*
X1808363Y40033D03*
X1803300Y39900D03*
X1776828Y155211D03*
X1818383Y133277D03*
X1815883D03*
X1777000Y115750D03*
X1787500Y155170D03*
X1813118Y127976D03*
X1807509Y128500D03*
X1778000Y120000D03*
X1780720Y153850D03*
X1807166Y147401D03*
X1783252Y109044D03*
X1788448Y98820D03*
X1788648Y101490D03*
X1807745Y104500D03*
X1803400Y114000D03*
X1796059Y104402D03*
X1801366Y151937D03*
X1811348Y143448D03*
X1800264Y143789D03*
X1828340Y149960D03*
X1803058Y143733D03*
X1815348Y143437D03*
X1796500Y120000D03*
X1827150Y97800D03*
X1830316Y102163D03*
X1828960Y153010D03*
X1824990Y103620D03*
X1787373Y120188D03*
X1824509Y143653D03*
X1821348Y143437D03*
X1815026Y121478D03*
X1808226Y136171D03*
X1803509Y128500D03*
X1800792Y122691D03*
X1821350Y98270D03*
X1810100Y114700D03*
X1812743Y104395D03*
X1810245Y104500D03*
X1814900Y116900D03*
X1816418Y127976D03*
X1800000Y132627D03*
X1788000Y129000D03*
X1784750Y124000D03*
X1808313Y111705D03*
X1800420Y148240D03*
X1820648Y155537D03*
X1816348D03*
X1833629Y170807D03*
X1777172Y179374D03*
X1778466Y198772D03*
X1783572Y179574D03*
X1802369Y179374D03*
X1808769Y179574D03*
X1815000Y179300D03*
X1789870Y179374D03*
X1796170Y179574D03*
X1795348Y172037D03*
X1797848D03*
X1792748Y171937D03*
X1821367Y179574D03*
X1827565Y179174D03*
X1833388Y179500D03*
X1821261Y170012D03*
X1824200Y176900D03*
X1787000Y175500D03*
X1834103Y176021D03*
X1778900Y165800D03*
X1785500Y164000D03*
Y168000D03*
X1834400Y216900D03*
X1830415Y196567D03*
X1791150Y209600D03*
X1794300Y209700D03*
X1794216Y198872D03*
X1791066Y198772D03*
X1819457Y198872D03*
X1828700Y198800D03*
X1820349Y209586D03*
X1828950Y209600D03*
X1832274Y209734D03*
X1816266Y198772D03*
X1804166Y198472D03*
X1807751Y209586D03*
X1803072Y209728D03*
X1806821Y198600D03*
X1815670Y209728D03*
X1781700Y209700D03*
X1778550Y209600D03*
X1781616Y198872D03*
X1816125Y169492D03*
X1816348Y163437D03*
X1818500Y159500D03*
X1820648Y163437D03*
X1776325Y211631D03*
X1777587Y176525D03*
X1783925Y211631D03*
X1796526Y212231D03*
X1809125D03*
X1821685Y212161D03*
X1788925Y211631D03*
X1801526Y212231D03*
X1814125D03*
X1826685Y212161D03*
X1790185Y176525D03*
X1802784D03*
X1815382D03*
X1782587D03*
X1795185D03*
X1807784D03*
X1820382D03*
X1783841Y196841D03*
X1776241D03*
X1814041D03*
X1801441D03*
X1809041D03*
X1821682D03*
X1796441D03*
X1788841D03*
X1782452Y237712D03*
X1820281Y250498D03*
X1809281D03*
X1801384D03*
X1790383D03*
X1835936Y235604D03*
X1784440Y232938D03*
X1831700Y252272D03*
X1804388Y249904D03*
X1826662Y232191D03*
X1822638Y232106D03*
X1826287Y250000D03*
X1824300Y251800D03*
X1826085Y236034D03*
X1822877Y235852D03*
X1793600Y235100D03*
X1793700Y232500D03*
X1806083Y232584D03*
X1803280Y232611D03*
X1791141Y232106D03*
X1828936Y249900D03*
X1819488Y232106D03*
X1810040D03*
X1800591D03*
X1781693D03*
X1817282Y250498D03*
X1798384D03*
X1779451Y237712D03*
X1793384Y250498D03*
X1812282D03*
X1775590Y448100D03*
X1778740D03*
X1828600Y450100D03*
X1825984Y448030D03*
X1816535Y448300D03*
X1813385Y447945D03*
X1804000Y447900D03*
X1800787Y447943D03*
X1791338Y448400D03*
X1788189Y448300D03*
X1785964Y450408D03*
X1780964D03*
X1836495Y450600D03*
X1823760Y450408D03*
X1811161D03*
X1798563D03*
X1831495Y450600D03*
X1818760Y450408D03*
X1806161D03*
X1793563D03*
X1776695Y512640D03*
X1779700Y472100D03*
X1784525Y491830D03*
X1781907Y467005D03*
X1785057D03*
X1779303Y497246D03*
X1832301Y467005D03*
X1835550Y466870D03*
X1789774Y476403D03*
X1801500Y471055D03*
X1795164Y476406D03*
X1789525Y491830D03*
X1801125D03*
X1796125D03*
X1817325Y481320D03*
X1806600Y471055D03*
X1812325Y481320D03*
X1806975Y491630D03*
X1830220Y479950D03*
X1824960Y473980D03*
X1824125Y491830D03*
X1822852Y467005D03*
X1819702D03*
X1819125Y491830D03*
X1807104Y467005D03*
X1810254D03*
X1811975Y491630D03*
X1797655Y467005D03*
X1794505D03*
X1810508Y515900D03*
X1804000Y498176D03*
X1834540Y519600D03*
X1790250Y522350D03*
X1834100Y523900D03*
X1791113Y496670D03*
X1788045Y496654D03*
X1825700Y514900D03*
X1828100Y516300D03*
X1828000Y513200D03*
X1814852Y519901D03*
X1809700Y506875D03*
X1820400Y501100D03*
X1806076Y523525D03*
X1798883Y515636D03*
X1810200Y513300D03*
X1815200Y501500D03*
X1801600Y515600D03*
X1794100Y521900D03*
X1803900Y491500D03*
X1796153Y514200D03*
X1783400Y522500D03*
X1780838Y522562D03*
X1836396Y481349D03*
X1789300Y520000D03*
X1836600Y521600D03*
X1828200Y519000D03*
X1833700Y497300D03*
X1786000Y522600D03*
X1796400Y498000D03*
X1804500Y526200D03*
X1795200Y525700D03*
X1816800D03*
X1810350Y525650D03*
X1813500Y526500D03*
X1824125Y488930D03*
X1811975Y488730D03*
X1801125Y488930D03*
X1789525D03*
X1819125D03*
X1806975Y488730D03*
X1796125Y488930D03*
X1784525D03*
X1829967Y476927D03*
X1817375Y478320D03*
X1794975Y479300D03*
X1779300Y475055D03*
X1825297Y476927D03*
X1812375Y478320D03*
X1789975Y479300D03*
X1801525Y473955D03*
X1806525D03*
X1779400Y582500D03*
X1818509Y527893D03*
X1829000Y536315D03*
X1792170Y583900D03*
X1783700Y576400D03*
X1798250Y529200D03*
X1810863Y560637D03*
X1816175Y567669D03*
X1785050Y584550D03*
X1792100Y566900D03*
X1816100Y576200D03*
X1816330Y545260D03*
X1816052Y584101D03*
X1809309Y555713D03*
X1831500Y548000D03*
X1835000Y550300D03*
X1781510Y546362D03*
X1786500Y562200D03*
X1783700Y579200D03*
X1828800Y546500D03*
X1828700Y540252D03*
X1828900Y552300D03*
X1834000Y534900D03*
X1811704Y554341D03*
X1807600Y552047D03*
X1806200Y549200D03*
X1786900Y552500D03*
X1801200Y529800D03*
X1806200Y582900D03*
X1780500Y570718D03*
Y568000D03*
X1781000Y565000D03*
X1780394Y561076D03*
X1782300Y555900D03*
X1779500Y579500D03*
X1779000Y585500D03*
X1810387Y571435D03*
X1794000Y568800D03*
X1793320Y557968D03*
X1828700Y569474D03*
X1836281Y589122D03*
X1828800Y575600D03*
X1828875Y563674D03*
X1828824Y557663D03*
X1810385Y568821D03*
X1807958Y565690D03*
X1781300Y537800D03*
X1808057Y573125D03*
Y570125D03*
X1813456Y583500D03*
X1803752Y529301D03*
X1810052Y545103D03*
X1816584Y530542D03*
X1793900Y550100D03*
X1793660Y560570D03*
X1829300Y572900D03*
X1816280Y550400D03*
Y553500D03*
X1792805Y574675D03*
X1812952Y545501D03*
X1794000Y552800D03*
X1811100Y586800D03*
X1816458Y587480D03*
X1829176Y584287D03*
X1779000Y588500D03*
X1793452Y586701D03*
X1831600Y529000D03*
X1832500Y539500D03*
X1788300Y585100D03*
X1791349Y589122D03*
X1812452Y538501D03*
Y533601D03*
X1807852D03*
X1807752Y538501D03*
X1779000Y598900D03*
X1776500Y621200D03*
X1778400Y618900D03*
X1800352Y596101D03*
X1795000Y599600D03*
X1791323Y594030D03*
X1805000Y606500D03*
X1787500Y600500D03*
X1778675Y592224D03*
X1784200Y593924D03*
X1787500Y597791D03*
X1825014Y593695D03*
X1811500Y603500D03*
X1794500Y612500D03*
X1791500Y606500D03*
X1800378Y593527D03*
X1819654Y593803D03*
X1805500Y603100D03*
X1782700Y610900D03*
X1808152Y591601D03*
X1812852Y596401D03*
X1808252D03*
X1812852Y591601D03*
X1837900Y9700D03*
X1837800Y-3600D03*
X1838850Y13160D03*
X1883041Y15814D03*
X1882999Y7383D03*
X1845420Y13310D03*
X1893094Y-10142D03*
X1838100Y3900D03*
X1868286Y12848D03*
X1871163Y13186D03*
X1870600Y25000D03*
X1848322Y12723D03*
X1841289Y21631D03*
X1876792Y18461D03*
X1876881Y22181D03*
X1843426Y9528D03*
X1840400Y9700D03*
X1893081Y-20735D03*
X1893094Y-12642D03*
X1858600Y74300D03*
X1837500Y35700D03*
X1853467Y35000D03*
X1841060Y35540D03*
X1846527Y34435D03*
X1849027Y34426D03*
X1873956Y60299D03*
X1883200Y76600D03*
X1850600Y41348D03*
X1858198Y41108D03*
X1860786Y41200D03*
X1855400Y40800D03*
X1878800Y43207D03*
Y40200D03*
X1878997Y37546D03*
X1889218Y43530D03*
Y53530D03*
X1846800Y95400D03*
X1847000Y86500D03*
X1848000Y56500D03*
X1850500D03*
X1890803Y63189D03*
X1884500Y79300D03*
X1882000D03*
X1895330Y64390D03*
X1877270Y63473D03*
X1889218Y56030D03*
Y61030D03*
Y46030D03*
Y51030D03*
X1880230Y76820D03*
X1879500Y79300D03*
X1880986Y53299D03*
X1868670Y42765D03*
X1878000Y73950D03*
X1848208Y49427D03*
X1896970Y73460D03*
X1867619Y39779D03*
X1895354Y75650D03*
X1842250Y84000D03*
X1849426Y90700D03*
Y95500D03*
X1893961Y73365D03*
X1860995Y84509D03*
X1856873Y91200D03*
X1856778Y87397D03*
X1864208Y87724D03*
X1864195Y84509D03*
X1864153Y91241D03*
X1860815Y91184D03*
X1842250Y90750D03*
X1877103Y60791D03*
X1875100Y51300D03*
X1854250Y138600D03*
X1854115Y131121D03*
X1864904Y114735D03*
X1872254Y138618D03*
X1839667Y151994D03*
X1837090Y149830D03*
X1848100Y134750D03*
X1839941Y156858D03*
X1845469Y135500D03*
X1872340Y147236D03*
X1895800Y149200D03*
X1885400Y147000D03*
X1878550Y99470D03*
X1882550D03*
X1894834Y139286D03*
X1863908Y140992D03*
X1878950Y137400D03*
X1871855Y104188D03*
X1856700Y110167D03*
X1843107Y97988D03*
X1857110Y113600D03*
X1890974Y105600D03*
X1898102Y107325D03*
X1897536Y120510D03*
Y114600D03*
X1874258Y103196D03*
X1885700Y141200D03*
X1862400Y124500D03*
X1851341Y106358D03*
X1857020Y129619D03*
Y126619D03*
X1861015Y130815D03*
X1867280Y135406D03*
X1878096Y152843D03*
X1871521Y153593D03*
X1881324Y153250D03*
X1869000Y153900D03*
X1875425Y152925D03*
X1875600Y156300D03*
X1886050Y151431D03*
X1886299Y153928D03*
X1895673Y151800D03*
X1865577Y124450D03*
X1878753Y139893D03*
X1866606Y109967D03*
X1860969Y136369D03*
Y133769D03*
X1872400Y144619D03*
X1857919Y156123D03*
X1895060Y136099D03*
X1848590Y141360D03*
X1857250Y138600D03*
X1853317Y108197D03*
X1887830Y102227D03*
X1852600Y97500D03*
X1857849Y148079D03*
X1854962Y133613D03*
X1887300Y121500D03*
X1850700Y156000D03*
X1875700Y115700D03*
Y121500D03*
X1881500Y115700D03*
Y121500D03*
Y127300D03*
X1887300D03*
X1875700D03*
X1887300Y115700D03*
X1846663Y153748D03*
X1864637Y201861D03*
X1868843Y207920D03*
X1839873Y159358D03*
X1854942Y181655D03*
X1836932Y170486D03*
X1854900Y175900D03*
X1877517Y217988D03*
X1839500Y212700D03*
X1876700Y207600D03*
X1875700Y184800D03*
X1895614Y204785D03*
X1895100Y201770D03*
X1883539Y199813D03*
X1883350Y202410D03*
X1858470Y206335D03*
X1855670Y206430D03*
X1897450Y213951D03*
Y216551D03*
X1882452Y195888D03*
X1877880Y203780D03*
X1863650Y189750D03*
X1893238Y208042D03*
X1857044Y186292D03*
X1863750Y163750D03*
X1868375Y171900D03*
X1846163Y168448D03*
X1886400Y172600D03*
Y170000D03*
X1886200Y161000D03*
X1883930Y176137D03*
X1883800Y179100D03*
X1857400Y175900D03*
X1862000Y177500D03*
X1876832Y173919D03*
X1875066Y175782D03*
X1886800Y210600D03*
X1886952Y213125D03*
X1883800Y213436D03*
X1884340Y217866D03*
X1859604Y213206D03*
X1861497Y211481D03*
X1874236Y213800D03*
X1871708Y213442D03*
X1850876Y212946D03*
X1847699D03*
X1847000Y198600D03*
X1864464Y198466D03*
X1886093Y202184D03*
X1878789Y213663D03*
X1864000Y184900D03*
X1858500Y200100D03*
X1861243Y183100D03*
X1872100Y207900D03*
X1884400Y183700D03*
X1891880Y204370D03*
X1854663Y158248D03*
X1846663D03*
X1886400Y178700D03*
X1836900Y232700D03*
X1850723Y219250D03*
X1843449Y244425D03*
X1856874Y219443D03*
X1896529Y235080D03*
X1884651Y234975D03*
X1854374Y248790D03*
X1844444Y224035D03*
X1850220Y253500D03*
X1858420Y253700D03*
X1843600Y239000D03*
X1840300Y239300D03*
X1861605Y253925D03*
X1881900Y224100D03*
X1884400D03*
X1882200Y234400D03*
X1882345Y231837D03*
X1840149Y244425D03*
X1864305Y253825D03*
X1872323Y264167D03*
X1852300Y252000D03*
X1858400Y251200D03*
X1843700Y253400D03*
X1892274Y235080D03*
X1885000Y227500D03*
X1870815Y453022D03*
X1858633Y452803D03*
X1839400Y450440D03*
X1838768Y454120D03*
X1847185Y454368D03*
X1860158Y450322D03*
X1864300Y447900D03*
X1882677Y447930D03*
X1895275Y454422D03*
X1898425Y447930D03*
Y454422D03*
X1844630Y454321D03*
X1878100Y450200D03*
X1859059Y448076D03*
X1872860Y450550D03*
Y447950D03*
X1875900Y453600D03*
X1866050Y451100D03*
X1868015Y452987D03*
X1841630Y454321D03*
X1837300Y472276D03*
X1837200Y525700D03*
X1866688Y517128D03*
X1845330Y466870D03*
X1843000Y505000D03*
X1857480Y466800D03*
X1861300D03*
X1881285Y467049D03*
X1849795Y493379D03*
X1850290Y486610D03*
X1872908Y471338D03*
X1870138Y485732D03*
X1852340Y509140D03*
X1859530Y516430D03*
X1842400Y516800D03*
X1843100Y494100D03*
X1840500D03*
X1843100Y491500D03*
X1840500D03*
Y484650D03*
Y487250D03*
X1842450Y507520D03*
X1896700Y472600D03*
X1896800Y470200D03*
X1894100Y472600D03*
X1894200Y470200D03*
X1864339Y509560D03*
X1843750Y475724D03*
X1840750D03*
X1841900Y498800D03*
X1852719Y487575D03*
Y492575D03*
X1873632Y500904D03*
X1860280Y520200D03*
X1847000Y487500D03*
X1860000Y495500D03*
X1844490Y509230D03*
X1875973Y499838D03*
X1869914Y517225D03*
X1877518Y527560D03*
X1857450Y473654D03*
X1842764Y528136D03*
X1838000Y549700D03*
X1837475Y573835D03*
X1837534Y579322D03*
X1838224Y586650D03*
X1889800Y580200D03*
X1878000Y539000D03*
X1861080Y537090D03*
X1870100Y561150D03*
X1854508Y552708D03*
X1858528Y544528D03*
X1857108Y550108D03*
X1875850Y567200D03*
X1857108Y552708D03*
X1840690Y557190D03*
X1878500Y553500D03*
X1858500Y540000D03*
X1852250Y547900D03*
X1858681Y568087D03*
X1879862Y581862D03*
X1896899Y557790D03*
X1845407Y533178D03*
X1868110Y536000D03*
X1878736Y533040D03*
X1864580Y537060D03*
X1852400Y554900D03*
X1869800Y557100D03*
X1878875Y565475D03*
X1897300Y548800D03*
X1855750Y548000D03*
X1882300Y565550D03*
X1885100Y584300D03*
X1873510Y541710D03*
X1840700Y563800D03*
X1848800Y551400D03*
X1848900Y548200D03*
X1854530Y533132D03*
X1859708Y552708D03*
X1856573Y576534D03*
X1857812Y557245D03*
X1842500Y534500D03*
X1844100Y551000D03*
X1848900Y545500D03*
X1878450Y548650D03*
X1870250Y541950D03*
X1896500Y555300D03*
X1879800Y579000D03*
X1858000Y574000D03*
X1870892Y583245D03*
X1874825Y564125D03*
X1859167Y559350D03*
X1894299Y557790D03*
X1895523Y586365D03*
X1844018Y586482D03*
X1858000Y586250D03*
X1866800Y588000D03*
X1875600Y588500D03*
X1856040Y588704D03*
X1837000Y534900D03*
X1896358Y595255D03*
X1868200Y590939D03*
X1848900Y590750D03*
X1845000Y590800D03*
X1900256Y-14760D03*
Y-18911D03*
X1906438Y-15968D03*
X1916078Y-16368D03*
X1903160Y-19416D03*
X1918352Y89300D03*
X1923300Y94300D03*
X1909406Y76790D03*
X1907986Y82393D03*
X1907929Y84793D03*
X1907907Y87223D03*
X1918379Y84788D03*
X1956891Y92513D03*
X1952110Y95513D03*
X1954391Y92513D03*
X1951670Y90363D03*
Y92863D03*
X1951770Y87863D03*
X1954169Y84111D03*
X1954861Y95163D03*
X1949610Y95513D03*
X1949270Y87863D03*
X1949170Y92863D03*
Y90363D03*
X1946670Y87863D03*
X1946570Y92863D03*
Y90363D03*
X1946670Y85363D03*
X1949270D03*
X1951770D03*
X1957361Y95163D03*
X1918113Y93576D03*
X1926890Y73106D03*
X1920300Y68300D03*
X1917600Y66000D03*
X1948472Y80362D03*
X1905501Y79790D03*
X1902796Y79820D03*
X1927918Y126156D03*
X1900100Y145100D03*
X1918210Y96103D03*
X1921199Y140499D03*
X1929711Y155759D03*
X1904136Y140160D03*
X1937000Y150000D03*
X1946500Y104974D03*
X1950934Y143730D03*
X1936187Y144013D03*
X1951700Y141000D03*
X1940700Y136300D03*
X1904215Y142812D03*
X1927810Y123544D03*
X1937900Y153600D03*
X1921264Y153000D03*
X1943752Y137548D03*
X1947078Y139300D03*
X1919484Y149500D03*
X1911961Y153000D03*
X1905092Y150170D03*
X1927000Y152200D03*
X1906414Y118004D03*
X1906467Y115305D03*
X1919702Y125920D03*
X1919195Y134396D03*
X1926952Y156049D03*
X1952726Y102950D03*
X1914500Y113300D03*
X1944609Y149184D03*
X1944600Y151700D03*
X1932998Y119438D03*
X1923329Y99475D03*
X1947000Y142600D03*
X1905540Y153000D03*
X1919702Y128501D03*
X1926892Y121203D03*
X1923837Y118800D03*
X1937728Y99441D03*
X1949389Y152083D03*
X1934000Y147100D03*
X1925358Y140685D03*
X1929756Y131037D03*
X1906871Y106049D03*
X1911231Y137097D03*
X1908715Y104512D03*
X1912100Y142600D03*
X1915030Y147250D03*
X1911440Y128840D03*
X1952440Y98520D03*
X1942637Y100877D03*
X1914152Y115928D03*
X1950983Y147344D03*
X1928100Y136078D03*
X1934544Y127957D03*
X1933914Y96040D03*
X1946770Y98150D03*
X1918002Y98902D03*
X1934256Y99459D03*
X1913392Y149381D03*
X1934100Y193400D03*
X1927064Y207564D03*
X1938400Y178200D03*
X1932837Y186700D03*
X1918489Y212513D03*
X1903917Y201472D03*
X1935600Y198700D03*
X1950981Y191218D03*
X1939200Y194300D03*
X1930500Y209464D03*
X1943500Y209500D03*
X1925000Y192000D03*
X1904042Y204895D03*
X1931483Y199350D03*
X1901100Y194200D03*
X1921500Y193600D03*
X1917024D03*
X1917568Y201215D03*
X1910123Y217349D03*
X1957334Y201269D03*
X1939300Y204300D03*
X1953200Y195530D03*
X1937100Y206800D03*
X1908967Y201609D03*
X1909186Y211906D03*
X1944500Y183900D03*
X1903524Y208156D03*
X1905074Y198163D03*
X1943200Y214800D03*
X1928400Y212500D03*
X1926000Y212400D03*
X1933898Y216707D03*
X1945156Y160236D03*
X1950994Y173745D03*
X1939316Y173600D03*
X1931639Y178396D03*
X1939550Y165600D03*
X1940647Y161600D03*
X1928218Y175443D03*
X1928249Y178179D03*
X1930300Y170147D03*
X1944550Y176450D03*
X1950981Y168064D03*
X1903150Y217250D03*
X1944300Y190200D03*
X1952717Y198614D03*
X1944611Y193400D03*
X1956901Y215241D03*
X1935600Y176300D03*
X1943217Y217645D03*
X1956901Y218391D03*
X1900740Y178720D03*
X1900700Y172990D03*
Y167290D03*
X1906440Y178720D03*
X1906500Y173100D03*
X1906400Y167290D03*
X1912190Y178870D03*
X1912230Y167330D03*
Y173030D03*
X1909421Y208805D03*
X1918143Y219848D03*
X1925835Y233735D03*
X1926100Y231200D03*
X1944463Y228458D03*
X1910340Y220741D03*
X1902907Y231294D03*
X1903032Y228368D03*
X1944925Y226001D03*
X1946105Y230344D03*
X1902909Y223195D03*
X1943517Y223637D03*
X1943800Y241800D03*
X1943900Y238500D03*
X1934750Y242700D03*
Y240300D03*
X1925600Y242700D03*
X1899816Y235035D03*
X1943217Y221154D03*
X1903020Y225776D03*
X1929000Y445800D03*
X1910500Y435600D03*
X1927100Y436200D03*
X1930100D03*
X1914173Y448200D03*
X1917700Y435600D03*
X1920700D03*
X1914700D03*
X1917322Y447930D03*
X1920472D03*
X1942000Y440500D03*
X1904724Y447930D03*
X1901574Y454422D03*
X1935300Y450600D03*
X1939845Y445055D03*
X1904724Y454422D03*
X1901574Y447930D03*
X1907500Y435600D03*
X1911023Y448400D03*
X1907874Y454422D03*
Y448400D03*
X1937430Y464785D03*
X1957212Y479521D03*
X1957100Y502990D03*
X1955790Y499790D03*
X1947380Y482450D03*
X1928620Y482710D03*
X1919230Y483430D03*
X1899100Y472600D03*
X1899200Y470200D03*
X1945000Y474000D03*
X1909800Y510700D03*
X1915100Y480050D03*
X1905010Y479410D03*
X1939000Y479400D03*
X1952500Y508000D03*
X1959260Y506010D03*
X1938410Y490650D03*
X1947550Y485350D03*
X1956500Y507470D03*
X1910500Y472000D03*
Y475000D03*
X1904200Y472700D03*
X1901700Y472600D03*
X1904300Y470300D03*
X1901800Y470200D03*
X1938300Y486250D03*
X1957250Y512050D03*
X1937300Y508900D03*
X1919510Y475100D03*
Y479200D03*
X1939000Y476600D03*
X1956300Y515900D03*
X1908300Y514500D03*
X1942328Y508712D03*
X1912800Y510700D03*
X1956606Y526671D03*
X1919000Y487210D03*
X1929480Y472880D03*
X1959300Y518000D03*
X1914750Y544863D03*
X1915050Y547900D03*
X1907200Y551600D03*
X1951900Y534900D03*
X1900250Y533700D03*
X1898850Y545250D03*
X1899800Y548100D03*
X1926600Y559500D03*
X1923600Y565100D03*
X1923000Y568700D03*
X1959120Y547050D03*
X1958940Y538890D03*
X1911000Y556700D03*
X1939800Y543700D03*
X1922500Y546700D03*
X1934600Y561900D03*
X1922000Y543750D03*
X1956191Y548700D03*
X1958500Y535000D03*
X1907500Y545600D03*
X1905000Y533900D03*
X1906050Y569100D03*
X1923600Y554200D03*
X1955400Y530500D03*
X1923600Y572300D03*
X1908400Y556800D03*
X1915593Y576807D03*
X1953500Y551900D03*
X1943300Y535700D03*
X1921244Y533750D03*
X1900729Y569557D03*
X1913800Y555500D03*
X1937250Y578200D03*
X1934400Y569400D03*
X1937200Y545100D03*
X1937300Y541600D03*
X1934200Y573700D03*
Y577700D03*
X1939700Y540900D03*
X1935400Y583000D03*
X1940800Y537300D03*
X1945900Y549900D03*
X1932800Y564300D03*
X1935400Y550800D03*
X1936900Y568000D03*
X1937800Y549700D03*
X1923500Y579500D03*
X1939800Y546300D03*
X1948100Y538700D03*
X1923400Y583000D03*
X1923600Y575500D03*
X1921800Y586100D03*
X1918880Y586460D03*
X1932390Y590100D03*
X1936770Y607210D03*
X1938130Y601480D03*
X1938000Y597320D03*
X1937870Y594480D03*
X1923504Y592500D03*
X1911750Y592800D03*
X1927000Y614500D03*
X1914700Y594600D03*
X1930500Y618900D03*
Y616100D03*
X1906200Y607800D03*
X1916050Y604450D03*
X1924000Y611391D03*
X1922900Y604450D03*
X1919900Y604550D03*
X1959400Y601100D03*
X1934350Y609250D03*
X1968179Y77969D03*
X1965679D03*
Y75369D03*
X1968179D03*
X1965679Y82969D03*
Y80469D03*
X1968179D03*
X1966212Y72897D03*
X1970679Y75369D03*
Y80469D03*
Y77969D03*
X1962800Y143700D03*
X1971200Y152500D03*
X1965400Y149700D03*
X1973328Y147303D03*
X1963400Y141100D03*
X1967580Y104721D03*
X1973004Y143120D03*
X1964382Y147318D03*
X1962800Y149300D03*
X1966700Y152400D03*
X1961472Y165760D03*
X1963300Y191000D03*
X1967817Y201029D03*
X1965900Y184600D03*
X1965057Y176447D03*
X1966542Y179606D03*
X1965973Y166190D03*
X1972598Y165236D03*
X1963092Y167936D03*
X1970270Y474640D03*
X1968870Y481710D03*
X1970500Y502720D03*
X1963500Y521000D03*
X1967200Y521600D03*
X1964270Y511410D03*
X1968375Y509375D03*
X1964890Y534940D03*
X1961500Y561700D03*
Y582700D03*
X1972700Y552700D03*
X1963000Y573000D03*
X1963097Y551000D03*
X1972700Y576400D03*
Y549950D03*
X1972800Y536800D03*
Y565200D03*
X1962950Y566600D03*
X1961715Y555639D03*
X1962500Y578500D03*
X1961700Y616700D03*
Y619500D03*
X1965400D03*
X1973000Y597200D03*
X1961771Y591744D03*
X1963300Y612800D03*
G54D21*
G01X-17190Y471340D02*
Y467732D01*
X-17084Y467626D01*
G01X-17190Y474840D02*
X-15190D01*
X-14190Y473840D01*
G01X-17500Y574000D02*
X-17287Y574213D01*
X-9387D01*
X-9200Y574400D01*
G01X7600Y29800D02*
X9912D01*
X11539Y31427D01*
G01X41677Y-14390D02*
X41793Y-14274D01*
Y-10114D01*
X43077Y-8830D01*
X46777D01*
G01X38227Y-20485D02*
X37081D01*
X35677Y-19081D01*
Y-16430D01*
G01X2621Y32939D02*
X2982Y33300D01*
X7600D01*
G01X602Y30502D02*
Y30920D01*
X2621Y32939D01*
G01X42520Y-16896D02*
X41374D01*
X39415Y-14937D01*
Y-12568D01*
X35677Y-8830D01*
G01X8500Y62800D02*
X11858D01*
X11864Y62794D01*
G01X17276Y59655D02*
Y56862D01*
X16625Y56211D01*
G01D02*
X16770Y56066D01*
Y53240D01*
G01X11300D02*
Y53486D01*
X14025Y56211D01*
G01X-1470Y63910D02*
X-360Y62800D01*
X5000D01*
G01X44310Y268160D02*
X43620D01*
X43360Y267900D01*
X41000D01*
G01X37000D02*
X33490D01*
G01X1500Y295000D02*
Y303095D01*
X11299Y312894D01*
Y343617D01*
X13838Y346156D01*
X40083D01*
X47622Y338617D01*
X51126D01*
X52809Y340300D01*
X54400D01*
G01X64500Y359250D02*
X54900D01*
X52450Y356800D01*
X48217D01*
X45450Y354033D01*
Y348600D01*
G01D02*
Y344400D01*
X49200Y340650D01*
G01X-13690Y464140D02*
Y466140D01*
X-12190Y467640D01*
G01X-13690Y464140D02*
X-8690D01*
G01D02*
X-6800D01*
X-6100Y464840D01*
G01X11100Y446200D02*
X13438Y448538D01*
X15650D01*
X17300Y450188D01*
Y450210D01*
G01X37568Y480095D02*
Y482836D01*
G01X-12190Y471140D02*
X-14690D01*
G01X28700Y478096D02*
X25634D01*
X24591Y479139D01*
G01X40200Y495721D02*
Y499732D01*
X40132Y499800D01*
G01X44050Y507100D02*
Y504383D01*
G01X37000Y515600D02*
X40156D01*
X42404Y513352D01*
Y508746D01*
X44050Y507100D01*
G01X17000Y475500D02*
X19596Y478096D01*
X20600D01*
G01X28700Y480064D02*
X34037D01*
X34068Y480095D01*
G01X28700Y484000D02*
X29782D01*
X30568Y484786D01*
X32854D01*
X34300Y483340D01*
Y482890D01*
G01D02*
X34160Y482750D01*
Y480187D01*
X34068Y480095D01*
G01X-6650Y487800D02*
Y493850D01*
X-9900Y497100D01*
Y502800D01*
G01Y506300D02*
Y502800D01*
G01X-5690Y470340D02*
X-8690D01*
G01X-5690Y467840D02*
Y470340D01*
G01X40200Y487879D02*
Y486191D01*
X42007Y484384D01*
X48184D01*
X50100Y486300D01*
Y487566D01*
X51200Y488666D01*
Y490750D01*
G01D02*
X53727Y493277D01*
Y498373D01*
X50596Y501504D01*
Y508212D01*
X48756Y510052D01*
X45441D01*
X44536Y510957D01*
Y514519D01*
X45617Y515600D01*
X48000D01*
G01X14500Y475500D02*
Y478300D01*
X16000Y479800D01*
X17300D01*
X17564Y480064D01*
X20600D01*
G01Y482032D02*
X13995D01*
X12217Y480254D01*
G01D02*
X11972Y480009D01*
Y475417D01*
G01X37618Y502853D02*
X37458D01*
X36458Y501853D01*
Y495721D01*
G01X37618Y502853D02*
X41547D01*
X42992Y501408D01*
X45719D01*
X47550Y503239D01*
Y504367D01*
G01X-1750Y574100D02*
X1422D01*
X1439Y574083D01*
G01Y538083D02*
X-1783D01*
X-2600Y538900D01*
G01X-9500Y539400D02*
X-7683D01*
X-4683Y542400D01*
X-2600D01*
G01X-9200Y574400D02*
X-8900Y574100D01*
X-5250D01*
G01X-14971Y540000D02*
X-14371Y539400D01*
X-9500D01*
G01X54808Y-14873D02*
X54675Y-14740D01*
X52967D01*
X52485Y-14258D01*
X52389D01*
G01X54808Y-14773D02*
Y-14873D01*
G01D02*
Y-17864D01*
G01X50586Y-20687D02*
X50473Y-20800D01*
X47900D01*
X46777Y-19677D01*
Y-16430D01*
G01X103600Y69778D02*
Y72300D01*
X102100Y73800D01*
G01X105700Y122000D02*
Y127041D01*
X106700Y128041D01*
X107254D01*
G01X97500Y118500D02*
X98000D01*
X101500Y122000D01*
X102400D01*
G01X75000Y176500D02*
X76000D01*
X77650Y178150D01*
G01X75000Y176500D02*
X71500D01*
G01X61402Y177773D02*
X62382D01*
X64609Y180000D01*
X71500D01*
G01X76143Y183019D02*
Y182023D01*
X75000Y180880D01*
Y180000D01*
G01D02*
X71500D01*
G01X72936Y202300D02*
X82779D01*
G01X78100Y189400D02*
Y197136D01*
X72936Y202300D01*
G01X70500Y183000D02*
X71899D01*
X78100Y189201D01*
Y189400D01*
G01X67000Y183000D02*
X63366D01*
X61366Y181000D01*
X61356D01*
G01X61256Y186000D02*
X61756Y186500D01*
X67000D01*
G01X63093Y202300D02*
Y198307D01*
X68200Y193200D01*
Y191200D01*
G01X70500Y186500D02*
Y188900D01*
X68200Y191200D01*
G01X91600Y278700D02*
X91421Y278521D01*
X85521D01*
X85500Y278500D01*
G01X82050Y283951D02*
X80500Y282401D01*
Y278500D01*
G01X77103Y283900D02*
X75500Y282297D01*
Y279500D01*
G01X100431Y317500D02*
Y324529D01*
X99770Y325190D01*
Y325249D01*
G01X103500Y302100D02*
X102400D01*
X101000Y303500D01*
G01X68418Y325500D02*
Y323382D01*
X69500Y322300D01*
Y322000D01*
G01X68418Y325500D02*
X68300Y325618D01*
Y328500D01*
X67600Y329200D01*
X63800D01*
X63300Y329700D01*
Y332500D01*
G01X85300Y335750D02*
Y335600D01*
X84781Y335081D01*
Y332500D01*
G01X70700Y330349D02*
Y330300D01*
X73000Y328000D01*
G01Y324500D02*
Y328000D01*
G01X94500Y299000D02*
X94000Y298500D01*
Y296600D01*
X93400Y296000D01*
G01X94500Y299000D02*
X96500D01*
G01D02*
X97500Y300000D01*
Y303500D01*
G01X83989Y320948D02*
Y324531D01*
X84000Y324542D01*
G01X91000Y321000D02*
X87500D01*
G01X83989Y320948D02*
X85369D01*
X85421Y321000D01*
X87500D01*
G01X79410Y331636D02*
Y332434D01*
X77311Y334533D01*
X74433D01*
X73100Y333200D01*
Y331900D01*
G01X46900Y294600D02*
X48000D01*
X49200Y295800D01*
Y296400D01*
X50900Y298100D01*
X53400D01*
G01X84000Y324542D02*
X84781Y325323D01*
Y327900D01*
G01X53400Y298100D02*
Y298200D01*
X54900Y299700D01*
X56000D01*
G01Y296200D02*
X57600D01*
X58600Y297200D01*
G01X51498Y295470D02*
X53735D01*
X54465Y296200D01*
X56000D01*
G01X58600Y297200D02*
X60290D01*
X60810Y296680D01*
X62120D01*
G01X62020Y300680D02*
X59580D01*
X58700Y299800D01*
G01X62020Y300680D02*
Y304609D01*
X62807Y305396D01*
G01X95500Y338200D02*
Y336350D01*
X94360Y335210D01*
G01X64600Y343150D02*
Y342050D01*
X65800Y340850D01*
Y338900D01*
G01X104600Y316602D02*
Y324900D01*
X102000Y327500D01*
X95500D01*
G01X106600Y303500D02*
X104900D01*
X103700Y304700D01*
X103500D01*
G01D02*
Y305300D01*
X101800Y307000D01*
X101000D01*
G01X100431Y312900D02*
Y307569D01*
X101000Y307000D01*
G01X98463Y312900D02*
X95300D01*
X94000Y311600D01*
Y310400D01*
G01Y307000D02*
X97500D01*
G01X94000Y310400D02*
Y307000D01*
G01X47100Y327000D02*
X49500Y324600D01*
Y320100D01*
X51550Y318050D01*
X56872D01*
G01X84866Y294213D02*
X86059Y293020D01*
X88870D01*
G01X89000Y299000D02*
X84300D01*
G01X94000Y303500D02*
Y303094D01*
X91984Y301078D01*
X91328D01*
X89250Y299000D01*
X89000D01*
G01X76500Y324500D02*
X76937D01*
X80489Y320948D01*
G01X76500Y324500D02*
Y323393D01*
X74887Y321780D01*
G01X80489Y320948D02*
X81500Y321959D01*
Y326587D01*
X82813Y327900D01*
G01X76600Y331900D02*
Y330532D01*
X76500Y330432D01*
Y328000D01*
G01D02*
X79173D01*
X82813Y331640D01*
Y332500D01*
G01X79600Y335200D02*
X81100Y333700D01*
X81613D01*
X82813Y332500D01*
G01X59452Y338800D02*
X59476Y338776D01*
Y337104D01*
X61080Y335500D01*
X64400D01*
X65859Y334041D01*
Y332500D01*
G01X80513Y338412D02*
X82150Y336775D01*
Y335800D01*
G01X53100Y315000D02*
X52400Y314300D01*
X48372D01*
G01X94850Y320650D02*
X92086Y323414D01*
Y324258D01*
G01X86750Y328000D02*
X91500D01*
X92000Y327500D01*
G01X65859Y325500D02*
Y323041D01*
X66900Y322000D01*
G01X92000Y327500D02*
Y324344D01*
X92086Y324258D01*
G01X91000Y313000D02*
Y317500D01*
G01X95000Y315300D02*
X95400D01*
X97600Y317500D01*
X98463D01*
G01X91000D02*
X92310D01*
X94510Y315300D01*
X95000D01*
G01X72750Y354750D02*
Y356450D01*
X70900Y358300D01*
G01X73500Y371300D02*
X74800Y372600D01*
X75000D01*
G01X64500Y355750D02*
X60400D01*
G01X68000D02*
X64500D01*
G01X69000Y345300D02*
X66350Y347950D01*
G01X72000Y345300D02*
X69000D01*
G01X66350Y347950D02*
X68500Y350100D01*
Y351500D01*
G01X68000Y359250D02*
Y360642D01*
X65750Y362892D01*
Y364500D01*
G01D02*
X65550Y364700D01*
X59302D01*
X58271Y363669D01*
G01D02*
X56502Y361900D01*
X56100D01*
G01X47550Y507100D02*
Y504367D01*
G01X109892Y531000D02*
X106392D01*
G01D02*
Y527413D01*
G01X105392Y568800D02*
Y566000D01*
G01X108892Y568800D02*
X105392D01*
G01X109392Y608500D02*
X105892D01*
G01D02*
X106192Y608200D01*
Y604600D01*
G01X133659Y22133D02*
Y19066D01*
X132692Y18099D01*
Y17800D01*
G01X170470Y22133D02*
Y19266D01*
X169492Y18288D01*
G01X133659Y97733D02*
Y94666D01*
X132692Y93699D01*
Y93400D01*
G01X133659Y59933D02*
Y56866D01*
X132692Y55899D01*
Y55600D01*
G01X169492Y56088D02*
X170470Y57066D01*
Y59933D01*
G01Y97733D02*
Y94866D01*
X169492Y93888D01*
G01Y90642D02*
X169770Y90364D01*
G01X112664Y128795D02*
X114208Y127251D01*
Y122310D01*
G01X109622Y128879D02*
X110385Y128116D01*
Y122633D01*
X110708Y122310D01*
G01X125624Y255633D02*
X124757Y256500D01*
X122000D01*
G01X125624Y223633D02*
X122733D01*
X122000Y222900D01*
G01X127500Y243500D02*
X125380Y241380D01*
X124980D01*
G01X127500Y275500D02*
X126460D01*
X125460Y274500D01*
Y273080D01*
G01X122000Y253000D02*
X119967D01*
X119958Y252991D01*
X118008D01*
G01D02*
X117183Y252166D01*
X114954D01*
X113399Y253721D01*
Y263301D01*
X116389Y266291D01*
Y271825D01*
X119710Y275146D01*
Y279710D01*
X122100Y282100D01*
Y284100D01*
G01X110740Y240361D02*
X112239Y241860D01*
X116776D01*
X119300Y244384D01*
Y247826D01*
X122000Y250526D01*
Y253000D01*
G01X110740Y240361D02*
X110692Y240313D01*
Y223844D01*
X114509Y220027D01*
X117044D01*
X118008Y220991D01*
G01D02*
X119599Y219400D01*
X122000D01*
G01X125624Y319633D02*
X124857Y320400D01*
X122100D01*
G01X125624Y287633D02*
X125591Y287600D01*
X122100D01*
G01X127500Y307500D02*
X125750D01*
X124750Y306500D01*
Y305430D01*
X124400Y305080D01*
G01X127000Y339000D02*
X126382D01*
X125062Y340320D01*
X122440D01*
X121620Y339500D01*
G01X118008Y348991D02*
X116612Y347595D01*
X115180D01*
X112860Y345275D01*
Y340450D01*
X109800Y337390D01*
Y331700D01*
X113200Y328300D01*
Y317150D01*
X114350Y316000D01*
X117017D01*
X118008Y316991D01*
G01X122100Y316900D02*
X118099D01*
X118008Y316991D01*
G01Y284991D02*
X118899Y284100D01*
X122100D01*
G01X118008Y284991D02*
X117017Y284000D01*
X114200D01*
X113200Y285000D01*
Y300282D01*
X119222Y306304D01*
Y311145D01*
X122100Y314023D01*
Y316900D01*
G01X125563Y346616D02*
X124747Y345800D01*
X121800D01*
G01X121862Y377600D02*
X124547D01*
X125563Y378616D01*
G01X175391Y400546D02*
X168843D01*
X164667Y404722D01*
Y407412D01*
G01X110452Y407092D02*
X114538D01*
X118630Y403000D01*
X129200D01*
X131200Y405000D01*
X142414D01*
X147274Y409860D01*
X150650D01*
G01X121800Y349300D02*
X118317D01*
X118008Y348991D01*
G01X118629Y381193D02*
X121507D01*
X121600Y381100D01*
X121862D01*
G01X172697Y407196D02*
X168905Y410988D01*
X167336D01*
X166792Y410444D01*
X164897D01*
G01X161397D02*
X157776D01*
G01D02*
X157678D01*
X154734Y407500D01*
X153392D01*
G01X161167Y407412D02*
X158572D01*
X155160Y404000D01*
X153392D01*
G01X170470Y523134D02*
Y520266D01*
X169492Y519288D01*
G01Y516042D02*
X169770Y515764D01*
G01X133659Y523134D02*
Y520066D01*
X132692Y519099D01*
Y518800D01*
G01X170470Y560934D02*
Y558066D01*
X169492Y557088D01*
G01Y553842D02*
X169770Y553564D01*
G01X133659Y560934D02*
Y557866D01*
X132692Y556899D01*
Y556600D01*
G01X170470Y598734D02*
Y595866D01*
X169492Y594888D01*
G01Y591642D02*
X169770Y591364D01*
G01X133659Y598734D02*
Y595666D01*
X132692Y594699D01*
Y594400D01*
G01X207281Y22133D02*
Y18990D01*
X206292Y18001D01*
Y17800D01*
G01X207281Y97733D02*
Y94590D01*
X206292Y93601D01*
Y93400D01*
G01Y55600D02*
Y55801D01*
X207281Y56790D01*
Y59933D01*
G01X252170Y337860D02*
X247800D01*
X240669Y344991D01*
Y357458D01*
X194078Y404049D01*
X180799D01*
G01X179574Y396363D02*
X175391Y400546D01*
G01X243705Y354394D02*
Y358665D01*
X195321Y407049D01*
X180629D01*
X177689Y404109D01*
G01X174609Y404009D02*
Y405959D01*
X178699Y410049D01*
X196564D01*
X243259Y363354D01*
G01X207281Y523134D02*
Y519990D01*
X206292Y519001D01*
Y518800D01*
G01X207281Y560934D02*
Y557790D01*
X206292Y556801D01*
Y556600D01*
G01X207281Y598734D02*
Y595590D01*
X206292Y594601D01*
Y594400D01*
G01X279903Y17700D02*
Y18100D01*
X280903Y19100D01*
Y22133D01*
G01X243092Y17700D02*
Y18100D01*
X244092Y19100D01*
Y22133D01*
G01Y59933D02*
Y56900D01*
X243092Y55900D01*
Y55500D01*
G01X279903D02*
Y55900D01*
X280903Y56900D01*
Y59933D01*
G01X279903Y93300D02*
Y93700D01*
X280903Y94700D01*
Y97733D01*
G01X243092Y93300D02*
Y93700D01*
X244092Y94700D01*
Y97733D01*
G01X271239Y269560D02*
X263960D01*
X253000Y258600D01*
G01X259820Y330210D02*
X252170Y337860D01*
G01X243705Y354394D02*
Y346365D01*
X248700Y341370D01*
X253540D01*
X260800Y334110D01*
G01X261519Y338010D02*
X254869Y344660D01*
X250071D01*
X246867Y347864D01*
Y359746D01*
X243259Y363354D01*
G01X249200Y349800D02*
Y348590D01*
X251180Y346610D01*
X260630D01*
X261780Y345460D01*
G01X280903Y523134D02*
Y520100D01*
X279903Y519100D01*
Y518700D01*
G01X244092Y523134D02*
Y520100D01*
X243092Y519100D01*
Y518700D01*
G01X280903Y560934D02*
Y557900D01*
X279903Y556900D01*
Y556500D01*
G01X244092Y560934D02*
Y557900D01*
X243092Y556900D01*
Y556500D01*
G01X280903Y598734D02*
Y595700D01*
X279903Y594700D01*
Y594300D01*
G01X244092Y598734D02*
Y595700D01*
X243092Y594700D01*
Y594300D01*
G01X313000Y253000D02*
X309409D01*
X308418Y252009D01*
G01X313000Y256500D02*
Y253000D01*
G01X312063Y345009D02*
Y341509D01*
G01Y345009D02*
X310501D01*
X309901Y345609D01*
X308418D01*
G01X323670Y494675D02*
X323700Y494645D01*
X329005D01*
X333470Y499110D01*
X347440D01*
X349402Y497148D01*
Y496030D01*
G01X304392Y497300D02*
X305222Y496470D01*
X306822D01*
X307692Y495600D01*
G01X319680Y491678D02*
X330350D01*
X334702Y496030D01*
G01X319300Y491630D02*
X318170Y492760D01*
Y494675D01*
G01X374401Y-11346D02*
X374592D01*
X375592Y-12346D01*
Y-13700D01*
G01X401375Y518157D02*
X401376Y518158D01*
G01X460912Y14814D02*
X460645Y15081D01*
G01Y17800D02*
Y18099D01*
X461612Y19066D01*
Y22133D01*
G01Y59933D02*
Y56866D01*
X460645Y55899D01*
Y55600D01*
G01Y52881D02*
X460912Y52614D01*
G01X461612Y97733D02*
Y94666D01*
X460645Y93699D01*
Y93400D01*
G01X450010Y115080D02*
X449978Y115112D01*
G01D02*
Y117880D01*
G01X435320Y115460D02*
X435278Y115502D01*
G01D02*
Y117880D01*
G01X461400Y274600D02*
Y283000D01*
G01X447148Y274841D02*
X446306D01*
G01D02*
X442434Y270969D01*
Y270091D01*
G01X461612Y560934D02*
Y557866D01*
X460645Y556899D01*
Y553781D01*
X460912Y553514D01*
G01X461612Y598734D02*
Y595666D01*
X460645Y594699D01*
Y591581D01*
X460912Y591314D01*
G01X535234Y22133D02*
Y19066D01*
X534267Y18099D01*
Y17800D01*
G01X497456D02*
Y18099D01*
X498423Y19066D01*
Y22133D01*
G01X535234Y59933D02*
Y56866D01*
X534267Y55899D01*
Y55600D01*
G01Y93400D02*
Y93699D01*
X535234Y94666D01*
Y97733D01*
G01X497456Y93400D02*
Y93699D01*
X498423Y94666D01*
Y97733D01*
G01X497456Y55600D02*
Y55899D01*
X498423Y56866D01*
Y59933D01*
G01X507472Y255647D02*
X507232D01*
X504832Y253247D01*
G01X507400Y260996D02*
Y259839D01*
X508707Y258532D01*
G01X535234Y523134D02*
Y520066D01*
X534267Y519099D01*
Y518800D01*
G01X498423Y523134D02*
Y520066D01*
X497456Y519099D01*
Y518800D01*
G01X535234Y560934D02*
Y557866D01*
X534267Y556899D01*
Y556600D01*
G01X498423Y560934D02*
Y557866D01*
X497456Y556899D01*
Y556600D01*
G01X535234Y598734D02*
Y595666D01*
X534267Y594699D01*
Y594400D01*
G01X498423Y598734D02*
Y595666D01*
X497456Y594699D01*
Y594400D01*
G01X571078Y17800D02*
Y18099D01*
X572045Y19066D01*
Y22133D01*
G01X564992Y14714D02*
X565006D01*
X565352Y15060D01*
Y22133D01*
G01Y52864D02*
Y59933D01*
G01X571078Y93400D02*
Y93699D01*
X572045Y94666D01*
Y97733D01*
G01X571078Y55600D02*
Y55899D01*
X572045Y56866D01*
Y59933D01*
G01X571078Y518800D02*
Y519099D01*
X572045Y520066D01*
Y523134D01*
G01Y560934D02*
Y557866D01*
X571078Y556899D01*
Y556600D01*
G01Y594400D02*
Y594699D01*
X572045Y595666D01*
Y598734D01*
G01X616500Y32000D02*
X616870D01*
X616892Y31978D01*
G01X655550Y14490D02*
X654310D01*
X651300Y17500D01*
G01X650050Y-14300D02*
X645670D01*
X644670Y-13300D01*
Y-8916D01*
X645200Y-8386D01*
Y-3427D01*
X647317Y-1310D01*
G01X661494Y32946D02*
X661800Y32640D01*
Y29000D01*
G01D02*
X663900D01*
X666400Y31500D01*
X692400D01*
X693900Y30000D01*
Y23350D01*
X693600Y23050D01*
G01X645430Y31067D02*
X649602Y35239D01*
X663839D01*
X668700Y40100D01*
Y63500D01*
X671400Y66200D01*
Y85200D01*
X672800Y86600D01*
Y91200D01*
X671234Y92766D01*
X668388D01*
G01X656600Y31500D02*
Y23100D01*
G01D02*
X656300Y22800D01*
G01X655550Y7490D02*
X652260D01*
X651100Y8650D01*
G01X668388Y92766D02*
Y94212D01*
X667800Y94800D01*
X663505D01*
X661471Y92766D01*
X659906D01*
G01X608856Y97733D02*
Y92599D01*
G01X612203Y97733D02*
Y92599D01*
G01X638488Y249513D02*
X634033D01*
X632692Y248172D01*
G01X643823Y283394D02*
X648194D01*
X648200Y283400D01*
X651288Y280312D01*
X655187D01*
X658576Y276923D01*
Y275577D01*
X666903Y267250D01*
X685891D01*
X687771Y269130D01*
X695223D01*
X697255Y267098D01*
G01X638500Y274000D02*
Y277000D01*
G01X643823Y283394D02*
Y279824D01*
X640999Y277000D01*
X638500D01*
G01X649500Y272000D02*
X649600D01*
X651200Y273600D01*
X652500D01*
G01X649500Y272000D02*
Y268500D01*
G01X646000Y265000D02*
X644200D01*
X643200Y264000D01*
X642800D01*
G01X646000Y265000D02*
X649300D01*
X649500Y264800D01*
G01X639000Y261100D02*
X642800D01*
G01X656000Y329800D02*
X653000Y332800D01*
Y333500D01*
G01X652100Y288300D02*
X653800Y290000D01*
X655500D01*
G01D02*
X656255D01*
X657884Y288371D01*
X658617D01*
G01X643823Y283394D02*
X639622D01*
G01X648900Y336600D02*
X649500Y336000D01*
Y333500D01*
G01X615300Y457900D02*
X618700Y461300D01*
X622280D01*
X626360Y465380D01*
Y472754D01*
X629256Y475650D01*
X634345D01*
X636812Y478117D01*
X646277D01*
X653091Y484931D01*
Y491691D01*
X656500Y495100D01*
Y499600D01*
X661200Y504300D01*
X664600D01*
X665559Y505259D01*
Y507500D01*
G01X618430Y488550D02*
X619750D01*
X622100Y486200D01*
Y481700D01*
X623400Y480400D01*
Y476300D01*
G01D02*
X620180D01*
X618430Y478050D01*
G01X615807Y470019D02*
Y469693D01*
X618890Y466610D01*
X619260D01*
G01X648500Y477400D02*
X648641D01*
X655641Y484400D01*
X661400D01*
X662000Y485000D01*
G01X669300Y504000D02*
X667300D01*
X663800Y500500D01*
X663000D01*
G01X673464Y507284D02*
Y508244D01*
X665858Y515850D01*
X651192D01*
X650050Y514708D01*
Y513092D01*
X651242Y511900D01*
X660300D01*
X661700Y510500D01*
X664200D01*
X665559Y509141D01*
Y507500D01*
G01X656170Y581690D02*
X654210D01*
X651750Y584150D01*
G01X656170Y574690D02*
X658173D01*
X660217Y576734D01*
G01X718230Y-10380D02*
Y-13086D01*
X716887Y-14429D01*
X716817D01*
Y-14448D01*
X716858D01*
G01X719437Y20952D02*
X720500Y22015D01*
Y24501D01*
X721999Y26000D01*
X727000D01*
X729500Y23500D01*
G01X724837Y13852D02*
X722937Y15752D01*
Y17452D01*
G01X680200Y13100D02*
X680700D01*
X682100Y14500D01*
X683950D01*
G01X710000Y21000D02*
X716094D01*
X717400Y19694D01*
Y19617D01*
X719437Y17580D01*
Y17452D01*
G01X719400Y14300D02*
X719437Y14337D01*
Y17452D01*
G01X710000Y21000D02*
Y19036D01*
X711486Y17550D01*
X714950D01*
G01X690515Y27586D02*
X687467D01*
X686042Y26161D01*
Y23941D01*
X683957Y21856D01*
X683050D01*
G01X684726Y18015D02*
Y18938D01*
X685750Y19962D01*
Y20068D01*
X687223Y21541D01*
Y22342D01*
X690515Y25634D01*
Y27586D01*
G01X684726Y18015D02*
X680327D01*
X679936Y18406D01*
G01X707893Y78798D02*
X711233D01*
G01X715130Y79574D02*
Y79660D01*
X714670D01*
X713808Y78798D01*
X711233D01*
G01X700419Y82850D02*
X699119D01*
X697200Y80931D01*
Y79500D01*
G01D02*
X697250Y79550D01*
X700419D01*
G01X680600Y42300D02*
X683105Y39795D01*
X684756D01*
X684904Y39943D01*
G01X689500Y37900D02*
X686000Y34400D01*
X682700D01*
G01D02*
X677632D01*
X675235Y36797D01*
G01X685000Y46650D02*
X683850Y47800D01*
X680600D01*
G01D02*
Y52800D01*
X679800Y53600D01*
G01X693000Y92500D02*
Y90990D01*
X691830Y89820D01*
G01X682204Y277776D02*
X678678D01*
X678454Y278000D01*
G01X713248Y276494D02*
X712254Y275500D01*
X709700D01*
G01X700800Y261300D02*
X699011Y263089D01*
Y263231D01*
X698950Y263292D01*
Y265964D01*
X699256Y266270D01*
Y267931D01*
X698185Y269002D01*
Y269285D01*
X694500Y272970D01*
Y275548D01*
X693083Y276965D01*
X690545D01*
X690130Y277380D01*
G01X700800Y261300D02*
X700098D01*
X694599Y255801D01*
G01X686500Y256000D02*
X688600D01*
X688799Y255801D01*
X694599D01*
G01X705511Y272561D02*
Y269086D01*
X705536Y269061D01*
G01D02*
Y263973D01*
X702863Y261300D01*
X700800D01*
G01X694599Y255801D02*
X697900Y252500D01*
X704500D01*
G01X666900Y329700D02*
X668500Y331300D01*
Y332500D01*
G01X673500Y291500D02*
Y289700D01*
X672150Y288350D01*
G01X673500Y291500D02*
X679740D01*
X679940Y291300D01*
X683000D01*
G01X712600Y303600D02*
Y306000D01*
X711600Y307000D01*
Y308748D01*
X713712Y310860D01*
X713970D01*
G01X674194Y358467D02*
X684433D01*
X687277Y361311D01*
X696500D01*
G01X717566Y358567D02*
X720600Y355533D01*
Y317490D01*
X713970Y310860D01*
G01X686600Y335600D02*
X684500Y333500D01*
Y333000D01*
G01Y321500D02*
X685335D01*
X687002Y319833D01*
X687400D01*
G01X687138Y317397D02*
X687035Y317500D01*
X684500D01*
G01X705900Y347800D02*
X713900D01*
G01X690500Y523300D02*
X687989Y520789D01*
X682083D01*
G01D02*
X680972Y521900D01*
X675500D01*
G01X722200Y571300D02*
X722500Y571600D01*
Y574000D01*
G01X716000Y577500D02*
X716950D01*
X718200Y578750D01*
Y581000D01*
G01X680029Y577503D02*
X681026Y578500D01*
X683600D01*
G01X722500Y583800D02*
Y580900D01*
G01Y583800D02*
X721391D01*
X720391Y582800D01*
Y579609D01*
X722500Y577500D01*
G01X682340Y584970D02*
Y583430D01*
X680910Y582000D01*
G01X682340Y584970D02*
X678944D01*
X677400Y583426D01*
Y581900D01*
G01X782567Y14814D02*
X782300Y15081D01*
Y18099D01*
X783267Y19066D01*
Y22133D01*
G01X756100Y36200D02*
X753208Y33308D01*
Y31978D01*
G01X783269Y97733D02*
X783267D01*
Y94666D01*
X782300Y93699D01*
Y93400D01*
G01X782567Y52614D02*
X782300Y52881D01*
Y55899D01*
X783267Y56866D01*
Y59933D01*
G01X775171Y218616D02*
X773484D01*
X772100Y220000D01*
G01X775171Y250616D02*
X773684D01*
X772300Y252000D01*
G01X771750Y242120D02*
X773100Y243470D01*
Y244300D01*
X775489Y246689D01*
X776532D01*
G01X776700Y275500D02*
X776000D01*
X775850Y275650D01*
X772600D01*
X771800Y274850D01*
G01X765007Y252363D02*
X765370Y252000D01*
X768800D01*
G01X761580Y220160D02*
X761740Y220000D01*
X768600D01*
G01X775171Y314616D02*
X773184D01*
X771900Y315900D01*
G01X775171Y282616D02*
X773384D01*
X771900Y284100D01*
G01X774460Y336700D02*
Y337311D01*
X777182Y340033D01*
G01X776270Y307100D02*
X776170Y307000D01*
X775350D01*
X773580Y305230D01*
G01X765007Y316363D02*
X765470Y315900D01*
X768400D01*
G01X765007Y284363D02*
X765270Y284100D01*
X768400D01*
G01X775121Y378616D02*
X773684D01*
X772100Y380200D01*
G01X775171Y346616D02*
X773984D01*
X772400Y348200D01*
G01X765007Y348363D02*
X765170Y348200D01*
X768900D01*
G01X768600Y380200D02*
X765120D01*
X764957Y380363D01*
G01X783269Y523134D02*
X783267Y523133D01*
Y520066D01*
X782300Y519099D01*
Y518800D01*
G01X756000Y525950D02*
Y531000D01*
G01X766535Y517900D02*
X766537Y517902D01*
Y523134D01*
G01X783269Y560934D02*
X783267Y560933D01*
Y557866D01*
X782300Y556899D01*
Y556600D01*
G01X756000Y531000D02*
X759500D01*
G01X755000Y568800D02*
Y566000D01*
G01X758500Y568800D02*
X755000D01*
G01X766537Y542824D02*
Y538547D01*
X765100Y537110D01*
G01X766535Y555700D02*
X766537Y555702D01*
Y560934D01*
G01X783269Y598734D02*
X783267Y598733D01*
Y595666D01*
X782300Y594699D01*
Y594400D01*
G01X759000Y608500D02*
X755500D01*
G01D02*
X755800Y608200D01*
Y604600D01*
G01X768917Y612000D02*
X766000D01*
G01X766535Y593500D02*
X766537Y593502D01*
Y598734D01*
G01X1001946Y621460D02*
X999356Y624050D01*
X728550D01*
X728000Y623500D01*
G01X820078Y22133D02*
Y19266D01*
X819100Y18288D01*
G01X820080Y97733D02*
X820078D01*
Y94866D01*
X819100Y93888D01*
G01Y90642D02*
X819378Y90364D01*
G01X820078Y59933D02*
Y57066D01*
X819100Y56088D01*
G01X844808Y382800D02*
X846619D01*
X847577Y381842D01*
G01X898100Y344800D02*
X897171Y343871D01*
X890763D01*
X883880Y350754D01*
Y361692D01*
X841147Y404425D01*
X836520D01*
X834002Y406943D01*
X822021D01*
X818078Y403000D01*
X813000D01*
X809501Y406499D01*
X806268D01*
X805367Y407400D01*
G01X882380Y355289D02*
Y361070D01*
X840525Y402925D01*
X835898D01*
X833380Y405443D01*
X822643D01*
X818700Y401500D01*
X812378D01*
X808879Y404999D01*
X806699D01*
X805600Y403900D01*
G01X797780Y423484D02*
X812516D01*
X819700Y416300D01*
X847012D01*
X895812Y367500D01*
G01X820080Y523134D02*
X820078Y523133D01*
Y520266D01*
X819100Y519288D01*
G01Y516042D02*
X819378Y515764D01*
G01X820080Y560934D02*
X820078Y560933D01*
Y558066D01*
X819100Y557088D01*
G01Y553842D02*
X819378Y553564D01*
G01X820080Y598734D02*
X820078Y598733D01*
Y595866D01*
X819100Y594888D01*
G01Y591642D02*
X819378Y591364D01*
G01X893702Y22133D02*
X893700D01*
G01X856889D02*
Y18990D01*
X855900Y18001D01*
Y17800D01*
G01X893700Y22133D02*
Y19100D01*
X892700Y18100D01*
Y17700D01*
G01X856891Y97733D02*
X856889D01*
Y94590D01*
X855900Y93601D01*
Y93400D01*
G01X856891Y59933D02*
X856889D01*
G01D02*
Y56790D01*
X855900Y55801D01*
Y55600D01*
G01X893700Y59933D02*
Y56900D01*
X892700Y55900D01*
Y55500D01*
G01X893700Y97733D02*
Y94700D01*
X892700Y93700D01*
Y93300D01*
G01X893702Y97733D02*
X893700D01*
G01X913787Y265660D02*
X910760D01*
X903050Y257950D01*
G01X899500Y262200D02*
X899450Y262150D01*
G01D02*
Y258050D01*
G01X901600Y344800D02*
X903575D01*
X904770Y343605D01*
Y342430D01*
X910600Y336600D01*
Y335800D01*
X912300Y334100D01*
G01X898100Y341000D02*
X896729Y342371D01*
X890141D01*
X882380Y350132D01*
Y355289D01*
G01X895812Y367500D02*
X896000D01*
G01X893702Y523134D02*
X893700Y523133D01*
Y520100D01*
X892700Y519100D01*
Y518700D01*
G01X856891Y523134D02*
X856889Y523133D01*
Y519990D01*
X855900Y519001D01*
Y518800D01*
G01X893702Y560934D02*
X893700Y560933D01*
Y557900D01*
X892700Y556900D01*
Y556500D01*
G01X856891Y560934D02*
X856889Y560933D01*
Y557790D01*
X855900Y556801D01*
Y556600D01*
G01X893702Y598734D02*
X893700Y598733D01*
Y595700D01*
X892700Y594700D01*
Y594300D01*
G01X856891Y598734D02*
X856889Y598733D01*
Y595590D01*
X855900Y594601D01*
Y594400D01*
G01X930513Y22133D02*
X930511D01*
G01D02*
Y19100D01*
X929511Y18100D01*
Y17700D01*
G01X930513Y59933D02*
X930511D01*
G01D02*
Y56900D01*
X929511Y55900D01*
Y55500D01*
G01X930511Y97733D02*
Y94700D01*
X929511Y93700D01*
Y93300D01*
G01X930513Y97733D02*
X930511D01*
G01X961139Y253100D02*
X959117D01*
X958026Y252009D01*
G01X961139Y256600D02*
Y253100D01*
G01X961630Y344340D02*
Y340840D01*
G01D02*
X960195D01*
X959326Y341709D01*
X958026D01*
G01X930513Y523134D02*
X930511Y523133D01*
Y520100D01*
X929511Y519100D01*
Y518700D01*
G01X930513Y560934D02*
X930511Y560933D01*
Y557900D01*
X929511Y556900D01*
Y556500D01*
G01X930513Y598734D02*
X930511Y598733D01*
Y595700D01*
X929511Y594700D01*
Y594300D01*
G01X1020650Y46900D02*
X1020868Y46682D01*
Y41823D01*
G01X1019800Y555800D02*
X1020868Y556868D01*
Y560934D01*
G01X1005470Y620380D02*
X1003026D01*
X1001946Y621460D01*
G01X1091141Y17059D02*
Y17042D01*
G01Y54842D02*
Y54859D01*
G01X1084700Y115500D02*
Y112700D01*
G01X1050983Y518157D02*
X1050984Y518158D01*
G01X1148033Y22133D02*
X1148031D01*
G01X1147064Y17800D02*
Y18099D01*
X1148031Y19066D01*
Y22133D01*
G01X1111222D02*
X1111220D01*
G01X1110520Y14814D02*
X1110253Y15081D01*
G01Y17800D02*
Y18099D01*
X1111220Y19066D01*
Y22133D01*
G01X1148033Y59933D02*
X1148031D01*
G01X1111222Y97733D02*
X1111220D01*
Y94666D01*
X1110253Y93699D01*
Y93400D01*
G01X1111220Y59933D02*
Y56866D01*
X1110253Y55899D01*
Y55600D01*
G01Y52881D02*
X1110520Y52614D01*
G01X1148031Y59933D02*
Y56866D01*
X1147064Y55899D01*
Y55600D01*
G01X1148031Y97733D02*
Y94666D01*
X1147064Y93699D01*
Y93400D01*
G01X1100100Y113500D02*
Y114800D01*
X1099400Y115500D01*
G01X1148033Y97733D02*
X1148031D01*
G01X1159410Y259720D02*
X1157238Y257548D01*
X1157013D01*
G01X1105256Y322341D02*
X1107959D01*
X1109000Y321300D01*
X1110300D01*
G01X1102300Y336700D02*
Y333400D01*
X1101100Y332200D01*
G01X1148033Y523134D02*
X1148031Y523133D01*
Y520066D01*
X1147064Y519099D01*
Y518800D01*
G01X1148033Y560934D02*
X1148031Y560933D01*
Y557866D01*
X1147064Y556899D01*
Y556600D01*
G01X1111222Y560934D02*
X1111220Y560933D01*
Y557866D01*
X1110253Y556899D01*
Y553781D01*
X1110520Y553514D01*
G01X1148033Y598734D02*
Y595668D01*
X1147064Y594699D01*
Y594400D01*
G01X1111222Y598734D02*
Y595668D01*
X1110253Y594699D01*
Y591581D01*
X1110520Y591314D01*
G01X1183875Y17800D02*
Y18099D01*
X1184842Y19066D01*
Y22133D01*
G01X1214962D02*
X1214960D01*
G01D02*
Y15060D01*
X1214614Y14714D01*
X1214600D01*
G01X1183875Y93400D02*
Y93699D01*
X1184842Y94666D01*
Y97733D01*
G01X1214962Y59933D02*
X1214960D01*
G01X1184842D02*
Y56866D01*
X1183875Y55899D01*
Y55600D01*
G01X1214960Y59933D02*
Y52864D01*
G01X1184844Y97733D02*
X1184842D01*
G01X1161900Y257726D02*
X1161404D01*
X1159410Y259720D01*
G01D02*
X1160833Y261143D01*
X1162022D01*
G01X1183875Y518800D02*
Y519099D01*
X1184842Y520066D01*
Y523133D01*
X1184844Y523134D01*
G01X1183875Y556600D02*
Y556899D01*
X1184842Y557866D01*
Y560933D01*
X1184844Y560934D01*
G01X1183875Y594400D02*
Y594699D01*
X1184842Y595666D01*
Y598733D01*
X1184844Y598734D01*
G01X1221655Y22133D02*
X1221653D01*
G01D02*
Y19066D01*
X1220686Y18099D01*
Y17800D01*
G01X1221655Y59933D02*
X1221653D01*
G01X1220686Y93400D02*
Y93699D01*
X1221653Y94666D01*
Y97731D01*
X1221655Y97733D01*
G01X1221653Y59933D02*
Y56866D01*
X1220686Y55899D01*
Y55600D01*
G01X1239213Y116188D02*
Y114575D01*
X1240550Y113238D01*
X1242502D01*
X1244331Y111409D01*
Y109188D01*
G01X1220580Y179810D02*
Y185773D01*
X1223554Y188747D01*
Y217276D01*
X1226384Y220106D01*
X1235557D01*
X1242291Y226840D01*
X1245755D01*
X1249756Y230841D01*
X1269709D01*
X1274074Y226476D01*
G01X1278183Y231886D02*
X1280425D01*
X1283065Y229246D01*
X1286036D01*
X1287265Y228017D01*
X1289679D01*
G01X1296679Y225458D02*
X1286995D01*
X1285977Y226476D01*
X1274074D01*
G01D02*
X1285598Y214952D01*
X1288024D01*
G01X1272830Y471660D02*
X1279153D01*
X1281600Y474107D01*
Y475860D01*
G01X1281350Y488700D02*
Y487700D01*
X1279930Y486280D01*
X1277580D01*
X1276000Y484700D01*
Y476860D01*
X1277000Y475860D01*
X1281600D01*
G01X1220686Y518800D02*
Y519099D01*
X1221653Y520066D01*
Y523133D01*
X1221655Y523134D01*
G01X1264700Y492143D02*
X1266650D01*
X1268381Y490412D01*
X1272419D01*
X1274131Y488700D01*
X1281350D01*
G01X1250400Y499500D02*
X1244700D01*
X1240640Y495440D01*
G01D02*
X1238200Y493000D01*
Y478750D01*
X1243250Y473700D01*
X1245200D01*
G01X1264700Y488643D02*
Y486490D01*
X1263600Y485390D01*
G01D02*
Y483540D01*
G01X1220686Y556600D02*
Y556899D01*
X1221653Y557866D01*
Y560933D01*
X1221655Y560934D01*
G01Y598734D02*
X1221653Y598733D01*
Y595666D01*
X1220686Y594699D01*
Y594400D01*
G01X1306320Y28900D02*
Y23683D01*
X1302637Y20000D01*
X1301500D01*
G01X1306320Y28900D02*
Y30970D01*
X1304940Y32350D01*
G01D02*
X1304390Y32900D01*
X1302200D01*
X1301200Y33900D01*
Y35900D01*
G01X1337500Y47000D02*
X1340500D01*
X1341400Y46100D01*
G01X1304500D02*
Y48271D01*
X1310629Y54400D01*
X1320554D01*
X1324127Y50827D01*
G01X1353500Y96959D02*
Y94051D01*
X1351449Y92000D01*
X1329000D01*
X1328500Y92500D01*
G01X1399100Y166900D02*
Y180928D01*
X1384066Y195962D01*
X1343739D01*
X1331824Y207877D01*
Y209051D01*
G01X1296679Y225458D02*
X1302863D01*
X1306397Y221924D01*
X1320988D01*
X1323030Y219882D01*
Y216531D01*
G01X1296679Y222899D02*
Y221321D01*
X1298000Y220000D01*
Y219000D01*
G01X1330800Y223950D02*
X1328150Y226600D01*
X1309530D01*
X1299675Y236455D01*
X1296089D01*
X1292044Y240500D01*
X1291000D01*
G01X1303250Y241500D02*
X1308191D01*
X1309462Y240229D01*
G01X1300444Y267919D02*
X1299540Y267015D01*
Y264840D01*
G01Y260840D02*
Y257151D01*
X1299589Y257102D01*
G01X1299540Y264840D02*
Y260840D01*
G01X1299589Y257102D02*
Y252677D01*
X1299572Y252660D01*
G01X1291000Y240500D02*
Y243500D01*
G01D02*
Y248000D01*
X1295660Y252660D01*
X1299572D01*
G01X1289679Y228017D02*
Y228621D01*
X1291170Y230112D01*
Y231199D01*
G01X1339800Y340300D02*
Y343300D01*
G01X1341500Y329100D02*
Y332700D01*
G01Y329100D02*
X1337430D01*
X1331720Y334810D01*
G01X1332650Y374450D02*
X1342388Y364712D01*
X1388369D01*
X1390459Y362622D01*
X1394718D01*
X1396052Y361288D01*
Y357720D01*
G01X1328500Y362300D02*
Y356679D01*
X1334494Y350685D01*
Y347856D01*
X1339050Y343300D01*
X1339800D01*
G01X1340969Y354526D02*
X1343969D01*
X1344253Y354242D01*
G01X1293000Y485500D02*
X1292250Y486250D01*
X1288760D01*
X1286050Y483540D01*
X1281600D01*
G01D02*
X1282600Y484540D01*
Y485050D01*
X1284850Y487300D01*
Y488700D01*
G01X1347081Y507919D02*
X1345362Y506200D01*
X1340000D01*
X1336550Y509650D01*
X1334250D01*
X1333700Y509100D01*
X1332500D01*
G01X1367189Y8476D02*
X1366789Y8076D01*
Y5776D01*
G01X1367400Y34700D02*
Y37500D01*
X1367100Y37800D01*
G01X1371500Y63200D02*
X1373300Y65000D01*
X1375500D01*
G01X1384671Y214832D02*
Y206730D01*
X1411844Y179557D01*
Y157922D01*
X1440604Y129162D01*
X1464886D01*
X1466924Y131200D01*
X1468590D01*
G01X1371000Y325400D02*
X1374500D01*
G01X1346550Y322350D02*
Y323800D01*
X1348250Y325500D01*
X1350000D01*
G01X1371000Y325400D02*
Y322400D01*
G01X1359200Y322200D02*
Y322600D01*
X1357000Y324800D01*
Y325500D01*
G01X1385580Y328782D02*
X1387222D01*
X1388450Y330010D01*
Y331250D01*
G01X1381800Y344500D02*
Y341500D01*
G01X1376400Y341938D02*
X1377962D01*
X1378900Y341000D01*
G01X1382800Y338400D02*
Y339700D01*
X1381800Y340700D01*
Y341500D01*
G01X1382800Y338400D02*
X1380800D01*
X1378900Y340300D01*
Y341000D01*
G01X1391212Y357760D02*
Y358873D01*
X1392805Y360466D01*
G01X1385920Y350658D02*
Y348908D01*
X1385300Y348288D01*
Y347518D01*
G01X1385920Y350658D02*
X1388294D01*
X1388500Y350864D01*
G01X1385900Y353803D02*
X1387498D01*
X1388500Y352801D01*
Y350864D01*
G01X1415500Y353200D02*
X1408246D01*
X1403726Y357720D01*
X1396052D01*
G01X1389500Y360500D02*
Y359800D01*
X1386548Y356848D01*
X1385280D01*
G01X1385300Y344500D02*
X1387300D01*
X1388300Y345500D01*
Y346200D01*
G01X1344253Y354242D02*
X1346918Y351577D01*
X1348988D01*
G01X1373830Y398940D02*
Y398491D01*
X1372007Y396668D01*
G01X1382420Y350658D02*
X1381258D01*
G01X1379100Y578000D02*
X1375988D01*
X1375961Y577973D01*
G01X1403090Y532250D02*
Y536180D01*
X1401761Y537509D01*
X1399721D01*
G01X1390500Y539000D02*
X1392568Y536932D01*
Y535672D01*
X1395490Y532750D01*
Y532250D01*
G01X1377700Y587500D02*
X1376600Y586400D01*
X1374700D01*
X1373700Y585400D01*
Y584656D01*
G01X1388600Y577800D02*
Y577724D01*
X1387986Y577110D01*
Y574960D01*
G01X1395862Y542932D02*
X1391594D01*
X1390462Y541800D01*
G01X1379100Y574500D02*
X1381600D01*
X1382500Y575400D01*
G01X1396158Y537595D02*
X1396935D01*
X1402272Y542932D01*
X1403462D01*
G01X1379200Y609300D02*
X1379073Y609173D01*
X1375961D01*
G01X1379200Y605800D02*
X1379700Y606300D01*
X1382200D01*
G01X1524557Y88336D02*
X1517880D01*
X1516345Y86801D01*
Y85279D01*
X1511550Y80484D01*
Y43050D01*
X1509000Y40500D01*
X1450800D01*
X1436968Y26668D01*
Y10884D01*
X1438725Y9127D01*
Y-204D01*
X1437800Y-1129D01*
Y-18615D01*
X1440485Y-21300D01*
X1618100D01*
X1623942Y-15458D01*
Y-12955D01*
X1630614Y-6283D01*
X1667017D01*
X1672700Y-600D01*
X1695500D01*
X1701300Y5200D01*
X1733807D01*
X1737000Y8393D01*
Y10829D01*
X1740471Y14300D01*
X1745836D01*
X1751925Y20389D01*
Y22896D01*
X1753095Y24066D01*
X1759521D01*
X1763576Y28121D01*
Y43178D01*
X1762300Y44454D01*
Y48100D01*
G01X1451273Y148905D02*
X1453496Y151128D01*
X1460354D01*
G01X1451021Y151626D02*
X1453045Y153650D01*
X1461950D01*
X1464130Y151470D01*
Y143310D01*
X1465328Y142112D01*
X1468572D01*
G01X1451021Y151626D02*
X1448438Y149043D01*
X1447428D01*
G01X1445500Y156800D02*
X1439240D01*
X1438348Y155908D01*
G01X1452659Y188296D02*
Y187571D01*
X1445906Y180818D01*
X1442251D01*
G01X1451427Y167818D02*
X1452343D01*
X1453372Y168847D01*
X1457838D01*
G01X1438500Y163300D02*
X1442000D01*
G01X1434338Y168847D02*
Y164700D01*
X1435738Y163300D01*
X1438500D01*
G01X1434338Y168847D02*
X1437457D01*
X1440124Y166180D01*
G01X1434338Y176527D02*
X1439173D01*
X1440150Y175550D01*
G01X1418300Y199900D02*
X1420220Y201820D01*
X1432750D01*
G01X1456250D02*
X1463670D01*
X1463900Y202050D01*
G01X1449847Y202322D02*
X1450349Y201820D01*
X1456250D01*
G01X1432750Y209500D02*
X1438000D01*
X1439000Y208500D01*
G01X1442251Y180818D02*
X1440332Y182737D01*
Y188452D01*
X1438852Y189932D01*
X1438072D01*
G01X1434338Y184207D02*
Y185907D01*
X1434572Y186141D01*
Y189932D01*
G01X1431664Y190213D02*
X1431945Y189932D01*
X1434572D01*
G01X1467992Y202135D02*
Y201300D01*
X1466792Y200100D01*
X1449146D01*
X1446331Y197285D01*
G01X1432750Y217180D02*
X1427760D01*
X1423461Y221479D01*
X1422281D01*
G01X1445500Y159800D02*
Y156800D01*
G01X1442000Y159800D02*
X1445500D01*
G01X1438500D02*
X1442000D01*
G01X1451365Y170318D02*
X1450678D01*
X1448000Y167640D01*
Y157800D01*
X1447000Y156800D01*
X1445500D01*
G01X1471950Y176700D02*
X1469850Y178800D01*
X1466700D01*
X1464427Y176527D01*
X1457838D01*
G01X1457835Y257526D02*
Y255847D01*
X1458800Y254882D01*
G01X1450182Y275181D02*
X1450181D01*
X1448603Y273603D01*
G01X1454902Y279902D02*
X1456476Y278328D01*
Y278324D01*
G01X1458500Y249000D02*
Y252000D01*
G01X1434750Y232000D02*
X1429500D01*
X1428400Y230900D01*
Y226000D01*
X1430080Y224320D01*
X1434750D01*
G01X1462700Y221700D02*
Y223125D01*
X1461505Y224320D01*
X1458250D01*
G01X1434750D02*
X1458250D01*
G01X1458800Y254882D02*
X1458500Y254582D01*
Y252000D01*
G01X1430900Y250350D02*
X1432300D01*
X1433750Y248900D01*
X1434800D01*
G01X1434750Y239680D02*
Y241658D01*
X1430900Y245508D01*
Y246850D01*
G01X1435655Y246550D02*
X1435355Y246850D01*
X1430900D01*
G01X1458250Y232000D02*
X1462034D01*
X1463457Y233423D01*
X1467054D01*
G01X1454902Y276753D02*
Y276365D01*
X1456093Y275174D01*
X1456476D01*
G01X1451753Y279902D02*
X1450182Y278331D01*
G01X1462000Y252000D02*
Y253766D01*
X1462704Y254470D01*
G01X1460835Y257526D02*
Y256339D01*
X1462704Y254470D01*
G01X1464500Y258600D02*
X1463300D01*
X1462226Y257526D01*
X1460835D01*
G01X1453327Y306678D02*
Y306450D01*
X1454679Y305098D01*
X1454902D01*
G01X1459628Y281473D02*
X1459257D01*
X1458051Y282679D01*
Y283051D01*
G01X1462770Y287777D02*
X1462777D01*
X1464351Y289351D01*
G01X1459627Y300373D02*
X1458051Y301949D01*
G01X1462777Y294072D02*
X1463156D01*
X1464351Y295267D01*
Y295349D01*
G01D02*
X1465650Y294050D01*
X1465949D01*
G01X1464351Y295349D02*
Y295649D01*
G01X1454902Y305098D02*
X1455476D01*
X1456477Y304097D01*
Y303528D01*
G01X1461202Y289351D02*
X1460966D01*
X1459620Y288005D01*
Y287777D01*
G01X1462775Y284620D02*
Y284626D01*
X1464351Y286202D01*
G01X1461202D02*
X1459628Y284628D01*
Y284623D01*
G01X1465949Y297200D02*
X1464351Y298798D01*
G01X1462777Y297222D02*
Y297223D01*
X1461202Y298798D01*
G01Y295649D02*
X1459628Y297223D01*
X1459627D01*
G01X1453327Y303528D02*
X1452895D01*
X1451753Y304670D01*
Y305098D01*
G01X1454902Y308247D02*
X1455476D01*
X1456477Y307246D01*
Y306678D01*
G01X1464124Y353776D02*
X1464650Y353250D01*
Y351376D01*
X1466061Y349965D01*
X1466967D01*
G01X1482000Y395098D02*
Y392709D01*
X1476583Y387292D01*
X1473280D01*
X1472253Y388319D01*
X1461928D01*
X1460631Y389616D01*
X1455940D01*
X1454834Y388510D01*
Y383766D01*
X1456750Y381850D01*
G01D02*
X1458923Y379677D01*
X1465512D01*
X1465735Y379900D01*
X1471950D01*
X1472680Y380630D01*
G01X1463200Y362200D02*
X1465048D01*
X1466600Y360648D01*
Y360500D01*
G01X1449564Y362601D02*
X1448050Y364115D01*
Y374950D01*
G01X1451850Y392790D02*
Y375196D01*
X1450698Y374044D01*
Y369193D01*
X1455589Y364302D01*
X1458761D01*
X1461016Y362047D01*
Y359965D01*
G01X1451850Y392790D02*
X1466510D01*
X1469215Y390085D01*
X1472471D01*
X1475500Y393114D01*
Y394900D01*
G01X1477000Y405200D02*
X1474400D01*
X1473071Y403871D01*
Y401183D01*
X1471688Y399800D01*
X1462682D01*
X1460657Y397775D01*
X1454143D01*
X1451850Y395482D01*
Y392790D01*
G01X1517200Y9641D02*
X1521484D01*
X1521733Y9392D01*
X1526700D01*
X1527700Y8392D01*
Y6963D01*
G01X1502300Y6141D02*
X1505500D01*
G01D02*
Y4500D01*
X1506500Y3500D01*
X1506900D01*
G01X1505500Y9641D02*
X1502300D01*
G01X1510200D02*
X1505500D01*
G01X1501900Y12541D02*
Y11301D01*
X1502300Y10901D01*
Y9641D01*
G01X1524200Y12218D02*
Y13300D01*
X1523092Y14408D01*
X1514500D01*
X1513500Y13408D01*
Y10641D01*
X1512500Y9641D01*
X1510200D01*
G01X1504400Y20300D02*
X1501900Y17800D01*
Y12541D01*
G01X1497500Y79500D02*
Y81933D01*
X1499613Y84046D01*
G01X1497500Y76000D02*
Y79500D01*
G01X1527233Y41018D02*
Y35966D01*
X1528961Y34238D01*
X1531389D01*
G01X1487000Y80000D02*
Y77000D01*
G01X1491164Y82923D02*
X1488241Y80000D01*
X1487000D01*
G01X1494000Y79500D02*
Y80087D01*
X1491164Y82923D01*
G01X1494000Y76000D02*
Y79500D01*
G01X1472072Y142112D02*
Y143589D01*
X1473354Y144871D01*
Y145919D01*
G01D02*
X1471820D01*
X1469747Y147992D01*
Y148276D01*
G01X1473354Y145919D02*
X1476119D01*
X1477200Y147000D01*
Y150400D01*
X1477839Y151039D01*
X1480354D01*
G01X1485150Y145000D02*
X1485984D01*
X1488084Y147100D01*
X1490400D01*
X1490900Y146600D01*
G01X1468572Y142112D02*
Y143528D01*
X1467354Y144746D01*
Y146010D01*
G01X1502192Y164871D02*
Y164946D01*
X1501704Y164458D01*
X1497892D01*
X1497600Y164750D01*
G01X1491196Y218527D02*
X1491853Y217870D01*
Y216455D01*
X1488648Y213250D01*
X1484750D01*
G01X1493700Y185400D02*
X1491600Y187500D01*
X1486700D01*
X1484015Y190185D01*
X1481962D01*
G01X1494783Y177907D02*
X1494725D01*
Y177881D01*
X1494688D01*
Y177862D01*
X1494800D01*
Y177750D01*
X1497200D01*
X1499000Y179550D01*
Y181450D01*
G01X1480250Y176800D02*
Y180000D01*
G01D02*
X1482523D01*
X1483523Y181000D01*
Y181100D01*
G01X1523400Y217900D02*
Y216000D01*
X1522400Y215000D01*
X1520250D01*
G01X1506250Y198250D02*
X1500800D01*
X1499800Y199250D01*
Y199300D01*
G01X1520000Y186000D02*
X1517536D01*
X1517328Y186208D01*
G01X1499000Y181450D02*
X1497050D01*
X1496050Y182450D01*
Y183758D01*
X1494408Y185400D01*
X1493700D01*
G01X1506000Y186570D02*
X1504000D01*
Y186500D01*
X1502500Y185000D01*
Y182000D01*
X1501950Y181450D01*
X1499000D01*
G01X1518798Y166578D02*
X1523078D01*
X1524226Y167726D01*
X1527500D01*
G01X1528065Y171552D02*
Y168291D01*
X1527500Y167726D01*
G01X1468700Y163100D02*
Y173350D01*
X1468450Y173600D01*
Y176700D01*
G01X1505250Y174000D02*
Y177000D01*
G01X1496713Y174853D02*
X1501447D01*
X1502300Y174000D01*
X1505250D01*
G01X1477442Y187269D02*
Y183297D01*
X1478089Y182650D01*
G01X1471388Y173700D02*
X1471988Y173100D01*
Y170177D01*
G01X1473723Y156988D02*
X1476349D01*
X1476761Y157400D01*
G01X1484100Y177700D02*
X1485800Y179400D01*
Y181900D01*
X1484500Y183200D01*
X1478639D01*
X1478089Y182650D01*
G01X1478611Y209695D02*
X1478626D01*
Y211614D01*
X1478006Y212234D01*
Y215348D01*
X1475500Y217854D01*
Y226200D01*
X1476800Y227500D01*
G01X1472758Y216495D02*
X1471250Y218003D01*
Y220000D01*
G01X1471800Y184400D02*
Y186954D01*
X1470382Y188372D01*
G01X1487716Y218650D02*
Y218416D01*
X1485050Y215750D01*
X1484750D01*
G01X1492469Y179387D02*
X1492471D01*
Y179240D01*
X1492473D01*
Y179173D01*
X1493700Y180400D01*
Y181900D01*
G01X1488962Y185067D02*
X1492129Y181900D01*
X1493700D01*
G01X1519243Y191627D02*
X1520000Y190870D01*
Y189000D01*
G01X1473200Y211850D02*
X1474400D01*
X1475401Y210849D01*
Y210017D01*
G01X1484100Y174200D02*
X1479376D01*
X1478642Y174934D01*
X1477808D01*
X1476750Y175992D01*
Y176800D01*
G01Y180000D02*
Y176800D01*
G01Y180000D02*
X1475250D01*
X1471950Y176700D01*
G01X1491700Y241661D02*
Y241600D01*
X1491500Y241400D01*
Y241132D01*
X1490118Y239750D01*
X1485450D01*
G01X1470554Y236923D02*
X1467054D01*
G01X1470729Y240547D02*
Y237098D01*
X1470554Y236923D01*
G01X1485450Y239750D02*
X1480750D01*
X1479500Y238500D01*
G01X1491407Y258353D02*
X1488857D01*
X1487230Y259980D01*
Y261150D01*
G01X1491925Y270500D02*
X1489592D01*
X1489546Y270454D01*
G01X1484822Y275177D02*
X1484823D01*
X1486397Y273603D01*
G01X1481672Y278329D02*
X1482023D01*
X1483247Y277105D01*
Y276753D01*
G01X1469150Y242931D02*
Y242850D01*
X1470729Y241271D01*
Y240547D01*
G01X1479500Y238500D02*
X1478424Y239576D01*
Y241688D01*
G01X1506950Y224750D02*
X1498720D01*
X1498685Y224715D01*
G01X1526900Y257200D02*
X1530200D01*
G01X1523470Y242580D02*
Y242770D01*
X1525071Y244371D01*
X1528460D01*
G01X1472200Y243000D02*
X1474100Y241100D01*
Y237850D01*
G01Y234350D02*
Y234846D01*
X1474678Y235424D01*
X1476092D01*
X1476800Y234716D01*
Y234017D01*
G01X1470554Y233423D02*
X1473173D01*
X1474100Y234350D01*
G01X1467054Y233423D02*
X1470554D01*
G01X1476800Y234017D02*
Y231000D01*
G01X1484822Y278327D02*
X1483247Y279902D01*
G01X1480098Y276753D02*
Y276425D01*
X1481344Y275179D01*
X1481672D01*
G01X1478000Y260000D02*
X1475000D01*
G01X1493450Y264640D02*
X1493500Y264690D01*
Y266500D01*
X1492697Y267303D01*
G01X1484000Y260000D02*
Y257500D01*
G01X1477397Y256657D02*
Y256718D01*
X1478000Y257321D01*
Y260000D01*
G01X1478424Y245188D02*
X1479848D01*
X1482786Y242250D01*
X1485450D01*
G01X1478424Y245188D02*
X1476103D01*
X1475004Y246287D01*
G01X1492697Y267303D02*
X1495075Y269681D01*
Y270500D01*
G01X1504200Y324500D02*
X1506090D01*
X1509280Y321310D01*
X1511700D01*
X1513060Y319950D01*
Y319170D01*
G01D02*
X1514740D01*
X1516510Y320940D01*
X1517600D01*
G01X1472781Y330195D02*
X1471410Y328824D01*
X1469468D01*
X1468326Y329966D01*
Y332768D01*
X1469319Y333761D01*
Y339769D01*
X1470624Y341074D01*
X1472500D01*
G01X1475373Y284626D02*
X1475374D01*
X1476949Y283051D01*
G01X1481672Y306679D02*
X1481679D01*
X1483247Y308247D01*
G01X1478523Y303521D02*
X1478861D01*
X1480098Y304758D01*
Y305098D01*
G01X1475365Y300366D02*
X1475366D01*
X1476949Y301949D01*
G01X1468429Y289284D02*
X1470582D01*
X1470649Y289351D01*
G01X1469000Y294100D02*
X1469322D01*
X1470649Y295427D01*
G01D02*
Y295649D01*
G01X1472226Y294076D02*
X1471910D01*
X1470649Y295337D01*
Y295427D01*
G01X1487000Y325500D02*
Y322400D01*
G01X1487426Y330100D02*
X1487425Y330099D01*
Y328250D01*
X1487100Y327925D01*
Y325900D01*
X1487000Y325800D01*
Y325500D01*
G01X1470649Y289351D02*
X1472222Y287778D01*
X1472223D01*
G01X1506996Y280694D02*
X1512147D01*
X1512300Y280847D01*
G01X1521817Y330937D02*
X1522230Y331350D01*
X1524280D01*
X1526610Y333680D01*
G01X1522810Y327640D02*
Y329944D01*
X1521817Y330937D01*
G01X1470467Y349965D02*
Y347383D01*
X1472500Y345350D01*
Y341074D01*
G01X1519310Y327640D02*
X1514200D01*
X1514050Y327490D01*
G01X1490500Y339500D02*
X1489012D01*
X1488100Y340412D01*
X1487858D01*
G01X1501930Y311510D02*
Y312540D01*
X1500930Y313540D01*
X1499390D01*
X1496590Y316340D01*
X1494490D01*
X1492696Y314546D01*
G01X1475373Y287776D02*
X1473798Y289351D01*
G01X1475365Y297216D02*
X1473798Y295649D01*
G01X1481672Y303529D02*
X1482050D01*
X1483247Y304726D01*
Y305098D01*
G01X1478523Y306671D02*
Y306672D01*
X1480098Y308247D01*
G01X1472223Y284628D02*
X1472674D01*
X1473798Y285752D01*
Y286202D01*
G01X1468429Y286134D02*
X1470581D01*
X1470649Y286202D01*
G01X1472226Y297226D02*
X1473798Y298798D01*
G01X1469000Y297250D02*
X1469101D01*
X1470649Y298798D01*
G01X1507019Y283694D02*
Y285869D01*
X1508650Y287500D01*
G01X1490000Y328600D02*
Y326000D01*
X1490500Y325500D01*
G01X1520000Y343750D02*
Y341766D01*
X1520766Y341000D01*
G01D02*
X1522290D01*
X1526610Y336680D01*
G01X1493240Y325780D02*
X1492480D01*
X1492200Y325500D01*
X1490500D01*
G01X1493240Y325780D02*
Y325500D01*
X1494240Y324500D01*
X1496800D01*
G01X1493240Y325828D02*
Y325780D01*
G01X1512952Y333582D02*
X1515952D01*
G01D02*
X1518952D01*
G01D02*
X1521952D01*
G01X1515952D02*
Y332836D01*
X1513796Y330680D01*
G01X1472680Y380630D02*
X1473050Y380260D01*
X1478130D01*
X1480040Y382170D01*
Y384210D01*
X1482000Y386170D01*
Y387224D01*
G01X1475500Y398400D02*
Y400085D01*
X1475700Y400285D01*
Y401900D01*
G01X1475500Y398400D02*
X1473450D01*
X1472550Y397500D01*
G01X1466967Y349965D02*
X1470467D01*
G01X1474049Y350889D02*
X1472792D01*
X1471868Y349965D01*
X1470467D01*
G01X1517000Y343150D02*
X1519400D01*
X1520000Y343750D01*
G01X1523000D02*
X1526000D01*
G01X1523000D02*
X1520000D01*
G01X1475755Y376254D02*
Y374554D01*
X1473855Y372654D01*
X1473255D01*
G01X1481000Y346750D02*
Y350000D01*
G01X1478163Y354940D02*
X1478080D01*
X1477770Y355250D01*
X1475500D01*
G01X1479150Y430678D02*
X1483737D01*
X1483818Y430597D01*
G01X1491425Y433406D02*
X1488595D01*
X1487980Y432791D01*
X1486572D01*
G01X1501219Y416596D02*
X1504200D01*
X1504240Y416556D01*
G01X1503125Y424834D02*
X1503925Y425634D01*
Y427100D01*
G01X1509200Y413600D02*
X1510775Y415175D01*
G01X1486572Y436291D02*
Y438048D01*
X1484756Y439864D01*
Y440623D01*
G01D02*
X1484533Y440400D01*
X1481800D01*
X1480600Y439200D01*
Y436700D01*
X1479150Y435250D01*
Y434178D01*
G01X1484756Y440623D02*
X1485300Y441167D01*
Y443484D01*
G01X1529000Y515310D02*
X1525700D01*
G01X1478000Y530750D02*
X1478700Y531450D01*
Y533700D01*
G01X1516000Y562500D02*
X1510000D01*
X1504500Y568000D01*
Y587600D01*
G01X1503008Y620018D02*
X1503000D01*
Y621324D01*
X1504676Y623000D01*
X1506540D01*
X1506650Y623110D01*
X1508600D01*
G01X1513700Y619900D02*
X1513800Y620000D01*
Y622000D01*
X1512800Y623000D01*
X1512210D01*
X1512100Y623110D01*
G01X1531389Y34238D02*
Y30941D01*
X1528488Y28040D01*
X1528384D01*
G01X1531200Y7100D02*
X1527837D01*
X1527700Y6963D01*
G01X1586600Y-9600D02*
Y-7703D01*
X1585599Y-6702D01*
X1584447D01*
G01X1573771Y101142D02*
Y100191D01*
X1574883Y99079D01*
Y95178D01*
X1571000Y91295D01*
Y83178D01*
X1575026Y79152D01*
Y74520D01*
X1572800Y72294D01*
Y64100D01*
X1578936Y57964D01*
Y27451D01*
X1573385Y21900D01*
X1550501D01*
X1549334Y23067D01*
Y23856D01*
G01X1538520Y11911D02*
X1538500D01*
Y13000D01*
X1540804Y15304D01*
X1576196D01*
X1587513Y26621D01*
Y60587D01*
X1579100Y69000D01*
G01X1586149Y94288D02*
X1584599D01*
X1582849Y96038D01*
G01X1542179Y39695D02*
X1540750Y41124D01*
Y43500D01*
X1543427Y46177D01*
Y49536D01*
G01X1532500Y64500D02*
Y68000D01*
G01X1529500Y64500D02*
X1532500D01*
G01X1555550Y78000D02*
X1556990D01*
X1558950Y79960D01*
Y81200D01*
G01X1554573Y37216D02*
X1556501D01*
X1558423Y39138D01*
Y44917D01*
X1557277Y46063D01*
G01X1588700Y94288D02*
X1586149D01*
G01X1583621Y87213D02*
X1583334Y87500D01*
X1580531D01*
G01X1583621Y87213D02*
X1583908Y87500D01*
X1586000D01*
X1587100Y88600D01*
Y91000D01*
G01X1532800Y78590D02*
X1532810Y78580D01*
Y68310D01*
X1532500Y68000D01*
G01X1538870Y78980D02*
Y77899D01*
X1541750Y75019D01*
X1541778D01*
X1542347Y74450D01*
X1549000D01*
G01X1577431Y87487D02*
X1574753D01*
X1573060Y85794D01*
Y84120D01*
G01X1583600Y91000D02*
X1580531D01*
G01X1577431Y90987D02*
X1580318D01*
X1580331Y91000D01*
X1580531D01*
G01X1577431Y90987D02*
Y95182D01*
X1577269Y95344D01*
G01X1551107Y65716D02*
Y62313D01*
X1547259Y58465D01*
X1537784D01*
X1536517Y57198D01*
X1534913D01*
G01X1536000Y64500D02*
Y68000D01*
G01Y64500D02*
Y63001D01*
X1534913Y61914D01*
Y57198D01*
G01X1535300Y78490D02*
X1535310Y78480D01*
Y72190D01*
X1536000Y71500D01*
Y68000D01*
G01X1556810Y71760D02*
Y66378D01*
X1558470Y64718D01*
X1559909D01*
G01X1534913Y41018D02*
Y46488D01*
X1542506Y54081D01*
X1549871D01*
X1551107Y52845D01*
Y49536D01*
G01X1559909Y64718D02*
X1562909D01*
G01X1551107Y49536D02*
X1557250D01*
X1557277Y49563D01*
G01X1534889Y34238D02*
Y40994D01*
X1534913Y41018D01*
G01X1541520Y79387D02*
X1541525D01*
Y79382D01*
X1543422Y77485D01*
X1544814D01*
G01D02*
X1546175D01*
X1546640Y77950D01*
X1549000D01*
G01X1552050Y78000D02*
X1550634D01*
X1550584Y77950D01*
X1549000D01*
G01D02*
Y79376D01*
X1548850Y79526D01*
Y81200D01*
G01X1551858Y98991D02*
Y96587D01*
X1552100Y96345D01*
Y94000D01*
G01X1558285Y54807D02*
Y58683D01*
X1560194Y60592D01*
Y64433D01*
X1559909Y64718D01*
G01X1558285Y54807D02*
Y50521D01*
X1557327Y49563D01*
X1557277D01*
G01X1548850Y81200D02*
Y82717D01*
X1548750Y82817D01*
Y88520D01*
X1552100Y91870D01*
Y94000D01*
G01X1588156Y125638D02*
X1591356D01*
G01X1585849Y105038D02*
Y101349D01*
X1585500Y101000D01*
G01X1545500Y112500D02*
Y109000D01*
G01X1558189Y107067D02*
Y107889D01*
X1560240Y109940D01*
X1561900D01*
G01X1545500Y109000D02*
Y104813D01*
X1548955Y101358D01*
G01X1551858Y102491D02*
X1550088D01*
X1548955Y101358D01*
G01X1588156Y125638D02*
X1586506D01*
X1585144Y127000D01*
X1583500D01*
G01X1585500Y101000D02*
X1584937D01*
X1582649Y103288D01*
G01X1554960Y153300D02*
Y155500D01*
X1556255Y156795D01*
Y159680D01*
X1560155Y163580D01*
X1562079D01*
G01X1580275Y101041D02*
X1580285D01*
X1580376Y101132D01*
Y101265D01*
X1579167Y102474D01*
Y104218D01*
G01X1581500Y137000D02*
Y139637D01*
X1581099Y140038D01*
G01X1567520Y133354D02*
Y133261D01*
X1566481Y132222D01*
Y130954D01*
G01X1562500Y149000D02*
X1565500D01*
G01X1562500D02*
X1562387Y148887D01*
X1555899D01*
X1554960Y147948D01*
Y145900D01*
G01X1567425Y144373D02*
X1566093Y145705D01*
Y145707D01*
X1565500Y146300D01*
Y149000D01*
G01X1557000Y117500D02*
X1560002D01*
G01X1554500Y109940D02*
X1556084D01*
X1557450Y111306D01*
Y114898D01*
X1557000Y115348D01*
Y117500D01*
G01X1549000Y112500D02*
Y109000D01*
G01X1554500Y109940D02*
X1552560D01*
X1550000Y112500D01*
X1549000D01*
G01D02*
Y115571D01*
G01Y109000D02*
Y105919D01*
X1549187Y105732D01*
Y104713D01*
G01D02*
X1549794D01*
X1550198Y105117D01*
X1564072D01*
X1566955Y108000D01*
X1568000D01*
G01X1585849Y108538D02*
X1586750D01*
X1588500Y106788D01*
G01X1582649D02*
X1584099D01*
X1585849Y108538D01*
G01X1582649Y106788D02*
X1581567D01*
X1580637Y107718D01*
X1579167D01*
G01D02*
X1575966D01*
X1574665Y106417D01*
G01X1577271Y101142D02*
X1579535Y98878D01*
X1580951D01*
X1581611Y99538D01*
X1582849D01*
G01X1588000Y100500D02*
Y99639D01*
X1586149Y97788D01*
G01X1582849Y99538D02*
X1584599Y97788D01*
X1586149D01*
G01X1576870Y127078D02*
Y128430D01*
X1576187Y129113D01*
Y131439D01*
G01X1548628Y176772D02*
X1556810D01*
X1557634Y175948D01*
G01X1531565Y176645D02*
X1532065D01*
X1532092Y176672D01*
X1535065D01*
G01X1537298Y162703D02*
X1541628Y167033D01*
Y171652D01*
G01X1535399Y190920D02*
X1530149D01*
G01X1583600Y207495D02*
Y207350D01*
X1583450Y207500D01*
Y207600D01*
X1583190Y207860D01*
Y210070D01*
G01D02*
X1579560D01*
X1579540Y210090D01*
G01X1540650Y258590D02*
Y263150D01*
X1541000Y263500D01*
G01X1555500Y247000D02*
Y250500D01*
G01D02*
X1557300D01*
X1558300Y249500D01*
X1561985D01*
X1563440Y250955D01*
G01X1537300Y248318D02*
X1534825D01*
X1533308Y249835D01*
X1530535D01*
X1528460Y247760D01*
Y244371D01*
G01X1552000Y247000D02*
Y250500D01*
G01Y247000D02*
Y242505D01*
X1550553Y241058D01*
X1546442D01*
X1544300Y243200D01*
G01X1547650Y253472D02*
X1549028D01*
X1552000Y250500D01*
G01X1544300Y243200D02*
Y242026D01*
X1542751Y240477D01*
G01X1532500Y260500D02*
Y272408D01*
X1533596Y273504D01*
G01X1544300Y243200D02*
X1541889D01*
X1540009Y241320D01*
X1532430D01*
X1532250Y241500D01*
G01X1572820Y305680D02*
X1575370D01*
X1577625Y303425D01*
Y294430D01*
X1578625Y293430D01*
X1578630D01*
G01X1562500Y296050D02*
Y304968D01*
X1563532Y306000D01*
X1568104D01*
X1568424Y305680D01*
X1572820D01*
G01X1578630Y293430D02*
X1578500Y293300D01*
X1577400D01*
X1576100Y292000D01*
G01X1563000Y334750D02*
X1566000D01*
G01X1559500Y343750D02*
Y341092D01*
X1560024Y340568D01*
Y331800D01*
G01D02*
X1561750D01*
X1563000Y333050D01*
Y334750D01*
G01X1582859Y341112D02*
X1582886Y341139D01*
X1583000D01*
X1584000Y342139D01*
Y343750D01*
G01X1538406Y330157D02*
X1539000Y330751D01*
Y333500D01*
G01X1538406Y330157D02*
X1537981D01*
X1535966Y332172D01*
Y333518D01*
G01X1585352Y366117D02*
Y369117D01*
G01D02*
X1584472Y369997D01*
X1583057D01*
X1582660Y369600D01*
X1582500D01*
G01X1571800Y344300D02*
Y343002D01*
X1570574Y341776D01*
G01X1562500Y343800D02*
X1559550D01*
X1559500Y343750D01*
G01X1554875Y434075D02*
X1555775Y434975D01*
Y436786D01*
G01X1535975Y443525D02*
X1537550Y441950D01*
G01X1540700D02*
X1539125Y443525D01*
G01X1549805Y416465D02*
X1550104D01*
X1551875Y414694D01*
G01X1574250Y418000D02*
X1572300D01*
X1572226Y418074D01*
X1569425D01*
G01X1549964Y424753D02*
X1549837D01*
X1549020Y425570D01*
X1546450D01*
X1545271Y424391D01*
Y422662D01*
G01X1547000Y416750D02*
X1545271Y418479D01*
Y419162D01*
G01X1551875Y443546D02*
X1550455D01*
X1548804Y445197D01*
X1546596D01*
G01X1529000Y515310D02*
X1530390D01*
X1531580Y514120D01*
Y510790D01*
G01X1587610Y579550D02*
X1587069Y579009D01*
X1584500D01*
G01Y583100D02*
X1586400D01*
X1586500Y583000D01*
X1588300D01*
G01X1584500Y579009D02*
Y583100D01*
G01X1538430Y604180D02*
Y601190D01*
X1538337Y601097D01*
G01X1551871Y597810D02*
Y601310D01*
G01X1538337Y601097D02*
Y600887D01*
X1538110Y600660D01*
Y598430D01*
G01X1584500Y603500D02*
Y605030D01*
X1583480Y606050D01*
X1579900D01*
G01X1551871Y594310D02*
X1552911D01*
X1555801Y597200D01*
X1582700D01*
X1584500Y599000D01*
Y600500D01*
G01D02*
Y603500D01*
G01X1579900Y606050D02*
X1578660D01*
X1574910Y609800D01*
X1568810D01*
X1563983Y614627D01*
X1560539D01*
G01X1545407Y604713D02*
X1545584Y604536D01*
X1548672D01*
G01X1541610Y598430D02*
Y601036D01*
X1541384Y601262D01*
G01X1541610Y598430D02*
Y593700D01*
G01X1543697Y606719D02*
Y605947D01*
X1541930Y604180D01*
G01X1620000Y-6218D02*
X1625082D01*
X1626400Y-4900D01*
Y4600D01*
G01X1609450Y34500D02*
X1611122Y32828D01*
X1611922D01*
X1613999Y30751D01*
Y28300D01*
G01X1630121Y37609D02*
X1630209D01*
Y37200D01*
X1630173Y37164D01*
Y36150D01*
X1628500Y34477D01*
Y31900D01*
G01X1616250Y17000D02*
Y13730D01*
X1615698Y13178D01*
Y12698D01*
X1615000Y12000D01*
G01X1651250Y28500D02*
X1646500D01*
X1646250Y28750D01*
X1644000D01*
G01D02*
X1642312D01*
X1638500Y32562D01*
Y36977D01*
X1639623Y38100D01*
G01X1615000Y12000D02*
X1613250Y13750D01*
Y18000D01*
G01X1602504Y-17346D02*
Y-16304D01*
X1601600Y-15400D01*
Y-14300D01*
G01X1592453Y2502D02*
X1590802D01*
X1589500Y1200D01*
Y-600D01*
G01X1605000Y-1100D02*
Y2900D01*
X1606700Y4600D01*
G01X1601650Y24160D02*
X1604740Y27250D01*
X1606500D01*
G01X1594821Y31300D02*
Y21684D01*
X1599255Y17250D01*
X1606500D01*
G01X1617500Y-14500D02*
X1616845Y-13845D01*
Y6258D01*
X1610073Y13030D01*
Y14110D01*
X1608683Y15500D01*
X1607500D01*
X1606500Y16500D01*
Y17250D01*
G01X1610750Y78000D02*
X1599528D01*
X1598878Y77350D01*
X1594968D01*
X1593550Y75932D01*
Y74892D01*
X1592351Y73693D01*
X1591523D01*
X1589739Y71909D01*
Y67953D01*
X1592508Y65184D01*
Y49402D01*
X1594821Y47089D01*
Y42536D01*
X1597331Y40026D01*
Y33810D01*
X1594821Y31300D01*
G01X1621500Y29250D02*
X1622950D01*
X1624500Y30800D01*
Y34099D01*
X1620099Y38500D01*
X1619000D01*
G01X1619750Y17000D02*
Y17708D01*
X1617458Y20000D01*
X1615000D01*
X1613999Y21001D01*
Y23700D01*
G01X1619750Y17000D02*
Y14750D01*
X1617098Y12098D01*
Y10648D01*
X1617000Y10550D01*
Y9500D01*
G01X1638550Y7200D02*
X1636181Y9569D01*
Y11901D01*
X1636196Y11916D01*
Y12018D01*
X1637750Y13572D01*
Y17000D01*
G01X1592453Y6002D02*
Y8502D01*
G01X1613000Y-1100D02*
X1608500D01*
G01D02*
Y-3600D01*
G01X1594600Y-9182D02*
Y5002D01*
X1593600Y6002D01*
X1592453D01*
G01X1590100Y-9600D02*
X1591700D01*
X1592118Y-9182D01*
X1594600D01*
G01X1644000Y32250D02*
X1642116D01*
X1641000Y33366D01*
Y35500D01*
G01X1644000Y32250D02*
X1646751D01*
X1647942Y31059D01*
X1651250D01*
G01X1606500Y30750D02*
Y32200D01*
X1605950Y32750D01*
Y34500D01*
G01X1606500Y30750D02*
X1611100D01*
X1612031Y29819D01*
Y28300D01*
G01X1601200Y32300D02*
X1603400Y34500D01*
X1605950D01*
G01X1609750Y18000D02*
Y19750D01*
X1608750Y20750D01*
X1606500D01*
G01X1612031Y23700D02*
X1607700D01*
X1606500Y22500D01*
Y20750D01*
G01X1601200Y20000D02*
X1601950Y20750D01*
X1606500D01*
G01X1638500Y84000D02*
X1641600D01*
G01X1648400Y67721D02*
X1645700D01*
X1644700Y66721D01*
Y54521D01*
X1646100Y53121D01*
X1648900D01*
G01X1641600Y94000D02*
Y96500D01*
G01X1638500Y94000D02*
Y96500D01*
G01X1611059Y46684D02*
Y47795D01*
X1612882Y49618D01*
X1614118D01*
X1616078Y51578D01*
Y54228D01*
X1617350Y55500D01*
X1619300D01*
G01X1608349Y90538D02*
X1606470Y92417D01*
Y93759D01*
G01X1632000Y80300D02*
Y83000D01*
G01X1609099Y86038D02*
Y85231D01*
X1608098Y84230D01*
X1606730D01*
G01X1600300Y57950D02*
X1599792D01*
X1597050Y60692D01*
Y67610D01*
X1595943Y68717D01*
Y71522D01*
G01X1635900Y83000D02*
X1636900Y84000D01*
X1638500D01*
G01X1610450Y37300D02*
X1610696Y37054D01*
Y35639D01*
X1609557Y34500D01*
X1609450D01*
G01X1592250Y90500D02*
Y92960D01*
X1591270Y93940D01*
G01X1606470Y93759D02*
Y94220D01*
X1608250Y96000D01*
G01X1606730Y84230D02*
X1606960Y84000D01*
X1607022D01*
X1609022Y82000D01*
X1609750D01*
G01X1641600Y84000D02*
X1644100D01*
X1646100Y82000D01*
Y78100D01*
X1648400Y75800D01*
Y67721D01*
G01X1639623Y38100D02*
Y40607D01*
X1624730Y55500D01*
X1619300D01*
G01X1651250Y36750D02*
X1650000Y35500D01*
X1648500D01*
G01X1612599Y86038D02*
Y82651D01*
X1613250Y82000D01*
G01X1614997Y84403D02*
X1614955D01*
X1613320Y86038D01*
X1612599D01*
G01X1614250Y78000D02*
Y81000D01*
X1613250Y82000D01*
G01X1617688Y79904D02*
X1615784Y78000D01*
X1614250D01*
G01X1619000Y38500D02*
X1619250Y38750D01*
G01X1606579Y86726D02*
X1605933Y87372D01*
Y88067D01*
X1603250Y90750D01*
X1602000D01*
G01X1599500Y75000D02*
Y74750D01*
X1599193Y74443D01*
Y70229D01*
G01X1620733Y74847D02*
X1619347D01*
X1618600Y74100D01*
X1612975D01*
X1611461Y75614D01*
X1606478D01*
X1604193Y73329D01*
Y70229D01*
G01X1641000Y35500D02*
X1645000D01*
G01X1598439Y128600D02*
X1596844D01*
X1595522Y127278D01*
G01X1598100Y131600D02*
Y130400D01*
X1598439Y130061D01*
Y128600D01*
G01X1591356Y125638D02*
X1593882D01*
X1595522Y127278D01*
G01X1594149Y100788D02*
Y99321D01*
X1595335Y98135D01*
G01X1616592Y156055D02*
Y153508D01*
X1616900Y153200D01*
G01X1602717Y102240D02*
X1602977Y102500D01*
X1606250D01*
G01X1639250Y115500D02*
Y112653D01*
X1638902Y112305D01*
G01X1644750Y122000D02*
X1651326D01*
X1651536Y121790D01*
G01X1635000Y125750D02*
X1638250D01*
G01X1604400Y115800D02*
X1605200D01*
X1606801Y117401D01*
Y118000D01*
X1607441Y118640D01*
G01X1601400Y116600D02*
X1601800Y116200D01*
X1604000D01*
X1604400Y115800D01*
G01X1638500Y96500D02*
Y99000D01*
G01X1641600Y96500D02*
Y99000D01*
G01X1595335Y98135D02*
X1597349Y100149D01*
Y100788D01*
G01X1595522Y127278D02*
Y126168D01*
X1596940Y124750D01*
X1598500D01*
G01X1603000Y110000D02*
X1602500D01*
X1601000Y108500D01*
Y107000D01*
G01X1591400Y111500D02*
X1592470Y110430D01*
Y110380D01*
X1595850Y107000D01*
X1601000D01*
G01X1590949Y100788D02*
Y97850D01*
G01X1597349Y104288D02*
X1599955D01*
X1600000Y104243D01*
G01X1594149Y104288D02*
X1590949D01*
G01X1594149D02*
X1597349D01*
G01X1591366Y108251D02*
X1590949Y107834D01*
Y104288D01*
G01X1608762Y108548D02*
X1608104Y107890D01*
X1606540D01*
X1605650Y107000D01*
X1604500D01*
G01X1626250Y103000D02*
Y106064D01*
G01X1629380Y179436D02*
Y177120D01*
X1627998Y175738D01*
Y172854D01*
G01X1604401Y213500D02*
X1602901Y212000D01*
X1601200D01*
G01X1635112Y195181D02*
X1635720Y194573D01*
Y194452D01*
X1635876Y194296D01*
Y190731D01*
G01X1601200Y212000D02*
Y214000D01*
X1599949Y215251D01*
X1597181D01*
X1596082Y216350D01*
Y219000D01*
G01X1627998Y172854D02*
Y170248D01*
X1627250Y169500D01*
G01X1613717Y365591D02*
Y364332D01*
X1615010Y363039D01*
X1619578D01*
X1620717Y361900D01*
Y360211D01*
G01X1613717Y365591D02*
X1615667D01*
X1616667Y366591D01*
Y369704D01*
X1617674Y370711D01*
X1620717D01*
G01Y349711D02*
X1619011D01*
X1616800Y347500D01*
Y345500D01*
X1615891Y344591D01*
X1613717D01*
G01X1620717Y349711D02*
Y352013D01*
X1619889Y352841D01*
G01X1620717Y370711D02*
Y373549D01*
X1620340Y373926D01*
X1620447D01*
G01X1608020Y356500D02*
Y356369D01*
X1609298Y355091D01*
X1613717D01*
G01X1630000Y381400D02*
X1634126Y385526D01*
Y404263D01*
X1641376Y411513D01*
Y422354D01*
X1635199Y428531D01*
Y458695D01*
X1635198Y458696D01*
Y459462D01*
X1635197Y459463D01*
Y460881D01*
X1635199Y460883D01*
Y461601D01*
X1642515Y468917D01*
Y476190D01*
X1642516Y476191D01*
Y477609D01*
X1642515Y477610D01*
Y477611D01*
X1641963Y478163D01*
Y482940D01*
X1647048Y488025D01*
X1651754D01*
G01X1626217Y363891D02*
X1627250D01*
X1628250Y362891D01*
Y354349D01*
X1629700Y352899D01*
Y352050D01*
G01X1630000Y381400D02*
X1628200Y379600D01*
Y371400D01*
X1627000Y370200D01*
X1626100D01*
G01X1626217Y363891D02*
Y365383D01*
X1625400Y366200D01*
Y369500D01*
X1626100Y370200D01*
G01X1595352Y369117D02*
X1596235Y370000D01*
X1597900D01*
G01X1619982Y408456D02*
X1618004Y406478D01*
Y388060D01*
X1614779Y384835D01*
X1595591D01*
X1594926Y385500D01*
X1592750D01*
G01X1653960Y562930D02*
Y560800D01*
X1647660Y554500D01*
X1645256D01*
G01X1665000Y23250D02*
Y26250D01*
G01X1672427Y9700D02*
X1670450Y11677D01*
Y22250D01*
X1669450Y23250D01*
X1665000D01*
G01X1762600Y15500D02*
X1754000D01*
X1750100Y11600D01*
X1740600D01*
X1739300Y10300D01*
Y6100D01*
X1736200Y3000D01*
X1703300D01*
X1694800Y-5500D01*
X1679888D01*
X1670900Y-14488D01*
X1667012D01*
G01X1665000Y29750D02*
X1662950D01*
X1661700Y28500D01*
X1658750D01*
G01X1669500D02*
X1668250Y29750D01*
X1665000D01*
G01X1692573Y85833D02*
X1691800Y86606D01*
Y88700D01*
G01X1670250Y87873D02*
Y86750D01*
X1669750Y86250D01*
Y85000D01*
G01X1659019Y95111D02*
X1658408Y94500D01*
X1656000D01*
G01Y84500D02*
X1658000D01*
X1659000Y85500D01*
G01X1713550Y56000D02*
Y54750D01*
X1712375Y53575D01*
X1708925D01*
X1707500Y55000D01*
X1703250D01*
G01X1726750Y47320D02*
X1721880D01*
X1720900Y48300D01*
X1711500D01*
X1709600Y46400D01*
Y45800D01*
G01D02*
X1708080Y47320D01*
X1703250D01*
G01X1684850Y68000D02*
X1683400D01*
X1679400Y72000D01*
X1671388D01*
X1669350Y69962D01*
G01X1702513Y79885D02*
Y85111D01*
X1700800Y86824D01*
Y88700D01*
G01X1691800D02*
X1690424D01*
X1687124Y92000D01*
X1686250D01*
G01D02*
Y95000D01*
G01X1703250Y62680D02*
X1716080D01*
X1718000Y64600D01*
X1728600D01*
X1731800Y67800D01*
X1743500D01*
X1744550Y66750D01*
Y61300D01*
G01X1686250Y89000D02*
Y86000D01*
G01D02*
X1689250D01*
G01X1666250Y85000D02*
X1665500Y84250D01*
Y81600D01*
G01X1666250Y85000D02*
X1662100D01*
G01X1682396Y74344D02*
X1682108D01*
Y74362D01*
X1682538D01*
X1684850Y72050D01*
Y71000D01*
G01X1663000Y81600D02*
X1659850Y78450D01*
X1656950D01*
X1653100Y74600D01*
Y63077D01*
X1655177Y61000D01*
X1658000D01*
X1659000Y60000D01*
Y58800D01*
G01X1662600Y52500D02*
Y54744D01*
X1660394Y56950D01*
X1660142D01*
X1659000Y58092D01*
Y58800D01*
G01X1667000Y51500D02*
X1666000Y52500D01*
X1662600D01*
G01X1694800Y88700D02*
X1697800D01*
G01X1696870Y86093D02*
X1695800D01*
X1694800Y87093D01*
Y88700D01*
G01X1659019Y95111D02*
Y95481D01*
X1657000Y97500D01*
X1656000D01*
G01X1659038Y95111D02*
X1659019D01*
G01X1651590Y118640D02*
Y121736D01*
X1651536Y121790D01*
G01X1711506Y168970D02*
Y167507D01*
X1710811Y166812D01*
Y165400D01*
G01X1708035Y172070D02*
X1705680D01*
X1705000Y172750D01*
Y175500D01*
X1708650Y179150D01*
X1719250D01*
G01X1708035Y172070D02*
Y168999D01*
X1708006Y168970D01*
G01X1713596Y175795D02*
X1712741Y176650D01*
X1710650D01*
G01X1657498Y277300D02*
X1656900D01*
X1655350Y275750D01*
X1652250D01*
G01X1660158Y539547D02*
X1662951D01*
X1667277Y535221D01*
G01X1762600Y15500D02*
X1765800D01*
X1772800Y22500D01*
Y25800D01*
X1771600Y27000D01*
Y31700D01*
G01X1773100Y18700D02*
X1773103Y18703D01*
Y19974D01*
X1776233Y23104D01*
Y25287D01*
X1777565Y26619D01*
G01X1752908Y9481D02*
X1755977Y12550D01*
X1765850D01*
X1772000Y18700D01*
X1773100D01*
G01X1766600Y37800D02*
Y33200D01*
X1768100Y31700D01*
G01X1759900Y71300D02*
X1758554D01*
X1757054Y69800D01*
Y66059D01*
G01X1740300Y92100D02*
X1734000D01*
X1733900Y92200D01*
G01X1762300Y51600D02*
X1763395Y52695D01*
X1771459D01*
G01X1774250Y75500D02*
X1770150D01*
X1768450Y77200D01*
Y77376D01*
G01D02*
X1767326Y78500D01*
X1763250D01*
G01X1743000Y54700D02*
Y51600D01*
G01X1748854Y58533D02*
Y58487D01*
X1745067Y54700D01*
X1743000D01*
G01X1743650Y74700D02*
X1747740D01*
X1748500Y75460D01*
Y79500D01*
G01X1737589Y63639D02*
Y61739D01*
X1736500Y60650D01*
X1735150D01*
G01X1720600Y70200D02*
Y71701D01*
X1716000Y76301D01*
Y79500D01*
G01X1749810Y85620D02*
X1753136D01*
X1754703Y84053D01*
G01X1749810Y85620D02*
Y89860D01*
X1752060Y92110D01*
G01X1774250Y75500D02*
Y74974D01*
X1772211Y72935D01*
Y70650D01*
G01Y67650D02*
Y70650D01*
G01X1749810Y82120D02*
X1751920D01*
X1752980Y81060D01*
X1756750D01*
G01X1760364Y85136D02*
Y83264D01*
X1758160Y81060D01*
X1756750D01*
G01X1746328Y59011D02*
X1746300D01*
Y58900D01*
X1745200Y57800D01*
X1743000D01*
G01X1759800Y68300D02*
Y65990D01*
X1760016Y65774D01*
G01X1728460Y83830D02*
X1728450Y83820D01*
X1715180D01*
X1713900Y85100D01*
Y87900D01*
G01X1727181Y89100D02*
Y87729D01*
X1728460Y86450D01*
Y83830D01*
G01X1766600Y37800D02*
X1771200Y42400D01*
X1779400D01*
X1785413Y36387D01*
Y32864D01*
X1787164Y31113D01*
G01X1770600Y46800D02*
X1763600D01*
X1762300Y48100D01*
G01X1770250Y99500D02*
X1767250D01*
G01X1770250Y104500D02*
X1767250D01*
G01X1733403Y130212D02*
Y132212D01*
X1731903Y133712D01*
G01X1748550Y144638D02*
X1747352D01*
X1745364Y142650D01*
G01X1730289Y130319D02*
Y126381D01*
G01X1733403Y126712D02*
X1732042D01*
X1731711Y126381D01*
X1730289D01*
G01X1759400Y246400D02*
Y248600D01*
X1758000Y250000D01*
G01X1759400Y243400D02*
Y246400D01*
G01X1768400Y512800D02*
X1770450Y514850D01*
Y519574D01*
X1768900Y521124D01*
G01X1764900Y512800D02*
X1768400D01*
G01X1749090Y513790D02*
Y511169D01*
X1750900Y509359D01*
X1752900D01*
G01X1774200Y512800D02*
X1770700Y509300D01*
X1768400D01*
G01X1759900Y509359D02*
X1764841D01*
X1764900Y509300D01*
G01D02*
X1768400D01*
G01X1766100Y521124D02*
Y520900D01*
X1768500Y518500D01*
Y517000D01*
G01X1729950Y559000D02*
Y561450D01*
X1730814Y562314D01*
Y565314D01*
G01X1718000Y587723D02*
Y587299D01*
X1719049Y586250D01*
X1720550D01*
G01X1733950Y586004D02*
X1730954D01*
X1730950Y586000D01*
G01X1746269Y581351D02*
Y583231D01*
X1743970Y585530D01*
X1742381D01*
G01X1730950Y586000D02*
X1729001D01*
X1728245Y585244D01*
G01X1733000Y560000D02*
X1733369Y560369D01*
Y565314D01*
G01X1750792Y581471D02*
X1748120D01*
X1748000Y581351D01*
X1746269D01*
G01X1762519Y566793D02*
X1759370D01*
X1756417Y563840D01*
G01X1769000Y578900D02*
Y576378D01*
G01Y581900D02*
Y578900D01*
G01X1765000Y582500D02*
X1766900D01*
X1767500Y581900D01*
X1769000D01*
G01X1769050Y585000D02*
Y581950D01*
X1769000Y581900D01*
G01X1769050Y588100D02*
Y585000D01*
G01X1769000Y591100D02*
Y588150D01*
X1769050Y588100D01*
G01X1770400Y562450D02*
X1770050Y562800D01*
X1767700D01*
X1767000Y563500D01*
G01X1745200Y555363D02*
X1747672D01*
X1749000Y554035D01*
Y552863D01*
G01X1730814Y565314D02*
Y568814D01*
G01X1741700Y555363D02*
Y556100D01*
X1742900Y557300D01*
X1743600D01*
X1744700Y558400D01*
Y559200D01*
G01X1724250Y588250D02*
X1722750Y589750D01*
X1720550D01*
G01X1724899Y584748D02*
Y584052D01*
X1728254Y580697D01*
Y575914D01*
G01X1770500Y555500D02*
X1767141D01*
G01X1753949Y586743D02*
X1756578D01*
G01X1729950Y555500D02*
X1726850D01*
G01X1742769Y581351D02*
Y579761D01*
X1742792Y579738D01*
Y578251D01*
G01X1729950Y555500D02*
X1731500D01*
X1733000Y557000D01*
G01X1739500Y586500D02*
Y584620D01*
X1742769Y581351D01*
G01X1757792Y576353D02*
X1762433D01*
X1762595Y576191D01*
G01X1765000Y579000D02*
Y578596D01*
X1762595Y576191D01*
G01X1741700Y555363D02*
Y553363D01*
X1742200Y552863D01*
G01X1750315Y560887D02*
X1747587D01*
X1745900Y559200D01*
X1744700D01*
G01X1724092Y618700D02*
X1726720D01*
X1726732Y618712D01*
G01X1760157Y598243D02*
X1759067Y597153D01*
Y593743D01*
G01X1736097Y596859D02*
X1732726D01*
X1732443Y597142D01*
G01X1760157Y598243D02*
X1762643D01*
X1763500Y599100D01*
G01D02*
Y600600D01*
X1766400Y603500D01*
G01X1754300Y618718D02*
X1750739D01*
G01X1771897Y613578D02*
Y611221D01*
X1772158Y610960D01*
G01X1742000Y613582D02*
X1744838D01*
X1746052Y614796D01*
G01X1757057Y601792D02*
Y603299D01*
X1758108Y604350D01*
X1758550D01*
G01D02*
X1759157D01*
X1760157Y603350D01*
Y601743D01*
G01X1735000Y618700D02*
X1730244D01*
X1730232Y618712D01*
G01X1735000Y618700D02*
Y621002D01*
G01X1761300Y613600D02*
X1764823D01*
G01X1768397Y613578D02*
X1768375Y613600D01*
X1764823D01*
G01X1848486Y29680D02*
X1846629Y31537D01*
X1836806D01*
X1835363Y32980D01*
X1833236D01*
G01D02*
X1829236D01*
G01X1825500Y14250D02*
X1829491D01*
X1830344Y13397D01*
G01X1784415Y15168D02*
Y11926D01*
X1785612Y10729D01*
G01X1784415Y18168D02*
Y15168D01*
G01X1782200Y21700D02*
X1784415Y19485D01*
Y18168D01*
G01X1788421Y8122D02*
X1788052Y8491D01*
Y14530D01*
X1790122Y16600D01*
X1793500D01*
G01X1777565Y26619D02*
X1779374Y24810D01*
X1788690D01*
X1793500Y20000D01*
Y16600D01*
G01X1777565Y26619D02*
Y31869D01*
X1774600Y34834D01*
Y37800D01*
G01X1804500Y16600D02*
Y15000D01*
X1806500Y13000D01*
Y8000D01*
X1809900Y4600D01*
Y2700D01*
X1812728Y-128D01*
X1820572D01*
X1823807Y-3363D01*
Y-3765D01*
X1825342Y-5300D01*
X1828200D01*
X1829590Y-3910D01*
X1833210D01*
G01D02*
X1837490D01*
X1837800Y-3600D01*
G01X1787164Y31113D02*
X1788463Y29814D01*
X1793206D01*
X1801000Y22020D01*
Y16600D01*
G01X1779440Y52250D02*
X1786928Y44762D01*
Y35744D01*
X1790372Y32300D01*
X1794800D01*
X1811645Y15455D01*
Y9755D01*
X1815100Y6300D01*
X1816877D01*
X1816902Y6275D01*
X1818526D01*
X1823374Y1427D01*
Y192D01*
X1824516Y-950D01*
X1834750D01*
X1835500Y-1700D01*
G01X1804814Y84623D02*
Y86557D01*
X1802300Y89071D01*
Y89500D01*
G01X1804814Y84623D02*
Y83650D01*
X1801164Y80000D01*
X1800000D01*
G01X1775000Y53500D02*
X1778190D01*
X1779440Y52250D01*
G01X1818383Y133277D02*
Y135743D01*
X1816526Y137600D01*
X1814900D01*
G01X1795436Y138481D02*
Y141836D01*
X1797389Y143789D01*
X1800264D01*
G01X1790318Y131481D02*
Y128380D01*
X1789127Y127189D01*
Y126481D01*
X1788627Y125981D01*
G01X1814900Y140600D02*
Y141952D01*
X1815348Y142400D01*
Y143437D01*
G01X1779300Y508100D02*
Y497249D01*
X1779303Y497246D01*
G01X1811975Y491630D02*
X1814400Y494055D01*
Y495600D01*
G01X1819125Y491830D02*
X1817900Y493055D01*
Y495600D01*
G01X1824125Y491830D02*
Y497375D01*
X1824750Y498000D01*
G01X1804541Y503600D02*
Y498717D01*
X1804000Y498176D01*
G01X1784182Y506600D02*
X1782700D01*
X1781200Y508100D01*
X1779300D01*
G01X1810508Y515900D02*
X1810208Y515600D01*
X1807600D01*
G01X1810508Y515900D02*
X1815186D01*
X1817918Y513168D01*
Y510600D01*
G01X1794100Y521900D02*
Y517000D01*
X1790700Y513600D01*
X1789300D01*
G01X1814400Y499100D02*
X1815200Y499900D01*
Y501500D01*
G01X1804100Y515600D02*
X1801600D01*
G01X1804541Y510600D02*
Y515159D01*
X1804100Y515600D01*
G01X1817900Y499100D02*
X1822100D01*
X1825000Y502000D01*
Y503700D01*
G01X1817900Y499100D02*
X1814400D01*
G01X1815200Y501500D02*
X1814300D01*
X1812800Y503000D01*
Y503600D01*
G01X1786741Y506600D02*
Y519041D01*
X1786800Y519100D01*
G01D02*
X1787700Y520000D01*
X1789300D01*
G01X1828824Y557663D02*
X1828687Y557800D01*
X1828420D01*
X1828238Y557982D01*
X1815400D01*
G01X1786200Y577800D02*
X1785100D01*
X1783700Y579200D01*
G01X1810863Y560637D02*
X1808400Y563100D01*
G01D02*
X1805500D01*
X1805000Y562600D01*
X1802400D01*
G01X1798250Y531800D02*
Y529200D01*
G01X1803950Y533048D02*
X1801348D01*
X1800100Y531800D01*
X1798250D01*
G01X1781800Y585000D02*
Y582457D01*
X1781448Y582105D01*
Y580310D01*
X1781450Y580308D01*
Y578692D01*
X1781448Y578690D01*
Y578652D01*
X1783700Y576400D01*
G01X1786200Y574700D02*
X1785400D01*
X1783700Y576400D01*
G01X1786200Y580900D02*
Y583400D01*
X1785050Y584550D01*
G01X1816330Y545260D02*
X1820589Y541001D01*
X1822052D01*
G01D02*
Y537501D01*
G01X1792100Y566900D02*
X1791800Y566600D01*
Y566224D01*
X1790800Y565224D01*
X1789188D01*
G01D02*
Y562112D01*
X1790500Y560800D01*
Y559100D01*
G01X1893094Y-10142D02*
X1892258D01*
X1889575Y-12825D01*
Y-15062D01*
G01X1877270Y63473D02*
X1876149Y64594D01*
X1870817D01*
G01X1880986Y53299D02*
Y53634D01*
X1880700Y53920D01*
Y54100D01*
X1879450Y55350D01*
X1877892D01*
G01X1868670Y42765D02*
X1869170D01*
X1869464Y42471D01*
X1873204D01*
X1875924Y45191D01*
Y47250D01*
G01X1871988Y55350D02*
Y57511D01*
X1870817Y58682D01*
Y61094D01*
G01D02*
X1871651D01*
X1873086Y62529D01*
X1875364D01*
X1877102Y60791D01*
X1877103D01*
G01D02*
X1877102Y60790D01*
Y58903D01*
X1875924Y57725D01*
Y55350D01*
G01X1877892Y47250D02*
Y45108D01*
X1879100Y43900D01*
Y43207D01*
X1878800D01*
G01X1886800Y72500D02*
X1888400Y74100D01*
X1893121D01*
X1893856Y73365D01*
X1893961D01*
G01X1900945Y41634D02*
X1891834D01*
X1890850Y40650D01*
X1888750D01*
X1886800Y42600D01*
Y72500D01*
G01X1873956Y47250D02*
Y45881D01*
X1872956Y44881D01*
X1868232D01*
X1863413Y49700D01*
X1858700D01*
G01D02*
X1854536D01*
X1851736Y52500D01*
X1842511D01*
X1839390Y55621D01*
Y59416D01*
G01X1843107Y97988D02*
X1842845Y98250D01*
X1839450D01*
G01X1875650Y142800D02*
X1875050Y142500D01*
X1869383D01*
G01X1883840Y152300D02*
Y158305D01*
G01X1875650Y147800D02*
Y150160D01*
X1876380Y150890D01*
X1878910D01*
X1879320Y151300D01*
X1882840D01*
X1883840Y152300D01*
G01X1881150Y142800D02*
Y147800D01*
G01X1895673Y151800D02*
X1897264D01*
X1898265Y150799D01*
Y149556D01*
X1900821Y147000D01*
X1902370D01*
G01X1881150Y147800D02*
X1882350Y149300D01*
X1893141D01*
X1895641Y151800D01*
X1895673D01*
G01X1889913Y210437D02*
X1886963D01*
X1886800Y210600D01*
G01X1881100Y176000D02*
X1883400Y173700D01*
X1885300D01*
X1886400Y172600D01*
G01D02*
X1887100D01*
X1888800Y170900D01*
X1889700D01*
G01X1886400Y170000D02*
X1888700Y167700D01*
X1889700D01*
G01X1889750Y174500D02*
Y175750D01*
X1890650Y176650D01*
Y178600D01*
G01X1889750Y174500D02*
X1888500D01*
X1886863Y176137D01*
X1883930D01*
G01X1882250Y463250D02*
Y466084D01*
X1881285Y467049D01*
G01X1846000Y506000D02*
X1844000D01*
X1843000Y505000D01*
G01X1874087Y487232D02*
X1872232D01*
X1870732Y485732D01*
X1870138D01*
G01X1854890Y508600D02*
X1852880D01*
X1852340Y509140D01*
G01X1854890Y508600D02*
Y507240D01*
X1854550Y506900D01*
Y505510D01*
G01X1864339Y509560D02*
X1866730D01*
G01X1894200Y470200D02*
X1890279D01*
X1886500Y473979D01*
X1886516Y473995D01*
G01X1854890Y512100D02*
X1858090D01*
G01X1836600Y521600D02*
X1837708Y520492D01*
X1859988D01*
X1860280Y520200D01*
G01D02*
X1861648Y518832D01*
Y515658D01*
X1858090Y512100D01*
G01X1870892Y583245D02*
X1872115Y584468D01*
Y586119D01*
G01X1893850Y575087D02*
Y577950D01*
X1891600Y580200D01*
X1889800D01*
G01X1877704Y576218D02*
Y576904D01*
X1879800Y579000D01*
G01X1858000Y574000D02*
X1859254Y572746D01*
X1861538D01*
G01X1845750Y542500D02*
Y544245D01*
X1847005Y545500D01*
X1848900D01*
G01X1841500Y552600D02*
X1842500D01*
X1844100Y551000D01*
G01X1874410Y527560D02*
X1877518D01*
G01X1887004Y539908D02*
X1878908D01*
X1878000Y539000D01*
G01X1859187Y534585D02*
Y534191D01*
X1859217Y534161D01*
Y531331D01*
G01X1861080Y537090D02*
X1860188D01*
X1859187Y536089D01*
Y534585D01*
G01X1875000Y579500D02*
X1877362Y581862D01*
X1879862D01*
G01X1865038Y572746D02*
Y568302D01*
X1864804Y568068D01*
G01X1852250Y545500D02*
Y547900D01*
G01X1865038Y572746D02*
X1864968Y572816D01*
Y574268D01*
X1866918Y576218D01*
X1868704D01*
G01X1875000Y579500D02*
Y576514D01*
X1874704Y576218D01*
G01D02*
X1871704D01*
G01D02*
X1868704D01*
G01X1864804Y568068D02*
X1858700D01*
X1858681Y568087D01*
G01X1838000Y552600D02*
Y549700D01*
G01X1865810Y533140D02*
Y534764D01*
X1867046Y536000D01*
X1868110D01*
G01X1866730Y527560D02*
Y531220D01*
X1865810Y532140D01*
Y533140D01*
G01X1879862Y581862D02*
X1881933Y579791D01*
Y577447D01*
X1880704Y576218D01*
G01X1862717Y531331D02*
X1862687Y531361D01*
Y534585D01*
G01D02*
Y535167D01*
X1864580Y537060D01*
G01X1875646Y533140D02*
X1878636D01*
X1878736Y533040D01*
G01X1849000Y530700D02*
X1846981D01*
X1845407Y532274D01*
Y533178D01*
G01X1896899Y557790D02*
X1898590D01*
X1899654Y558854D01*
Y560968D01*
G01X1899700Y594600D02*
X1897013D01*
X1896358Y595255D01*
G01X1872115Y591239D02*
X1871815Y590939D01*
X1868200D01*
G01X1899972Y609913D02*
Y602472D01*
X1895100Y597600D01*
X1886700D01*
X1883287Y594187D01*
Y592361D01*
X1882165Y591239D01*
X1879115D01*
G01X1909406Y76790D02*
X1908847D01*
X1904736Y72679D01*
Y70607D01*
G01X1902796Y79820D02*
Y76346D01*
X1898143Y71693D01*
Y70589D01*
G01X1924000Y71500D02*
X1925284D01*
X1926890Y73106D01*
G01X1944740Y81810D02*
X1947024D01*
X1948472Y80362D01*
G01X1945156Y160236D02*
X1945992Y159400D01*
X1948300D01*
X1948921Y158779D01*
Y156109D01*
G01X1954041D02*
X1957874D01*
X1958902Y157137D01*
Y159545D01*
G01X1950983Y147344D02*
X1951756D01*
X1953597Y145503D01*
X1956376D01*
G01X1917953Y115400D02*
X1914680D01*
X1914152Y115928D01*
G01X1942637Y103377D02*
Y100877D01*
G01X1901000Y131500D02*
Y137024D01*
X1904136Y140160D01*
G01X1929937Y145452D02*
Y147437D01*
X1932377Y149877D01*
Y153093D01*
X1929711Y155759D01*
G01D02*
X1931552Y157600D01*
X1933250D01*
G01X1910500Y119000D02*
X1909000Y120500D01*
X1904000D01*
X1901000Y123500D01*
Y128000D01*
G01X1921264Y153000D02*
X1917964Y156300D01*
X1916300D01*
G01X1940900Y153400D02*
X1938100D01*
X1937900Y153600D01*
G01X1920100Y143100D02*
X1917800D01*
X1914700Y140000D01*
Y137600D01*
G01X1920100Y143100D02*
Y147358D01*
X1921434Y148692D01*
Y152830D01*
X1921264Y153000D01*
G01X1908100Y155900D02*
X1910200D01*
X1910700Y156400D01*
X1912100D01*
G01X1911961Y153000D02*
X1912100Y153139D01*
Y156400D01*
G01X1905540Y153000D02*
Y155960D01*
X1904650Y156850D01*
X1901400D01*
G01X1932700Y206835D02*
X1937065D01*
X1937100Y206800D01*
G01X1943776Y173012D02*
X1943791Y173027D01*
X1945207D01*
X1946406Y171828D01*
X1947662D01*
G01X1950994Y173745D02*
X1949077Y171828D01*
X1947662D01*
G01X1958902Y159545D02*
X1960749D01*
X1963751Y156543D01*
Y156309D01*
G01X1947686Y197022D02*
X1949752D01*
X1951244Y195530D01*
X1953200D01*
G01X1926949Y183722D02*
Y188593D01*
X1926841Y188701D01*
G01X1931639Y178396D02*
Y180722D01*
X1930639Y181722D01*
X1928241D01*
X1927449Y182514D01*
Y182586D01*
X1926949Y183086D01*
Y183722D01*
G01X1922250Y171600D02*
Y167750D01*
X1922600Y167400D01*
G01X1928218Y175443D02*
X1927891D01*
X1924048Y171600D01*
X1922250D01*
G01X1921974Y175140D02*
Y179429D01*
X1922013Y179468D01*
G01X1901400Y156850D02*
Y161200D01*
G01X1900086Y220827D02*
X1900927D01*
X1902909Y222809D01*
Y223195D01*
G01X1934200Y444500D02*
X1938600Y448900D01*
Y455267D01*
G01X1901574Y454422D02*
X1901500Y454496D01*
Y451000D01*
G01X1934800Y454200D02*
Y451100D01*
X1935300Y450600D01*
G01X1905010Y479410D02*
X1905410D01*
X1907161Y481161D01*
X1908859D01*
G01X1950620Y510380D02*
Y509780D01*
X1952400Y508000D01*
X1952500D01*
G01X1951439Y526250D02*
Y528639D01*
X1953300Y530500D01*
X1955400D01*
G01X1929453Y511202D02*
X1934695Y505960D01*
X1938390D01*
X1939850Y507420D01*
Y513140D01*
X1940860Y514150D01*
Y519515D01*
X1943518Y522173D01*
Y524500D01*
G01X1942722Y498100D02*
Y494962D01*
X1938410Y490650D01*
G01X1944710Y484520D02*
X1946780Y482450D01*
X1947380D01*
G01X1952970Y501030D02*
X1954550D01*
X1955790Y499790D01*
G01X1954120Y510380D02*
Y509620D01*
X1952500Y508000D01*
G01X1959260Y506010D02*
X1961922D01*
G01X1915100Y480050D02*
X1913972Y481178D01*
X1912342D01*
G01X1952970Y504530D02*
X1953560D01*
X1956500Y507470D01*
G01X1947840Y505100D02*
X1952400D01*
X1952970Y504530D01*
G01X1946350Y488450D02*
Y486550D01*
X1947550Y485350D01*
G01X1949940Y488450D02*
X1946350D01*
G01X1949940D02*
Y487740D01*
X1947550Y485350D01*
G01X1934720Y520400D02*
X1935790Y519330D01*
X1937730D01*
X1938400Y518660D01*
Y517500D01*
G01X1954120Y513880D02*
X1950620D01*
G01X1951439Y519250D02*
Y514699D01*
X1950620Y513880D01*
G01X1937300Y508900D02*
Y516400D01*
X1938400Y517500D01*
G01X1941210Y484520D02*
X1940030D01*
X1938300Y486250D01*
G01X1933360Y486480D02*
X1938070D01*
X1938300Y486250D01*
G01X1923260Y482920D02*
X1919740D01*
X1919230Y483430D01*
G01X1923260Y486420D02*
X1919790D01*
X1919000Y487210D01*
G01X1923600Y554200D02*
Y554100D01*
X1924200Y553500D01*
X1925941D01*
G01X1940000Y532600D02*
X1940200D01*
X1943300Y535700D01*
G01X1904250Y556750D02*
X1908350D01*
X1908400Y556800D01*
G01X1899654Y566968D02*
Y563968D01*
G01X1906050Y569100D02*
X1904656D01*
X1902524Y566968D01*
X1899654D01*
G01X1913800Y555500D02*
X1914300Y556000D01*
X1915900D01*
X1917500Y554400D01*
G01X1918000Y549900D02*
X1917050D01*
X1915050Y547900D01*
G01X1898154Y569968D02*
X1900318D01*
X1900729Y569557D01*
G01X1936770Y607210D02*
Y607040D01*
X1935730Y606000D01*
X1931059D01*
G01X1916050Y604450D02*
X1917750Y602750D01*
Y600400D01*
G01X1959400Y601100D02*
X1962400Y598100D01*
X1963200D01*
G01X1921250Y600400D02*
Y603200D01*
X1919900Y604550D01*
G01X1925941Y599000D02*
Y601409D01*
X1922900Y604450D01*
G01X1926240Y594760D02*
X1925764D01*
X1923504Y592500D01*
G01X1944882Y589960D02*
X1937610D01*
X1936970Y590600D01*
G01X1899972Y609913D02*
X1906743D01*
X1907240Y610410D01*
G01X1944882Y605708D02*
X1947523Y608349D01*
G01X1942241D02*
X1944882Y605708D01*
G01X1965400Y149700D02*
Y150400D01*
X1963751Y152049D01*
Y156309D01*
G01X1968871D02*
X1969991D01*
X1971100Y155200D01*
Y152600D01*
X1971200Y152500D01*
G01D02*
X1971109Y152409D01*
X1969808D01*
X1968329Y150930D01*
Y149961D01*
X1968249Y149881D01*
G01X1963400Y141100D02*
X1964901Y139599D01*
X1968376D01*
G01X1971749Y149881D02*
X1971829Y149801D01*
Y148879D01*
X1973328Y147380D01*
Y147303D01*
G01X1965973Y166190D02*
Y169460D01*
G01X1963500Y518200D02*
Y521000D01*
G01X1967040Y513010D02*
Y518160D01*
X1967000Y518200D01*
G01D02*
Y521400D01*
X1967200Y521600D01*
G01X1972700Y552700D02*
X1972300D01*
X1970700Y551100D01*
X1969100D01*
G01X1964382Y583300D02*
X1962100D01*
X1961500Y582700D01*
G01X1964882Y563000D02*
X1962800D01*
X1961500Y561700D01*
G01X1965700Y574700D02*
X1964700D01*
X1963000Y573000D01*
G01X1966500Y545500D02*
Y550600D01*
X1966100Y551000D01*
G01X1966500Y540500D02*
Y545500D01*
G01X1966100Y551000D02*
X1963097D01*
G01X1969500Y590300D02*
Y588200D01*
X1972700Y585000D01*
Y576400D01*
G01X1970000Y570000D02*
Y574400D01*
X1969800Y574600D01*
G01X1972700Y576400D02*
X1970900Y574600D01*
X1969800D01*
X-13780Y598560D03*
X-3937Y-43307D03*
X-7874Y216181D03*
Y325315D03*
X40512Y458744D03*
X-4488Y425472D03*
X-3937Y646063D03*
X99980Y136909D03*
X133563Y183126D03*
Y419626D03*
X224410Y301378D03*
X326772Y163582D03*
Y439173D03*
X500000Y163582D03*
Y439173D03*
X602362Y214764D03*
Y387992D03*
X638541Y171945D03*
Y454425D03*
X783171Y183126D03*
X752641Y159945D03*
X783171Y419626D03*
X752641Y442425D03*
X874016Y301378D03*
X976378Y163582D03*
Y439173D03*
X1149606Y163582D03*
Y439173D03*
X1251969Y214764D03*
Y387992D03*
X1288068Y171945D03*
Y454425D03*
X1401516Y23976D03*
X1402168Y159945D03*
Y442425D03*
X1454685Y338189D03*
X1466693Y375787D03*
X1504666Y29882D03*
X1527844Y80791D03*
Y159531D03*
X1536123Y23968D03*
X1572599Y505315D03*
X1628142Y240199D03*
Y263999D03*
X1600355Y527165D03*
X1638131Y525946D03*
Y475946D03*
X1611283Y567874D03*
Y615236D03*
X1712012Y195587D03*
X1699600Y235400D03*
Y454297D03*
X1674921Y528523D03*
X1658528Y567874D03*
X1705772D03*
X1674921Y545059D03*
X1705772Y615236D03*
X1724606Y235430D03*
X1724807Y451179D03*
X1773347Y528523D03*
Y545059D03*
X1836693Y120158D03*
X1800986Y523267D03*
X1800985Y602503D03*
X1872343Y29874D03*
X1854501Y195587D03*
X1866923Y235400D03*
X1841929Y235430D03*
X1859854Y501441D03*
Y525063D03*
X1956693Y-43307D03*
X1954804Y120158D03*
X1956890Y211535D03*
Y237126D03*
X1955506Y454297D03*
X1930319Y451179D03*
X1956693Y646063D03*
X1969291Y486064D03*
Y497874D03*
G54D123*
X1395512Y344135D03*
X1399012D03*
G54D241*
G01X1668247Y100653D02*
X1668276Y100624D01*
X1674104D01*
X1678959Y95769D01*
X1680255D01*
X1681102Y94922D01*
Y93210D01*
X1682312Y92000D01*
X1682750D01*
G01X1695236Y138938D02*
X1695364Y138810D01*
G03X1696986Y138138I1622J1622D01*
G01X1698084D01*
G02X1701709Y136637I0J-5128D01*
G01X1703100Y135246D01*
G01D02*
X1704997Y133349D01*
G03X1712840Y130100I7843J7842D01*
G01X1723264D01*
X1723314Y130050D01*
G01X1715318Y128300D02*
X1712840D01*
G02X1703724Y132076I0J12892D01*
G01X1700436Y135364D01*
G03X1698084Y136338I-2352J-2353D01*
G01X1697173D01*
G03X1695236Y135788I0J-3686D01*
G01X1677386Y132788D02*
X1677605Y132413D01*
G03X1677964Y132208I358J211D01*
G01X1684383D01*
G02X1686019Y131530I0J-2313D01*
G01X1696069Y121480D01*
G03X1697952Y120700I1883J1882D01*
G01X1709277D01*
G01D02*
X1711807D01*
G02X1714015Y119785I-1J-3124D01*
G01X1718412Y115389D01*
G03X1719714Y114850I1302J1302D01*
G01X1726145D01*
G02X1728857Y113727I0J-3836D01*
G01X1731785Y110799D01*
G03X1733480Y112494I848J848D01*
G01X1731491Y114483D01*
Y114484D01*
X1728967Y117008D01*
G02X1731182Y122357I2215J2216D01*
G01X1733475D01*
G02X1736859Y120759I0J-4383D01*
G01X1737580Y119882D01*
Y119881D01*
G02X1739064Y117450I-7890J-6485D01*
G01X1690860Y124143D02*
X1686018Y128985D01*
X1684745Y130257D01*
G03X1684383Y130408I-363J-361D01*
G01X1677785D01*
G03X1677386Y130009I0J-399D01*
G01Y129638D01*
G01X1735914Y117450D02*
G03X1736189Y118738I-375J753D01*
G01X1735468Y119615D01*
G03X1733474Y120557I-1994J-1640D01*
G01X1731182D01*
G03X1730240Y118281I0J-1333D01*
G01X1733291Y115230D01*
Y115229D01*
X1734753Y113767D01*
X1734754D01*
G02X1730512Y109526I-2121J-2121D01*
G01X1727584Y112454D01*
G03X1726145Y113050I-1439J-1439D01*
G01X1719715D01*
G02X1717139Y114116I-2J3641D01*
G01X1712742Y118512D01*
G03X1711806Y118900I-936J-936D01*
G01X1697953D01*
X1697952Y118899D01*
Y118900D01*
G02X1694796Y120207I-1J4462D01*
G01X1690860Y124143D01*
G01X1712642Y99814D02*
X1711244Y98416D01*
G02X1707003Y102656I-2120J2120D01*
G01X1709700Y105352D01*
G03X1707970Y107082I-865J865D01*
G01X1705402Y104514D01*
G02X1700562Y106519I-2005J2005D01*
G01Y109053D01*
G03X1698167I-1197J0D01*
G01Y108523D01*
G02X1692172I-2997J0D01*
G01Y109223D01*
G03X1689777I-1197J0D01*
G01Y108539D01*
G02X1683782I-2998J0D01*
G01Y108958D01*
G03X1682607Y110133I-1175J0D01*
G01X1682112D01*
G02X1679917Y112328I0J2195D01*
G01Y120019D01*
G03X1679223Y120713I-694J0D01*
G01X1678516D01*
G03X1676886Y120038I0J-2305D01*
G01Y123188D02*
G03X1678516Y122513I1630J1630D01*
G01X1679223D01*
G02X1681717Y120019I0J-2494D01*
G01Y116349D01*
G01D02*
Y112328D01*
G03X1682112Y111933I395J0D01*
G01X1682607D01*
G02X1685582Y108958I0J-2975D01*
G01Y108539D01*
G03X1687977I1197J0D01*
G01Y109223D01*
G02X1693972I2998J0D01*
G01Y108523D01*
G03X1696367I1197J0D01*
G01Y109053D01*
G02X1702362I2998J0D01*
G01Y106519D01*
G03X1704129Y105787I1035J0D01*
G01X1706697Y108355D01*
G02X1710973Y104079I2138J-2138D01*
G01X1708277Y101383D01*
G03X1709971Y99689I847J-847D01*
G01X1713023Y102741D01*
G02X1716460I1719J-1718D01*
G01X1717798Y101402D01*
G03X1718708Y101025I910J910D01*
G01X1721687D01*
G03X1723312Y101698I0J2298D01*
G01X1723314Y101700D01*
G01X1726789Y130319D02*
X1723583D01*
X1723314Y130050D01*
G01Y126900D02*
G03X1719944Y128300I-3370J-3356D01*
G01X1715318D01*
G01X1726789Y126381D02*
X1723833D01*
X1723314Y126900D01*
G01Y98550D02*
X1722874Y98990D01*
G03X1722307Y99225I-567J-567D01*
G01X1718708D01*
G02X1716525Y100128I-1J3088D01*
G01X1715186Y101468D01*
G03X1714296I-445J-445D01*
G01X1712642Y99814D01*
G01X1871163Y13186D02*
Y12523D01*
X1871360Y12326D01*
G01X1883951Y9897D02*
X1885554Y11500D01*
X1888164D01*
X1891798Y7866D01*
X1896769D01*
X1897271Y7364D01*
Y6170D01*
X1896771Y5670D01*
X1895945D01*
G01X1883993Y13300D02*
X1888910D01*
X1892544Y9666D01*
X1900945D01*
G01X1880451Y9897D02*
Y8703D01*
X1881771Y7383D01*
X1882999D01*
G01X1880493Y13300D02*
Y14494D01*
X1881813Y15814D01*
X1883041D01*
G54D232*
G01X466300Y277700D02*
Y274942D01*
X468495Y272747D01*
X470500D01*
X471707Y271540D01*
Y270060D01*
X471463Y269816D01*
G01X467343Y259253D02*
X466101D01*
X463838Y256990D01*
X462409D01*
X460817Y255398D01*
G01X452244Y251116D02*
X450318Y249190D01*
X448889D01*
X446940Y247241D01*
X445509D01*
X443768Y245500D01*
X442084D01*
X440237Y243653D01*
X438808D01*
X436857Y241702D01*
X435426D01*
X433477Y239753D01*
X432126D01*
X430120Y237747D01*
X428748D01*
X426854Y235853D01*
X425052D01*
X423360Y237545D01*
X421854D01*
X419803Y239596D01*
X415634D01*
G01Y243496D02*
X419904D01*
X421698Y241702D01*
X423281D01*
X425230Y239753D01*
X426718D01*
X428584Y241619D01*
X430267D01*
X431989Y243341D01*
X433420D01*
X435369Y245290D01*
X436798D01*
X438749Y247241D01*
X440180D01*
X442129Y249190D01*
X443558D01*
X445509Y251141D01*
X446685D01*
X448634Y253090D01*
G01X453778Y255374D02*
X455706Y257302D01*
X457137D01*
X458776Y258941D01*
X460460D01*
X462409Y260890D01*
X463585D01*
X464947Y262252D01*
Y263975D01*
X464134Y264788D01*
Y275966D01*
X463250Y276850D01*
Y284750D01*
X462000Y286000D01*
X461400D01*
G01X466300Y277700D02*
X467100Y278500D01*
Y283572D01*
X461672Y289000D01*
X461400D01*
G01X419214Y245447D02*
X423247D01*
X425041Y243653D01*
X426973D01*
X428610Y245290D01*
X429790D01*
X432000Y247500D01*
X433679D01*
X435369Y249190D01*
X436798D01*
X438749Y251141D01*
X440180D01*
X442129Y253090D01*
X443558D01*
X445509Y255041D01*
X446940D01*
X449201Y257302D01*
X450377D01*
X452328Y259253D01*
X453757D01*
X455706Y261202D01*
X457202D01*
X459153Y263153D01*
X460517D01*
X461567Y264203D01*
Y268933D01*
X460229Y270271D01*
Y273429D01*
X461400Y274600D01*
G01X462200Y332100D02*
Y343489D01*
X464273Y345562D01*
Y346847D01*
G01X461500Y310000D02*
X462352Y309148D01*
X466652D01*
X468108Y307692D01*
X471048D01*
X472026Y308670D01*
Y322274D01*
X462200Y332100D01*
G01X464273Y342947D02*
X464961Y342259D01*
Y332139D01*
X473900Y323200D01*
Y305801D01*
X472201Y304102D01*
X469099D01*
X465518Y307683D01*
X462183D01*
X461500Y307000D01*
G01Y304000D02*
X465321D01*
X469119Y300202D01*
X471339D01*
X476048Y304911D01*
G01X456900Y333000D02*
X456500Y333400D01*
Y339141D01*
X458744Y341385D01*
Y345540D01*
X459307Y346103D01*
Y348953D01*
X457513Y350747D01*
G01X1121500Y273338D02*
Y274426D01*
X1119135Y276791D01*
X1118693D01*
X1117718Y277766D01*
Y283550D01*
X1111927Y289341D01*
X1111256D01*
G01X1113740Y274852D02*
Y278129D01*
X1111256Y280613D01*
Y282941D01*
G01X1111200Y304100D02*
X1112192D01*
X1116192Y300100D01*
X1120845D01*
X1126536Y305791D01*
X1127882D01*
X1129194Y307103D01*
Y308606D01*
X1128986Y308814D01*
Y310586D01*
X1129400Y311000D01*
Y312538D01*
X1128986Y312952D01*
Y314486D01*
X1129194Y314694D01*
G01X1125765Y326444D02*
X1124909Y327300D01*
X1123199D01*
X1120641Y329858D01*
Y339047D01*
G01X1107121Y350747D02*
X1108915Y348953D01*
Y346015D01*
X1108300Y345400D01*
Y341699D01*
X1110100Y339899D01*
Y337000D01*
X1107100Y334000D01*
X1105900D01*
G01X1111256Y307241D02*
X1112697Y305800D01*
X1116900D01*
X1118600Y304100D01*
X1121600D01*
X1122938Y305438D01*
Y323198D01*
X1114337Y331799D01*
Y342491D01*
X1113881Y342947D01*
G01X1111256Y310241D02*
X1111615Y310600D01*
X1115100D01*
X1118000Y307700D01*
X1120100D01*
X1121650Y309250D01*
Y322651D01*
X1111900Y332401D01*
Y334199D01*
G01D02*
Y343586D01*
X1113881Y345567D01*
Y346847D01*
G01X1365087Y353950D02*
Y360054D01*
X1365731Y360698D01*
G01X1362510Y360717D02*
Y357798D01*
X1360363Y355651D01*
Y353950D01*
G01X1365731Y360698D02*
X1366662Y359767D01*
Y353950D01*
G01X1354650Y349812D02*
X1352400D01*
X1350635Y351577D01*
X1348988D01*
G01X1381258Y350658D02*
X1380458D01*
X1379000Y349200D01*
Y347700D01*
X1378200Y346900D01*
G01D02*
X1376387Y345087D01*
X1373950D01*
G01X1482000Y387224D02*
X1485208D01*
X1489018Y391034D01*
X1491425D01*
G01X1524100Y494123D02*
Y493512D01*
X1520826Y490238D01*
Y486674D01*
X1522600Y484900D01*
Y483330D01*
X1520660Y481390D01*
Y480040D01*
X1522600Y478100D01*
Y476600D01*
X1520675Y474675D01*
Y470586D01*
G01X1524575D02*
Y474625D01*
X1526601Y476651D01*
Y477959D01*
X1524500Y480060D01*
Y481380D01*
X1526554Y483434D01*
Y484846D01*
X1524583Y486817D01*
Y489586D01*
G01D02*
X1527600Y492603D01*
Y494123D01*
G01X1535200D02*
Y492100D01*
X1532400Y489300D01*
Y486800D01*
X1534200Y485000D01*
Y483300D01*
X1532500Y481600D01*
Y480000D01*
X1534200Y478300D01*
Y476600D01*
X1532346Y474746D01*
Y473274D01*
X1534300Y471320D01*
Y470023D01*
X1535531Y468792D01*
X1537329D01*
X1537698Y469161D01*
X1539062D01*
X1539431Y468792D01*
X1541173D01*
X1541550Y469169D01*
X1542954D01*
X1543331Y468792D01*
X1545073D01*
X1545378Y469097D01*
X1546926D01*
X1547231Y468792D01*
X1548860D01*
X1549223Y469155D01*
X1550444D01*
X1551875Y470586D01*
G01X1531700Y494123D02*
Y492176D01*
X1528459Y488935D01*
Y486741D01*
X1530300Y484900D01*
Y483300D01*
X1528440Y481440D01*
Y480000D01*
X1530300Y478140D01*
Y476400D01*
X1528600Y474700D01*
Y473200D01*
X1530550Y471250D01*
Y469800D01*
X1532267Y468083D01*
Y466726D01*
X1533581Y465412D01*
X1535069D01*
X1535510Y465853D01*
X1537040D01*
X1537481Y465412D01*
X1538969D01*
X1539449Y465892D01*
X1540901D01*
X1541381Y465412D01*
X1542869D01*
X1543238Y465781D01*
X1544912D01*
X1545281Y465412D01*
X1546769D01*
X1546977Y465620D01*
X1548339D01*
X1549925Y467206D01*
G54D223*
G01X1067716Y65807D02*
X1067718Y65805D01*
G01X1061024Y65822D02*
X1061025Y65821D01*
G01X1067718Y54844D02*
X1067716Y54842D01*
G54D133*
X1456476Y278324D03*
Y275174D03*
X1459627Y300373D03*
Y297223D03*
X1481672Y278329D03*
Y275179D03*
X1475365Y300366D03*
Y297216D03*
X1468429Y289284D03*
Y286134D03*
X1472223Y287778D03*
Y284628D03*
X1481672Y306679D03*
Y303529D03*
X1520225Y440375D03*
Y437225D03*
X1517075Y443525D03*
Y440375D03*
X1523375D03*
Y437225D03*
X1526525Y440375D03*
Y437225D03*
X1513925Y443525D03*
Y440375D03*
X1510775Y443525D03*
Y440375D03*
X1504240Y416556D03*
Y413406D03*
X1532825Y452975D03*
Y449825D03*
X1539125Y452975D03*
Y449825D03*
X1542275Y440375D03*
Y437225D03*
X1535975Y440375D03*
Y437225D03*
X1532825Y440375D03*
Y437225D03*
X1539125Y421475D03*
Y418325D03*
X1532825Y421475D03*
Y418325D03*
G54D13*
X-16100Y25200D03*
X-16016Y45478D03*
X-15700Y35500D03*
X-15950Y55460D03*
X-8500Y25200D03*
X-8416Y45478D03*
X-8100Y35500D03*
X-8350Y55460D03*
X722268Y35902D03*
X720800Y523000D03*
X729868Y35902D03*
X751800Y213500D03*
X744200D03*
X728400Y523000D03*
X1390831Y97354D03*
X1383231D03*
X1398120Y378198D03*
Y370363D03*
X1374084Y555453D03*
X1366484D03*
X1396115Y557832D03*
X1388515D03*
X1396115Y565472D03*
X1388515D03*
X1395490Y532250D03*
X1403090D03*
X1395862Y542932D03*
X1403462D03*
X1405720Y378198D03*
Y370363D03*
X1464300Y598500D03*
X1456700D03*
X1872100Y162100D03*
X1879700D03*
X1872140Y169749D03*
X1879740D03*
X1870900Y179700D03*
X1878500D03*
X1871000Y191100D03*
X1878600D03*
G54D214*
X1899369Y237015D03*
G54D31*
X18228Y178386D03*
X-1969D03*
G54D124*
X1395512Y342485D03*
X1399012D03*
G54D151*
X1589000Y298000D03*
X1572820D03*
X1589000Y303120D03*
X1572820D03*
X1589000Y300560D03*
X1572820D03*
Y305680D03*
X1589000D03*
X1864804Y568068D03*
Y565508D03*
Y562948D03*
X1887004Y542468D03*
Y545028D03*
Y547588D03*
Y550148D03*
Y552708D03*
Y555268D03*
X1864804Y557828D03*
Y555268D03*
Y552708D03*
Y550148D03*
Y547588D03*
Y545028D03*
Y542468D03*
Y539908D03*
X1887004Y557828D03*
Y560388D03*
Y568068D03*
Y539908D03*
Y562948D03*
Y565508D03*
X1864804Y560388D03*
G54D40*
X37000Y515600D03*
X48000D03*
X1728050Y255900D03*
X1739050D03*
G54D205*
X1941937Y139548D03*
Y145452D03*
Y143484D03*
X1929937Y145452D03*
Y143484D03*
Y141516D03*
Y139548D03*
X1941937Y141516D03*
X1956376Y145503D03*
Y143535D03*
Y141567D03*
Y139599D03*
X1968376D03*
Y145503D03*
Y143535D03*
Y141567D03*
G54D160*
X1629618Y128018D03*
X1772903Y118212D03*
G54D115*
X1242459Y344788D03*
G54D106*
X1229071Y340046D03*
G54D22*
X30500Y-42250D03*
Y-52250D03*
X50500Y-42250D03*
X70500D03*
X90500D03*
X110500D03*
X50500Y-52250D03*
X70500D03*
X90500D03*
X110500D03*
X60512Y467244D03*
X130500Y-42250D03*
Y-52250D03*
X457246Y-52301D03*
Y-42301D03*
X477246Y-52301D03*
Y-42301D03*
X497246Y-52301D03*
Y-42301D03*
X517246Y-52301D03*
Y-42301D03*
X537246Y-52301D03*
Y-42301D03*
X557246Y-52301D03*
Y-42301D03*
X788984Y-52057D03*
Y-42057D03*
X808984Y-52057D03*
Y-42057D03*
X828984Y-52057D03*
Y-42057D03*
X848984Y-52057D03*
Y-42057D03*
X868984Y-52057D03*
Y-42057D03*
X888984Y-52057D03*
Y-42057D03*
X1125583Y-52285D03*
Y-42285D03*
X1145583Y-52285D03*
Y-42285D03*
X1382258Y-52257D03*
Y-42257D03*
X1402258Y-52257D03*
Y-42257D03*
X1422258Y-52257D03*
Y-42257D03*
X1442258Y-52257D03*
Y-42257D03*
X1891086Y592105D03*
X1904100Y493000D03*
G54D142*
X1526871Y23968D03*
X1809665Y618663D03*
X1819665D03*
X1829665D03*
X1881595Y23968D03*
G54D242*
G01X1868286Y12848D02*
X1871237Y9897D01*
X1876951D01*
G01X1871360Y12326D02*
X1871985Y11701D01*
X1875394D01*
X1876993Y13300D01*
G54D233*
G01X528491Y360496D02*
X527337Y359831D01*
X526985Y359926D01*
G03X525181Y360872I-1873J-1379D01*
G01X525052D01*
G02X523746Y361659I59J1575D01*
G03X521816Y362821I-2015J-1163D01*
G01X521731D01*
G02X520380Y363586I0J1575D01*
G01X520367Y363609D01*
G03X518422Y364772I-2015J-1162D01*
G01X518293D01*
G02X516987Y365559I59J1575D01*
G03X515057Y366721I-2015J-1163D01*
G01X514928D01*
G02X513607Y369084I44J1575D01*
G03Y371410I-2015J1163D01*
G02Y372984I1365J787D01*
G01X513632Y373026D01*
G03X513607Y375309I-2040J1119D01*
G01X513588Y375343D01*
G02X513607Y376884I1384J754D01*
G03X513632Y379167I-2015J1164D01*
G01X513607Y379209D01*
X513588Y379243D01*
G02X513607Y380784I1384J754D01*
G03X513632Y383067I-2015J1164D01*
G01X513607Y383109D01*
X513588Y383143D01*
G02X513607Y384684I1384J754D01*
G03X513632Y386967I-2015J1164D01*
G01X513607Y387009D01*
X513588Y387043D01*
G02X513607Y388584I1384J754D01*
G03X513632Y390867I-2015J1164D01*
G01X513607Y390909D01*
X513588Y390943D01*
G02X513607Y392484I1384J754D01*
G03Y394810I-2015J1163D01*
G02Y396384I1365J787D01*
G01X513632Y396426D01*
G03X513607Y398709I-2040J1119D01*
G01X513588Y398743D01*
G02X513607Y400284I1384J754D01*
G03X513632Y402567I-2015J1164D01*
G01X513607Y402609D01*
X513588Y402643D01*
G02X513607Y404184I1384J754D01*
G03X513896Y405849I-2123J1226D01*
G01X513814Y406299D01*
X513550Y406813D01*
Y407513D01*
X513940Y407903D01*
Y408603D01*
X513550Y408993D01*
Y409693D01*
X513940Y410083D01*
Y410783D01*
X513550Y411173D01*
Y414368D01*
X511400Y416518D01*
Y418000D01*
X511500Y418100D01*
Y418187D01*
G01X525111Y358547D02*
X526265Y359212D01*
X526348Y359522D01*
G03X525155Y360122I-1238J-975D01*
G01X525026D01*
G02X523096Y361284I85J2325D01*
G03X521790Y362071I-1365J-788D01*
G01X521661D01*
G02X519716Y363234I70J2325D01*
G01X519703Y363257D01*
G03X518352Y364022I-1351J-810D01*
G01X518267D01*
G02X516337Y365184I85J2325D01*
G03X515031Y365971I-1365J-788D01*
G01X514902D01*
G02X512957Y369459I70J2325D01*
G03X512976Y371000I-1365J787D01*
G01X512957Y371034D01*
G02X512932Y373317I2015J1164D01*
G01X512957Y373359D01*
G03Y374933I-1365J787D01*
G02Y377259I2015J1163D01*
G03X512976Y378800I-1365J787D01*
G01X512957Y378834D01*
X512932Y378876D01*
G02X512957Y381159I2040J1119D01*
G03X512976Y382700I-1365J787D01*
G01X512957Y382734D01*
X512932Y382776D01*
G02X512957Y385059I2040J1119D01*
G03X512976Y386600I-1365J787D01*
G01X512957Y386634D01*
X512932Y386676D01*
G02X512957Y388959I2040J1119D01*
G03X512976Y390500I-1365J787D01*
G01X512957Y390534D01*
X512932Y390576D01*
G02X512957Y392859I2040J1119D01*
G03X512976Y394400I-1365J787D01*
G01X512957Y394434D01*
G02X512932Y396717I2015J1164D01*
G01X512957Y396759D01*
G03Y398333I-1365J787D01*
G02Y400659I2015J1163D01*
G03X512976Y402200I-1365J787D01*
G01X512957Y402234D01*
X512932Y402276D01*
G02X512957Y404559I2040J1119D01*
G01X512958Y404560D01*
G03X513158Y405715I-1475J850D01*
G01X513096Y406055D01*
X512800Y406631D01*
Y414057D01*
X510650Y416207D01*
Y418000D01*
X510550Y418100D01*
Y418187D01*
G01X525111Y370247D02*
Y368916D01*
X525339Y368688D01*
G03X525182Y371821I-227J1559D01*
G01X525041D01*
G02X523096Y372984I70J2325D01*
G03X521802Y373771I-1365J-787D01*
G01X521646D01*
G02X519716Y377260I85J2325D01*
G03Y378834I-1364J787D01*
G01X519681Y378894D01*
G02X519716Y381160I2050J1102D01*
G03Y382734I-1364J787D01*
G01X519681Y382794D01*
G02X519716Y385060I2050J1102D01*
G03Y386634I-1364J787D01*
G01X519681Y386694D01*
G02X519716Y388960I2050J1102D01*
G03Y390534I-1364J787D01*
G01X519681Y390594D01*
G02X519716Y392860I2050J1102D01*
G03Y394434I-1364J787D01*
G02X519691Y396717I2015J1164D01*
G03X519717Y398335I-1337J831D01*
G02X519692Y400618I2015J1164D01*
G01X519717Y400660D01*
X519736Y400694D01*
G03X519717Y402235I-1384J754D01*
G02X519869Y404787I2011J1161D01*
G01X519946Y404889D01*
Y407232D01*
X519556Y407622D01*
Y408322D01*
X519946Y408712D01*
Y409412D01*
X519556Y409802D01*
Y410502D01*
X519946Y410892D01*
Y411592D01*
X519556Y411982D01*
Y412682D01*
X519946Y413072D01*
Y417493D01*
X518352Y419087D01*
Y420552D01*
X518252Y420652D01*
Y420739D01*
G01X531871Y370247D02*
X530717Y369581D01*
X530407Y369665D01*
G02X530487Y371000I1465J582D01*
G01X530506Y371034D01*
G03X530531Y373317I-2015J1164D01*
G01X530506Y373359D01*
G02Y374933I1365J787D01*
G03Y377259I-2015J1163D01*
G02X530487Y378800I1365J787D01*
G01X530506Y378834D01*
X530531Y378876D01*
G03X530506Y381159I-2040J1119D01*
G02X530487Y382700I1365J787D01*
G01X530506Y382734D01*
X530531Y382776D01*
G03X530506Y385059I-2040J1119D01*
G02X530487Y386600I1365J787D01*
G01X530506Y386634D01*
X530531Y386676D01*
G03X530506Y388959I-2040J1119D01*
G02X530487Y390500I1365J787D01*
G01X530506Y390534D01*
X530531Y390576D01*
G03X530506Y392859I-2040J1119D01*
G02X530487Y394400I1365J787D01*
G01X530506Y394434D01*
G03X530531Y396717I-2015J1164D01*
G01X530506Y396759D01*
G02Y398333I1365J787D01*
G03Y400659I-2015J1163D01*
G02X530487Y402200I1365J787D01*
G01X530506Y402234D01*
X530531Y402276D01*
G03X530506Y404559I-2040J1119D01*
G02Y406135I1365J788D01*
G01X531528Y407906D01*
Y408606D01*
X531918Y408996D01*
Y409696D01*
X531528Y410086D01*
Y418257D01*
X531628Y418357D01*
Y418444D01*
G01X525111Y362447D02*
X523863Y363463D01*
G03X521816Y366721I-2132J933D01*
G01X521731D01*
G02X520380Y367486I0J1575D01*
G01X520367Y367509D01*
G03X518422Y368672I-2015J-1162D01*
G01X518293D01*
G02X516968Y371000I59J1575D01*
G01X516987Y371034D01*
G03X517012Y373317I-2015J1164D01*
G01X516987Y373359D01*
G02Y374933I1365J787D01*
G03Y377259I-2015J1163D01*
G02X516968Y378800I1365J787D01*
G01X516987Y378834D01*
X517012Y378876D01*
G03X516987Y381159I-2040J1119D01*
G02X516968Y382700I1365J787D01*
G01X516987Y382734D01*
X517012Y382776D01*
G03X516987Y385059I-2040J1119D01*
G02X516968Y386600I1365J787D01*
G01X516987Y386634D01*
X517012Y386676D01*
G03X516987Y388959I-2040J1119D01*
G02X516968Y390500I1365J787D01*
G01X516987Y390534D01*
X517012Y390576D01*
G03X516987Y392859I-2040J1119D01*
G02X516968Y394400I1365J787D01*
G01X516987Y394434D01*
G03X517012Y396717I-2015J1164D01*
G01X516987Y396759D01*
G02Y398333I1365J787D01*
G03Y400659I-2015J1163D01*
G02X516968Y402200I1365J787D01*
G01X516987Y402234D01*
X517012Y402276D01*
G03X516987Y404559I-2040J1119D01*
G01X516700Y405056D01*
Y406982D01*
X517100Y407949D01*
Y416400D01*
X515250Y418250D01*
Y420363D01*
X515350Y420463D01*
Y420550D01*
G01X528491Y356596D02*
X529645Y355931D01*
X529955Y356015D01*
G03X529856Y357384I-1465J582D01*
G02X529831Y359667I2015J1164D01*
G01X529856Y359709D01*
X529875Y359743D01*
G03X529856Y361284I-1384J754D01*
G02X529831Y363567I2015J1164D01*
G01X529856Y363609D01*
X529875Y363643D01*
G03X529856Y365184I-1384J754D01*
G02X531801Y368672I2015J1163D01*
G01X531930D01*
G03X533255Y371000I-59J1575D01*
G01X533236Y371034D01*
G02X533211Y373317I2015J1164D01*
G01X533236Y373359D01*
G03Y374933I-1365J787D01*
G02Y377259I2015J1163D01*
G03X533255Y378800I-1365J787D01*
G01X533236Y378834D01*
X533211Y378876D01*
G02X533236Y381159I2040J1119D01*
G03X533255Y382700I-1365J787D01*
G01X533236Y382734D01*
X533211Y382776D01*
G02X533236Y385059I2040J1119D01*
G03X533255Y386600I-1365J787D01*
G01X533236Y386634D01*
X533211Y386676D01*
G02X533236Y388959I2040J1119D01*
G03X533255Y390500I-1365J787D01*
G01X533236Y390534D01*
X533211Y390576D01*
G02X533236Y392859I2040J1119D01*
G03X533255Y394400I-1365J787D01*
G01X533236Y394434D01*
G02X533211Y396717I2015J1164D01*
G01X533236Y396759D01*
G03Y398333I-1365J787D01*
G02Y400659I2015J1163D01*
G03Y402235I-1365J788D01*
G02Y404559I2013J1162D01*
G01X534723Y407135D01*
Y411322D01*
X534333Y411712D01*
Y412412D01*
X534723Y412802D01*
Y413502D01*
X534333Y413892D01*
Y414592D01*
X534723Y414982D01*
Y417064D01*
X534623Y417164D01*
Y417251D01*
G01X525111Y378047D02*
X523957Y377381D01*
X523647Y377465D01*
G02X523727Y378800I1465J582D01*
G01X523746Y378834D01*
X523771Y378876D01*
G03X523746Y381159I-2040J1119D01*
G02X523727Y382700I1365J787D01*
G01X523746Y382734D01*
X523771Y382776D01*
G03X523746Y385059I-2040J1119D01*
G02X523727Y386600I1365J787D01*
G01X523746Y386634D01*
X523771Y386676D01*
G03X523746Y388959I-2040J1119D01*
G02X523727Y390500I1365J787D01*
G01X523746Y390534D01*
X523771Y390576D01*
G03X523746Y392859I-2040J1119D01*
G02X523727Y394400I1365J787D01*
G01X523746Y394434D01*
G03X523771Y396717I-2015J1164D01*
G01X523746Y396759D01*
G02Y398333I1365J787D01*
G03Y400659I-2015J1163D01*
G02X523727Y402200I1365J787D01*
G01X523746Y402234D01*
X523771Y402276D01*
G03X523746Y404559I-2040J1119D01*
G02Y406135I1365J788D01*
G01X523745D01*
X524148Y406832D01*
X524300Y406984D01*
Y407291D01*
X524298Y407293D01*
Y407993D01*
X524688Y408383D01*
Y409083D01*
X524298Y409473D01*
Y419164D01*
X523000Y420462D01*
Y421529D01*
X523100Y421629D01*
Y421716D01*
G01X525111Y374146D02*
X525768Y373768D01*
X526265Y373481D01*
X526575Y373565D01*
G03X526476Y374933I-1464J582D01*
G02Y377259I2015J1163D01*
G03X526495Y378800I-1365J787D01*
G01X526476Y378834D01*
X526451Y378876D01*
G02X526476Y381159I2040J1119D01*
G03X526495Y382700I-1365J787D01*
G01X526476Y382734D01*
X526451Y382776D01*
G02X526476Y385059I2040J1119D01*
G03X526495Y386600I-1365J787D01*
G01X526476Y386634D01*
X526451Y386676D01*
G02X526476Y388959I2040J1119D01*
G03X526495Y390500I-1365J787D01*
G01X526476Y390534D01*
X526451Y390576D01*
G02X526476Y392859I2040J1119D01*
G03X526495Y394400I-1365J787D01*
G01X526476Y394434D01*
G02X526451Y396717I2015J1164D01*
G01X526476Y396759D01*
G03Y398333I-1365J787D01*
G02Y400659I2015J1163D01*
G03X526495Y402200I-1365J787D01*
G01X526476Y402234D01*
X526451Y402276D01*
G02X526476Y404559I2040J1119D01*
G01X527100Y405640D01*
Y409948D01*
X526710Y410338D01*
Y411038D01*
X527100Y411428D01*
Y420289D01*
X526173Y421216D01*
Y422873D01*
X526073Y422973D01*
Y423060D01*
G01X519202Y420739D02*
Y420652D01*
X519102Y420552D01*
Y419398D01*
X520696Y417804D01*
Y404639D01*
X520470Y404337D01*
G03X520367Y402610I1258J-942D01*
G02X520392Y400327I-2015J-1164D01*
G01X520367Y400285D01*
X520348Y400251D01*
G03X520367Y398710I1384J-754D01*
G02X520392Y396426I-2019J-1164D01*
G01X520367Y396384D01*
G03Y394810I1364J-787D01*
G01X520392Y394768D01*
G02X520367Y392483I-2040J-1120D01*
G03Y390909I1364J-787D01*
G01X520402Y390849D01*
G02X520367Y388583I-2050J-1102D01*
G03Y387009I1364J-787D01*
G01X520402Y386949D01*
G02X520367Y384683I-2050J-1102D01*
G03Y383109I1364J-787D01*
G01X520402Y383049D01*
G02X520367Y380783I-2050J-1102D01*
G03Y379209I1364J-787D01*
G01X520402Y379149D01*
G02X520367Y376883I-2050J-1102D01*
G03X521683Y374522I1364J-787D01*
G01X521801D01*
G02X523746Y373359I-70J-2325D01*
G03X525040Y372572I1365J787D01*
G01X525196D01*
G02X525367Y367934I-84J-2325D01*
G01X525111Y367678D01*
Y366347D01*
G01X528491Y368296D02*
X529645Y368962D01*
X529739Y369314D01*
G02X529856Y371410I2132J932D01*
G03Y372984I-1365J787D01*
G01X529831Y373026D01*
G02X529856Y375309I2040J1119D01*
G01X529875Y375343D01*
G03X529856Y376884I-1384J754D01*
G02X529831Y379167I2015J1164D01*
G01X529856Y379209D01*
X529875Y379243D01*
G03X529856Y380784I-1384J754D01*
G02X529831Y383067I2015J1164D01*
G01X529856Y383109D01*
X529875Y383143D01*
G03X529856Y384684I-1384J754D01*
G02X529831Y386967I2015J1164D01*
G01X529856Y387009D01*
X529875Y387043D01*
G03X529856Y388584I-1384J754D01*
G02X529831Y390867I2015J1164D01*
G01X529856Y390909D01*
X529875Y390943D01*
G03X529856Y392484I-1384J754D01*
G02Y394810I2015J1163D01*
G03Y396384I-1365J787D01*
G01X529831Y396426D01*
G02X529856Y398709I2040J1119D01*
G01X529875Y398743D01*
G03X529856Y400284I-1384J754D01*
G02X529831Y402567I2015J1164D01*
G01X529856Y402609D01*
X529875Y402643D01*
G03X529856Y404184I-1384J754D01*
G02Y406510I2015J1163D01*
G01X530778Y408107D01*
Y418257D01*
X530678Y418357D01*
Y418444D01*
G01X521731Y364396D02*
X523195Y363815D01*
G03X521790Y365971I-1465J581D01*
G01X521661D01*
G02X519716Y367134I70J2325D01*
G01X519703Y367157D01*
G03X518352Y367922I-1351J-810D01*
G01X518267D01*
G02X516337Y371410I85J2325D01*
G03Y372984I-1365J787D01*
G01X516312Y373026D01*
G02X516337Y375309I2040J1119D01*
G01X516356Y375343D01*
G03X516337Y376884I-1384J754D01*
G02X516312Y379167I2015J1164D01*
G01X516337Y379209D01*
X516356Y379243D01*
G03X516337Y380784I-1384J754D01*
G02X516312Y383067I2015J1164D01*
G01X516337Y383109D01*
X516356Y383143D01*
G03X516337Y384684I-1384J754D01*
G02X516312Y386967I2015J1164D01*
G01X516337Y387009D01*
X516356Y387043D01*
G03X516337Y388584I-1384J754D01*
G02X516312Y390867I2015J1164D01*
G01X516337Y390909D01*
X516356Y390943D01*
G03X516337Y392484I-1384J754D01*
G02Y394810I2015J1163D01*
G03Y396384I-1365J787D01*
G01X516312Y396426D01*
G02X516337Y398709I2040J1119D01*
G01X516356Y398743D01*
G03X516337Y400284I-1384J754D01*
G02X516312Y402567I2015J1164D01*
G01X516337Y402609D01*
X516356Y402643D01*
G03X516337Y404184I-1384J754D01*
G01X515950Y404854D01*
Y407131D01*
X516350Y408098D01*
Y408798D01*
X515960Y409188D01*
Y409888D01*
X516350Y410278D01*
Y416089D01*
X514500Y417939D01*
Y420363D01*
X514400Y420463D01*
Y420550D01*
G01X535573Y417251D02*
Y417164D01*
X535473Y417064D01*
Y406934D01*
X533886Y404183D01*
G03Y402610I1364J-786D01*
G02Y400284I-2017J-1163D01*
G03X533867Y398743I1365J-787D01*
G01X533886Y398709D01*
G02X533911Y396426I-2015J-1164D01*
G01X533886Y396384D01*
G03Y394810I1365J-787D01*
G02Y392484I-2015J-1163D01*
G03X533867Y390943I1365J-787D01*
G01X533886Y390909D01*
X533911Y390867D01*
G02X533886Y388584I-2040J-1119D01*
G03X533867Y387043I1365J-787D01*
G01X533886Y387009D01*
X533911Y386967D01*
G02X533886Y384684I-2040J-1119D01*
G03X533867Y383143I1365J-787D01*
G01X533886Y383109D01*
X533911Y383067D01*
G02X533886Y380784I-2040J-1119D01*
G03X533867Y379243I1365J-787D01*
G01X533886Y379209D01*
X533911Y379167D01*
G02X533886Y376884I-2040J-1119D01*
G03X533867Y375343I1365J-787D01*
G01X533886Y375309D01*
G02X533911Y373026I-2015J-1164D01*
G01X533886Y372984D01*
G03Y371410I1365J-787D01*
G02X531956Y367922I-2015J-1163D01*
G01X531827D01*
G03X530506Y365559I44J-1575D01*
G02X530531Y363276I-2015J-1164D01*
G01X530506Y363234D01*
X530487Y363200D01*
G03X530506Y361659I1384J-754D01*
G02X530531Y359376I-2015J-1164D01*
G01X530506Y359334D01*
X530487Y359300D01*
G03X530506Y357759I1384J-754D01*
G02X530623Y355663I-2015J-1164D01*
G01X530717Y355312D01*
X531871Y354647D01*
G01X522150Y421716D02*
Y421629D01*
X522250Y421529D01*
Y420151D01*
X523548Y418853D01*
Y407293D01*
X523096Y406511D01*
G03Y404184I2015J-1164D01*
G02X523115Y402643I-1365J-787D01*
G01X523096Y402609D01*
X523071Y402567D01*
G03X523096Y400284I2040J-1119D01*
G02X523115Y398743I-1365J-787D01*
G01X523096Y398709D01*
G03X523071Y396426I2015J-1164D01*
G01X523096Y396384D01*
G02Y394810I-1365J-787D01*
G03Y392484I2015J-1163D01*
G02X523115Y390943I-1365J-787D01*
G01X523096Y390909D01*
X523071Y390867D01*
G03X523096Y388584I2040J-1119D01*
G02X523115Y387043I-1365J-787D01*
G01X523096Y387009D01*
X523071Y386967D01*
G03X523096Y384684I2040J-1119D01*
G02X523115Y383143I-1365J-787D01*
G01X523096Y383109D01*
X523071Y383067D01*
G03X523096Y380784I2040J-1119D01*
G02X523115Y379243I-1365J-787D01*
G01X523096Y379209D01*
X523071Y379167D01*
G03X522979Y377114I2039J-1120D01*
G01X522885Y376762D01*
X521731Y376096D01*
G01X528491Y372197D02*
X527337Y372862D01*
X527243Y373213D01*
G03X527126Y375309I-2132J932D01*
G01X527107Y375343D01*
G02X527126Y376884I1384J754D01*
G03X527151Y379167I-2015J1164D01*
G01X527126Y379209D01*
X527107Y379243D01*
G02X527126Y380784I1384J754D01*
G03X527151Y383067I-2015J1164D01*
G01X527126Y383109D01*
X527107Y383143D01*
G02X527126Y384684I1384J754D01*
G03X527151Y386967I-2015J1164D01*
G01X527126Y387009D01*
X527107Y387043D01*
G02X527126Y388584I1384J754D01*
G03X527151Y390867I-2015J1164D01*
G01X527126Y390909D01*
X527107Y390943D01*
G02X527126Y392484I1384J754D01*
G03Y394810I-2015J1163D01*
G02Y396384I1365J787D01*
G01X527151Y396426D01*
G03X527126Y398709I-2040J1119D01*
G01X527107Y398743D01*
G02X527126Y400284I1384J754D01*
G03X527151Y402567I-2015J1164D01*
G01X527126Y402609D01*
X527107Y402643D01*
G02X527126Y404184I1384J754D01*
G01X527850Y405439D01*
Y420600D01*
X526923Y421527D01*
Y422873D01*
X527023Y422973D01*
Y423060D01*
G01X542011Y379996D02*
X543165Y380662D01*
X543259Y381014D01*
G02X545321Y384272I2131J933D01*
G01X545450D01*
G03X546756Y385059I-59J1575D01*
G02X548686Y386221I2015J-1163D01*
G01X548856D01*
G02X550786Y385059I-85J-2325D01*
G03X552092Y384272I1365J788D01*
G01X552221D01*
G02X554166Y383109I-70J-2325D01*
G03X555487Y382321I1365J787D01*
G01X556331D01*
G02X557703Y381148I-800J-2325D01*
G03X559060Y380331I1357J719D01*
G01X560579D01*
X561550Y379360D01*
Y354533D01*
X560925Y353452D01*
G03X560926Y351910I1332J-770D01*
G02X560951Y349627I-2015J-1164D01*
G01X560926Y349585D01*
X560907Y349551D01*
G03X560926Y348010I1384J-754D01*
G02Y345684I-2017J-1163D01*
G03X560907Y344143I1365J-787D01*
G01X560926Y344109D01*
X560951Y344067D01*
G02X560926Y341784I-2040J-1119D01*
G03X560907Y340243I1365J-787D01*
G01X560926Y340209D01*
X560951Y340167D01*
G02X558996Y336722I-2040J-1120D01*
G01X558867D01*
G03X557546Y335934I44J-1575D01*
G02X555601Y334771I-2015J1162D01*
G01X555472D01*
G03X554166Y333984I59J-1575D01*
G02X552236Y332822I-2015J1163D01*
G01X552107D01*
G03X550786Y332034I44J-1575D01*
G02X548841Y330871I-2015J1162D01*
G01X548712D01*
G03X547406Y330084I59J-1575D01*
G02X545476Y328922I-2015J1163D01*
G01X545347D01*
G03X544026Y328134I44J-1575D01*
G02X542081Y326971I-2015J1162D01*
G01X541952D01*
G03X540646Y326184I59J-1575D01*
G02X538682Y325021I-2015J1163D01*
G01X538587D01*
G03X537266Y324233I44J-1575D01*
G02X535336Y323071I-2015J1163D01*
G01X535207D01*
G03X533886Y322283I44J-1575D01*
G02X531956Y321121I-2015J1163D01*
G01X531786D01*
G02X529856Y322283I85J2325D01*
G03X528535Y323071I-1365J-787D01*
G01X528406D01*
G02X526476Y324233I85J2325D01*
G03X525155Y325021I-1365J-787D01*
G01X525060D01*
G02X523096Y326184I51J2326D01*
G03X521790Y326971I-1365J-788D01*
G01X521661D01*
G02X519716Y328134I70J2325D01*
G01X519703Y328157D01*
G03X518352Y328922I-1351J-810D01*
G01X518267D01*
G02X516337Y330084I85J2325D01*
G03X515031Y330871I-1365J-788D01*
G01X514902D01*
G02X512957Y332034I70J2325D01*
G03X511636Y332822I-1365J-787D01*
G01X511507D01*
G02X509577Y333984I85J2325D01*
G03X508271Y334771I-1365J-788D01*
G01X508142D01*
G02X506197Y335934I70J2325D01*
G03X504876Y336722I-1365J-787D01*
G01X504747D01*
G02X502817Y337884I85J2325D01*
G03X501511Y338671I-1365J-788D01*
G01X501382D01*
G02X499437Y339834I70J2325D01*
G03X498116Y340622I-1365J-787D01*
G01X497987D01*
G02X496057Y341784I85J2325D01*
G03X494751Y342571I-1365J-788D01*
G01X494622D01*
G02X492677Y343734I70J2325D01*
G03X491356Y344522I-1365J-787D01*
G01X491227D01*
G02X489297Y345684I85J2325D01*
G03X487991Y346471I-1365J-788D01*
G01X487862D01*
G02X485917Y349959I70J2325D01*
G03X485936Y351500I-1365J787D01*
G01X485917Y351534D01*
X485892Y351576D01*
G02X485917Y353859I2040J1119D01*
G03X485936Y355400I-1365J787D01*
G01X485917Y355434D01*
X485892Y355476D01*
G02X485917Y357759I2040J1119D01*
G03X485936Y359300I-1365J787D01*
G01X485917Y359334D01*
X485892Y359376D01*
G02X485917Y361659I2040J1119D01*
G03X485936Y363200I-1365J787D01*
G01X485917Y363234D01*
X485892Y363276D01*
G02X485917Y365559I2040J1119D01*
G03X485936Y367100I-1365J787D01*
G01X485917Y367134D01*
X485892Y367176D01*
G02X485917Y369459I2040J1119D01*
G03X485936Y371000I-1365J787D01*
G01X485917Y371034D01*
G02X485892Y373317I2015J1164D01*
G01X485917Y373359D01*
G03Y374933I-1365J787D01*
G02Y377259I2015J1163D01*
G03X485936Y378800I-1365J787D01*
G01X485917Y378834D01*
X485892Y378876D01*
G02X485917Y381159I2040J1119D01*
G03X485936Y382700I-1365J787D01*
G01X485917Y382734D01*
X485892Y382776D01*
G02X485917Y385059I2040J1119D01*
G03X485936Y386600I-1365J787D01*
G01X485917Y386634D01*
X485892Y386676D01*
G02X485917Y388959I2040J1119D01*
G03X485936Y390500I-1365J787D01*
G01X485917Y390534D01*
X485892Y390576D01*
G02X485917Y392859I2040J1119D01*
G03X485936Y394400I-1365J787D01*
G01X485675Y394856D01*
X484713Y395866D01*
X483367Y396662D01*
X470389Y409640D01*
X467762Y410327D01*
X467049Y410465D01*
X466934Y410386D01*
X466849Y410402D01*
G01X545391Y381947D02*
X544237Y381281D01*
X543927Y381365D01*
G02X545347Y383522I1465J582D01*
G01X545476D01*
G03X547406Y384684I-85J2325D01*
G02X548712Y385471I1365J-788D01*
G01X548830D01*
G02X550136Y384684I-59J-1575D01*
G03X552066Y383522I2015J1163D01*
G01X552195D01*
G02X553516Y382734I-44J-1575D01*
G03X555461Y381571I2015J1162D01*
G01X556193D01*
G02X557040Y380796I-663J-1575D01*
G03X559059Y379581I2020J1071D01*
G01X560268D01*
X560800Y379049D01*
Y377472D01*
X560402Y377074D01*
Y376374D01*
X560800Y375976D01*
Y373125D01*
X560460Y372785D01*
Y372085D01*
X560800Y371745D01*
Y369370D01*
X560460Y369030D01*
Y368330D01*
X560800Y367990D01*
Y365210D01*
X560460Y364870D01*
Y364170D01*
X560800Y363830D01*
Y363130D01*
X560460Y362790D01*
Y362090D01*
X560800Y361750D01*
Y361050D01*
X560460Y360710D01*
Y360010D01*
X560800Y359670D01*
Y358970D01*
X560460Y358630D01*
Y357930D01*
X560800Y357590D01*
Y354735D01*
X560275Y353827D01*
G03X560276Y351535I1981J-1145D01*
G02X560295Y349994I-1365J-787D01*
G01X560276Y349960D01*
X560251Y349918D01*
G03X560276Y347635I2040J-1119D01*
G02Y346059I-1364J-788D01*
G03X560251Y343776I2015J-1164D01*
G01X560276Y343734D01*
X560295Y343700D01*
G02X560276Y342159I-1384J-754D01*
G03X560251Y339876I2015J-1164D01*
G01X560276Y339834D01*
X560295Y339800D01*
G02X558970Y337472I-1384J-753D01*
G01X558841D01*
G03X556896Y336309I70J-2325D01*
G02X555575Y335521I-1365J787D01*
G01X555446D01*
G03X553516Y334359I85J-2325D01*
G02X552210Y333572I-1365J788D01*
G01X552081D01*
G03X550136Y332409I70J-2325D01*
G02X548815Y331621I-1365J787D01*
G01X548686D01*
G03X546756Y330459I85J-2325D01*
G02X545450Y329672I-1365J788D01*
G01X545321D01*
G03X543376Y328509I70J-2325D01*
G02X542055Y327721I-1365J787D01*
G01X541926D01*
G03X539996Y326559I85J-2325D01*
G02X538690Y325772I-1365J788D01*
G01X538580D01*
G03X536616Y324609I51J-2326D01*
G02X535295Y323821I-1365J787D01*
G01X535166D01*
G03X533236Y322659I85J-2325D01*
G02X531942Y321872I-1365J787D01*
G01X531800D01*
G02X530506Y322659I71J1574D01*
G03X528576Y323821I-2015J-1163D01*
G01X528447D01*
G02X527126Y324609I44J1575D01*
G03X525162Y325772I-2015J-1163D01*
G01X525052D01*
G02X523746Y326559I59J1575D01*
G03X521816Y327721I-2015J-1163D01*
G01X521731D01*
G02X520380Y328486I0J1575D01*
G01X520367Y328509D01*
G03X518422Y329672I-2015J-1162D01*
G01X518293D01*
G02X516987Y330459I59J1575D01*
G03X515057Y331621I-2015J-1163D01*
G01X514928D01*
G02X513607Y332409I44J1575D01*
G03X511662Y333572I-2015J-1162D01*
G01X511533D01*
G02X510227Y334359I59J1575D01*
G03X508297Y335521I-2015J-1163D01*
G01X508168D01*
G02X506847Y336309I44J1575D01*
G03X504902Y337472I-2015J-1162D01*
G01X504773D01*
G02X503467Y338259I59J1575D01*
G03X501537Y339421I-2015J-1163D01*
G01X501408D01*
G02X500087Y340209I44J1575D01*
G03X498142Y341372I-2015J-1162D01*
G01X498013D01*
G02X496707Y342159I59J1575D01*
G03X494777Y343321I-2015J-1163D01*
G01X494648D01*
G02X493327Y344109I44J1575D01*
G03X491382Y345272I-2015J-1162D01*
G01X491253D01*
G02X489947Y346059I59J1575D01*
G03X488017Y347221I-2015J-1163D01*
G01X487888D01*
G02X486567Y349584I44J1575D01*
G03X486592Y351867I-2015J1164D01*
G01X486567Y351909D01*
X486548Y351943D01*
G02X486567Y353484I1384J754D01*
G03X486592Y355767I-2015J1164D01*
G01X486567Y355809D01*
X486548Y355843D01*
G02X486567Y357384I1384J754D01*
G03X486592Y359667I-2015J1164D01*
G01X486567Y359709D01*
X486548Y359743D01*
G02X486567Y361284I1384J754D01*
G03X486592Y363567I-2015J1164D01*
G01X486567Y363609D01*
X486548Y363643D01*
G02X486567Y365184I1384J754D01*
G03X486592Y367467I-2015J1164D01*
G01X486567Y367509D01*
X486548Y367543D01*
G02X486567Y369084I1384J754D01*
G03Y371410I-2015J1163D01*
G02Y372984I1365J787D01*
G01X486592Y373026D01*
G03X486567Y375309I-2040J1119D01*
G01X486548Y375343D01*
G02X486567Y376884I1384J754D01*
G03X486592Y379167I-2015J1164D01*
G01X486567Y379209D01*
X486548Y379243D01*
G02X486567Y380784I1384J754D01*
G03X486592Y383067I-2015J1164D01*
G01X486567Y383109D01*
X486548Y383143D01*
G02X486567Y384684I1384J754D01*
G03X486592Y386967I-2015J1164D01*
G01X486567Y387009D01*
X486548Y387043D01*
G02X486567Y388584I1384J754D01*
G03X486592Y390867I-2015J1164D01*
G01X486567Y390909D01*
X486548Y390943D01*
G02X486567Y392484I1384J754D01*
G03Y394810I-2015J1163D01*
G01X486281Y395309D01*
X485184Y396459D01*
X483831Y397260D01*
X483283Y397808D01*
Y398372D01*
X482788Y398867D01*
X482224D01*
X481730Y399361D01*
Y399925D01*
X481235Y400420D01*
X480671D01*
X480177Y400914D01*
Y401478D01*
X479682Y401973D01*
X479118D01*
X478624Y402467D01*
Y402948D01*
X478128Y403444D01*
X477647D01*
X477153Y403938D01*
Y404419D01*
X476657Y404915D01*
X476176D01*
X475682Y405409D01*
Y405890D01*
X475186Y406386D01*
X474705D01*
X474211Y406880D01*
Y407361D01*
X473715Y407857D01*
X473234D01*
X470776Y410315D01*
X467930Y411059D01*
X467194Y411202D01*
X467115Y411319D01*
X467030Y411335D01*
G01X552151Y374146D02*
G02X550017Y373709I-1133J102D01*
G03X548727Y374520I-1359J-731D01*
G01Y374521D01*
G02X547406Y375309I44J1575D01*
G03X543351Y373026I-2015J-1163D01*
G01X543376Y372984D01*
G02Y371410I-1365J-787D01*
G03Y369084I2015J-1163D01*
G02X543395Y367543I-1365J-787D01*
G01X543376Y367509D01*
X543351Y367467D01*
G03X543376Y365184I2040J-1119D01*
G02X542055Y362821I-1365J-788D01*
G01X541926D01*
G03X539971Y359376I85J-2325D01*
G01X539996Y359334D01*
X540015Y359300D01*
G02X539996Y357759I-1384J-754D01*
G03X539971Y355476I2015J-1164D01*
G01X539996Y355434D01*
X540015Y355400D01*
G02X539996Y353859I-1384J-754D01*
G03X539971Y351576I2015J-1164D01*
G01X539996Y351534D01*
X540015Y351500D01*
G02X538690Y349172I-1384J-753D01*
G01X538561D01*
G03X536616Y348009I70J-2325D01*
G02X535295Y347221I-1365J787D01*
G01X535166D01*
G03X533236Y346059I85J-2325D01*
G02X531930Y345272I-1365J788D01*
G01X531812D01*
G02X530506Y346059I59J1575D01*
G03X528576Y347221I-2015J-1163D01*
G01X528447D01*
G02X527126Y348009I44J1575D01*
G03X525181Y349172I-2015J-1162D01*
G01X525052D01*
G02X523746Y349959I59J1575D01*
G03X521816Y351121I-2015J-1163D01*
G01X521731D01*
G02X520380Y351886I0J1575D01*
G01X520367Y351909D01*
G03X518422Y353072I-2015J-1162D01*
G01X518293D01*
G02X516987Y353859I59J1575D01*
G03X515057Y355021I-2015J-1163D01*
G01X514928D01*
G02X513607Y355809I44J1575D01*
G03X511662Y356972I-2015J-1162D01*
G01X511533D01*
G02X510227Y357759I59J1575D01*
G03X508297Y358921I-2015J-1163D01*
G01X508168D01*
G02X506847Y361284I44J1575D01*
G03X506872Y363567I-2015J1164D01*
G01X506847Y363609D01*
X506828Y363643D01*
G02X506847Y365184I1384J754D01*
G03X506872Y367467I-2015J1164D01*
G01X506847Y367509D01*
X506828Y367543D01*
G02X506847Y369084I1384J754D01*
G03Y371410I-2015J1163D01*
G02Y372984I1365J787D01*
G01X506872Y373026D01*
G03X506847Y375309I-2040J1119D01*
G01X506828Y375343D01*
G02X506847Y376884I1384J754D01*
G03X506872Y379167I-2015J1164D01*
G01X506847Y379209D01*
X506828Y379243D01*
G02X506847Y380784I1384J754D01*
G03X506872Y383067I-2015J1164D01*
G01X506847Y383109D01*
X506828Y383143D01*
G02X506847Y384684I1384J754D01*
G03X506872Y386967I-2015J1164D01*
G01X506847Y387009D01*
X506828Y387043D01*
G02X506847Y388584I1384J754D01*
G03X506872Y390867I-2015J1164D01*
G01X506847Y390909D01*
X506828Y390943D01*
G02X506847Y392484I1384J754D01*
G03Y394810I-2015J1163D01*
G02Y396384I1365J787D01*
G03X507158Y397545I-2015J1162D01*
G01Y409222D01*
X503776Y412604D01*
Y412605D01*
X503777Y412684D01*
Y412744D01*
X503745Y412776D01*
G01X473305Y418040D02*
X473390Y418023D01*
X473505Y418101D01*
X473508Y418100D01*
X474812Y417841D01*
X487112Y405541D01*
X489640D01*
X492881Y402300D01*
Y401013D01*
X492677Y400659D01*
G03Y398333I2015J-1163D01*
G02Y396759I-1365J-787D01*
G01X492652Y396717D01*
G03X492677Y394434I2040J-1119D01*
G01X492696Y394400D01*
G02X492677Y392859I-1384J-754D01*
G03X492652Y390576I2015J-1164D01*
G01X492677Y390534D01*
X492696Y390500D01*
G02X492677Y388959I-1384J-754D01*
G03X492652Y386676I2015J-1164D01*
G01X492677Y386634D01*
X492696Y386600D01*
G02X492677Y385059I-1384J-754D01*
G03X492652Y382776I2015J-1164D01*
G01X492677Y382734D01*
X492696Y382700D01*
G02X492677Y381159I-1384J-754D01*
G03X492652Y378876I2015J-1164D01*
G01X492677Y378834D01*
X492696Y378800D01*
G02X492677Y377259I-1384J-754D01*
G03Y374933I2015J-1163D01*
G02Y373359I-1365J-787D01*
G01X492652Y373317D01*
G03X492677Y371034I2040J-1119D01*
G01X492696Y371000D01*
G02X492677Y369459I-1384J-754D01*
G03X492652Y367176I2015J-1164D01*
G01X492677Y367134D01*
X492696Y367100D01*
G02X492677Y365559I-1384J-754D01*
G03X492652Y363276I2015J-1164D01*
G01X492677Y363234D01*
X492696Y363200D01*
G02X492677Y361659I-1384J-754D01*
G03X492652Y359376I2015J-1164D01*
G01X492677Y359334D01*
X492696Y359300D01*
G02X492677Y357759I-1384J-754D01*
G03X492652Y355476I2015J-1164D01*
G01X492677Y355434D01*
X492696Y355400D01*
G02X492677Y353859I-1384J-754D01*
G03X494622Y350371I2015J-1163D01*
G01X494751D01*
G02X496057Y349584I-59J-1575D01*
G03X497987Y348422I2015J1163D01*
G01X498116D01*
G02X499437Y347634I-44J-1575D01*
G03X501382Y346471I2015J1162D01*
G01X501511D01*
G02X502817Y345684I-59J-1575D01*
G03X504747Y344522I2015J1163D01*
G01X504876D01*
G02X506197Y343734I-44J-1575D01*
G03X508142Y342571I2015J1162D01*
G01X508271D01*
G02X509577Y341784I-59J-1575D01*
G03X511507Y340622I2015J1163D01*
G01X511636D01*
G02X512957Y339834I-44J-1575D01*
G03X514902Y338671I2015J1162D01*
G01X515031D01*
G02X516337Y337884I-59J-1575D01*
G03X518267Y336722I2015J1163D01*
G01X518352D01*
G02X519703Y335957I0J-1575D01*
G01X519716Y335934D01*
G03X521661Y334771I2015J1162D01*
G01X521790D01*
G02X523096Y333984I-59J-1575D01*
G03X525026Y332822I2015J1163D01*
G01X525155D01*
G02X526476Y332034I-44J-1575D01*
G03X528421Y330871I2015J1162D01*
G01X528550D01*
G02X529856Y330084I-59J-1575D01*
G03X531786Y328922I2015J1163D01*
G01X531956D01*
G03X533886Y330084I-85J2325D01*
G02X535192Y330871I1365J-788D01*
G01X535321D01*
G03X537266Y332034I-70J2325D01*
G02X538587Y332822I1365J-787D01*
G01X538716D01*
G03X540646Y333984I-85J2325D01*
G02X541952Y334771I1365J-788D01*
G01X542081D01*
G03X544026Y335934I-70J2325D01*
G02X545347Y336722I1365J-787D01*
G01X545476D01*
G03X547406Y337884I-85J2325D01*
G02X548712Y338671I1365J-788D01*
G01X548841D01*
G03X550786Y339834I-70J2325D01*
G02X552107Y340622I1365J-787D01*
G01X552236D01*
G03X554191Y344067I-85J2325D01*
G01X554166Y344109D01*
X554147Y344143D01*
G02X554166Y345684I1384J754D01*
G03X554191Y347967I-2015J1164D01*
G01X554166Y348009D01*
X554147Y348043D01*
G02X554166Y349584I1384J754D01*
G03Y351910I-2015J1163D01*
G02Y353484I1365J787D01*
G03X554210Y353560I-1624J991D01*
G03X554497Y354726I-2040J1120D01*
G03X554487Y354899I-2327J-48D01*
G01Y362412D01*
G03X554166Y363609I-2394J0D01*
G02X554147Y365150I1365J787D01*
G02X554166Y365184I1235J-668D01*
G03X552221Y368672I-2015J1163D01*
G01X552092D01*
G02X550786Y369459I59J1575D01*
G03X548822Y370622I-2015J-1163D01*
G01X548727D01*
G02X547406Y371410I44J1575D01*
G03X546610Y372228I-2014J-1164D01*
G01X546387Y372365D01*
G02X545391Y374146I1094J1781D01*
G01X548771Y360496D02*
X549925Y359831D01*
X550008Y359521D01*
G02X548815Y358921I-1238J975D01*
G01X548686D01*
G03X546731Y355476I85J-2325D01*
G01X546756Y355434D01*
X546775Y355400D01*
G02X546756Y353859I-1384J-754D01*
G03X546731Y351576I2015J-1164D01*
G01X546756Y351534D01*
X546775Y351500D01*
G02X546756Y349959I-1384J-754D01*
G03X546731Y347676I2015J-1164D01*
G01X546756Y347634D01*
X546775Y347600D01*
G02X545450Y345272I-1384J-753D01*
G01X545321D01*
G03X543376Y344109I70J-2325D01*
G02X542055Y343321I-1365J787D01*
G01X541926D01*
G03X539996Y342159I85J-2325D01*
G02X538690Y341372I-1365J788D01*
G01X538561D01*
G03X536616Y340209I70J-2325D01*
G02X535295Y339421I-1365J787D01*
G01X535166D01*
G03X533236Y338259I85J-2325D01*
G02X531930Y337472I-1365J788D01*
G01X531812D01*
G02X530506Y338259I59J1575D01*
G03X528576Y339421I-2015J-1163D01*
G01X528447D01*
G02X527126Y340209I44J1575D01*
G03X525181Y341372I-2015J-1162D01*
G01X525052D01*
G02X523746Y342159I59J1575D01*
G03X521816Y343321I-2015J-1163D01*
G01X521731D01*
G02X520380Y344086I0J1575D01*
G01X520367Y344109D01*
G03X518422Y345272I-2015J-1162D01*
G01X518293D01*
G02X516987Y346059I59J1575D01*
G03X515057Y347221I-2015J-1163D01*
G01X514928D01*
G02X513607Y348009I44J1575D01*
G03X511662Y349172I-2015J-1162D01*
G01X511533D01*
G02X510227Y349959I59J1575D01*
G03X508297Y351121I-2015J-1163D01*
G01X508168D01*
G02X506847Y351909I44J1575D01*
G03X504902Y353072I-2015J-1162D01*
G01X504773D01*
G02X503467Y353859I59J1575D01*
G03X501537Y355021I-2015J-1163D01*
G01X501408D01*
G02X500087Y357384I44J1575D01*
G03X500112Y359667I-2015J1164D01*
G01X500087Y359709D01*
X500068Y359743D01*
G02X500087Y361284I1384J754D01*
G03X500112Y363567I-2015J1164D01*
G01X500087Y363609D01*
X500068Y363643D01*
G02X500087Y365184I1384J754D01*
G03X500112Y367467I-2015J1164D01*
G01X500087Y367509D01*
X500068Y367543D01*
G02X500087Y369084I1384J754D01*
G03Y371410I-2015J1163D01*
G02Y372984I1365J787D01*
G01X500112Y373026D01*
G03X500087Y375309I-2040J1119D01*
G01X500068Y375343D01*
G02X500087Y376884I1384J754D01*
G03X500112Y379167I-2015J1164D01*
G01X500087Y379209D01*
X500068Y379243D01*
G02X500087Y380784I1384J754D01*
G03X500112Y383067I-2015J1164D01*
G01X500087Y383109D01*
X500068Y383143D01*
G02X500087Y384684I1384J754D01*
G03X500112Y386967I-2015J1164D01*
G01X500087Y387009D01*
X500068Y387043D01*
G02X500087Y388584I1384J754D01*
G03X500112Y390867I-2015J1164D01*
G01X500087Y390909D01*
X500068Y390943D01*
G02X500087Y392484I1384J754D01*
G03Y394810I-2015J1163D01*
G02Y396384I1365J787D01*
G01X500396Y396919D01*
G03X500426Y397045I-2325J620D01*
G03X500075Y398880I-2354J501D01*
G01X499848Y399222D01*
Y405445D01*
X499282Y406011D01*
Y406564D01*
X498787Y407059D01*
X498234D01*
X497740Y407553D01*
Y408106D01*
X497245Y408601D01*
X496692D01*
X496198Y409095D01*
Y409648D01*
X495703Y410143D01*
X495150D01*
X494656Y410637D01*
Y411190D01*
X494161Y411685D01*
X493608D01*
X493114Y412179D01*
Y412732D01*
X492619Y413227D01*
X492066D01*
X485942Y419351D01*
Y419493D01*
X485881Y419554D01*
G01X478640Y419861D02*
X478701Y419800D01*
X478841D01*
X482117Y416524D01*
X482118D01*
X496441Y402201D01*
Y399375D01*
X496057Y398709D01*
G03X496032Y396426I2015J-1164D01*
G01X496057Y396384D01*
G02Y394810I-1365J-787D01*
G03Y392484I2015J-1163D01*
G02X496076Y390943I-1365J-787D01*
G01X496057Y390909D01*
X496032Y390867D01*
G03X496057Y388584I2040J-1119D01*
G02X496076Y387043I-1365J-787D01*
G01X496057Y387009D01*
X496032Y386967D01*
G03X496057Y384684I2040J-1119D01*
G02X496076Y383143I-1365J-787D01*
G01X496057Y383109D01*
X496032Y383067D01*
G03X496057Y380784I2040J-1119D01*
G02X496076Y379243I-1365J-787D01*
G01X496057Y379209D01*
X496032Y379167D01*
G03X496057Y376884I2040J-1119D01*
G02X496076Y375343I-1365J-787D01*
G01X496057Y375309D01*
G03X496032Y373026I2015J-1164D01*
G01X496057Y372984D01*
G02Y371410I-1365J-787D01*
G03Y369084I2015J-1163D01*
G02X496076Y367543I-1365J-787D01*
G01X496057Y367509D01*
X496032Y367467D01*
G03X496057Y365184I2040J-1119D01*
G02X496076Y363643I-1365J-787D01*
G01X496057Y363609D01*
X496032Y363567D01*
G03X496057Y361284I2040J-1119D01*
G02X496076Y359743I-1365J-787D01*
G01X496057Y359709D01*
X496032Y359667D01*
G03X496057Y357384I2040J-1119D01*
G02X496076Y355843I-1365J-787D01*
G01X496057Y355809D01*
X496032Y355767D01*
G03X497987Y352322I2040J-1120D01*
G01X498116D01*
G02X499437Y351534I-44J-1575D01*
G03X501382Y350371I2015J1162D01*
G01X501511D01*
G02X502817Y349584I-59J-1575D01*
G03X504747Y348422I2015J1163D01*
G01X504876D01*
G02X506197Y347634I-44J-1575D01*
G03X508142Y346471I2015J1162D01*
G01X508271D01*
G02X509577Y345684I-59J-1575D01*
G03X511507Y344522I2015J1163D01*
G01X511636D01*
G02X512957Y343734I-44J-1575D01*
G03X514902Y342571I2015J1162D01*
G01X515031D01*
G02X516337Y341784I-59J-1575D01*
G03X518267Y340622I2015J1163D01*
G01X518352D01*
G02X519703Y339857I0J-1575D01*
G01X519716Y339834D01*
G03X521661Y338671I2015J1162D01*
G01X521790D01*
G02X523096Y337884I-59J-1575D01*
G03X525026Y336722I2015J1163D01*
G01X525155D01*
G02X526476Y335934I-44J-1575D01*
G03X528421Y334771I2015J1162D01*
G01X528550D01*
G02X529856Y333984I-59J-1575D01*
G03X531786Y332822I2015J1163D01*
G01X531956D01*
G03X533886Y333984I-85J2325D01*
G02X535192Y334771I1365J-788D01*
G01X535321D01*
G03X537266Y335934I-70J2325D01*
G02X538587Y336722I1365J-787D01*
G01X538716D01*
G03X540646Y337884I-85J2325D01*
G02X541952Y338671I1365J-788D01*
G01X542081D01*
G03X544026Y339834I-70J2325D01*
G02X545347Y340622I1365J-787D01*
G01X545476D01*
G03X547406Y341784I-85J2325D01*
G02X548712Y342571I1365J-788D01*
G01X548841D01*
G03X550786Y346059I-70J2325D01*
G02X550767Y347600I1365J787D01*
G03X550811Y347676I-1624J991D01*
G03X550786Y349959I-2040J1119D01*
G02X550767Y351500I1365J787D01*
G01X550786Y351534D01*
X550811Y351576D01*
G03X549027Y355009I-2040J1120D01*
G01X548771Y355265D01*
Y356596D01*
G01X503073Y412104D02*
X503215D01*
X506408Y408911D01*
Y397546D01*
G02X506197Y396759I-1576J1D01*
G01X506172Y396717D01*
G03X506197Y394434I2040J-1119D01*
G01X506216Y394400D01*
G02X506197Y392859I-1384J-754D01*
G03X506172Y390576I2015J-1164D01*
G01X506197Y390534D01*
X506216Y390500D01*
G02X506197Y388959I-1384J-754D01*
G03X506172Y386676I2015J-1164D01*
G01X506197Y386634D01*
X506216Y386600D01*
G02X506197Y385059I-1384J-754D01*
G03X506172Y382776I2015J-1164D01*
G01X506197Y382734D01*
X506216Y382700D01*
G02X506197Y381159I-1384J-754D01*
G03X506172Y378876I2015J-1164D01*
G01X506197Y378834D01*
X506216Y378800D01*
G02X506197Y377259I-1384J-754D01*
G03Y374933I2015J-1163D01*
G02Y373359I-1365J-787D01*
G01X506172Y373317D01*
G03X506197Y371034I2040J-1119D01*
G01X506216Y371000D01*
G02X506197Y369459I-1384J-754D01*
G03X506172Y367176I2015J-1164D01*
G01X506197Y367134D01*
X506216Y367100D01*
G02X506197Y365559I-1384J-754D01*
G03X506172Y363276I2015J-1164D01*
G01X506197Y363234D01*
X506216Y363200D01*
G02X506197Y361659I-1384J-754D01*
G03X508142Y358171I2015J-1163D01*
G01X508271D01*
G02X509577Y357384I-59J-1575D01*
G03X511507Y356222I2015J1163D01*
G01X511636D01*
G02X512957Y355434I-44J-1575D01*
G03X514902Y354271I2015J1162D01*
G01X515031D01*
G02X516337Y353484I-59J-1575D01*
G03X518267Y352322I2015J1163D01*
G01X518352D01*
G02X519703Y351557I0J-1575D01*
G01X519716Y351534D01*
G03X521661Y350371I2015J1162D01*
G01X521790D01*
G02X523096Y349584I-59J-1575D01*
G03X525026Y348422I2015J1163D01*
G01X525155D01*
G02X526476Y347634I-44J-1575D01*
G03X528421Y346471I2015J1162D01*
G01X528550D01*
G02X529856Y345684I-59J-1575D01*
G03X531786Y344522I2015J1163D01*
G01X531956D01*
G03X533886Y345684I-85J2325D01*
G02X535192Y346471I1365J-788D01*
G01X535321D01*
G03X537266Y347634I-70J2325D01*
G02X538587Y348422I1365J-787D01*
G01X538716D01*
G03X540671Y351867I-85J2325D01*
G01X540646Y351909D01*
X540627Y351943D01*
G02X540646Y353484I1384J754D01*
G03X540671Y355767I-2015J1164D01*
G01X540646Y355809D01*
X540627Y355843D01*
G02X540646Y357384I1384J754D01*
G03X540671Y359667I-2015J1164D01*
G01X540646Y359709D01*
X540627Y359743D01*
G02X541952Y362071I1384J753D01*
G01X542081D01*
G03X544026Y365559I-70J2325D01*
G02X544007Y367100I1365J787D01*
G01X544026Y367134D01*
X544051Y367176D01*
G03X544026Y369459I-2040J1119D01*
G02X544007Y371000I1365J787D01*
G01X544026Y371034D01*
G03X544051Y373317I-2015J1164D01*
G01X544026Y373359D01*
G02X546756Y374933I1365J787D01*
G03X548686Y373771I2015J1163D01*
G02X549355Y373354I-29J-791D01*
G02X548771Y372196I-698J-374D01*
G01X473490Y418972D02*
X473575Y418955D01*
X473654Y418837D01*
X473655Y418836D01*
X475182Y418533D01*
X476809Y416906D01*
X477290Y416905D01*
X477786Y416409D01*
Y415929D01*
X478280Y415434D01*
X478844D01*
X479339Y414939D01*
Y414376D01*
X479833Y413881D01*
X480397D01*
X480892Y413386D01*
Y412823D01*
X481386Y412328D01*
X481950D01*
X482445Y411833D01*
Y411270D01*
X482939Y410775D01*
X483420D01*
X483916Y410279D01*
Y409799D01*
X484410Y409304D01*
X484891D01*
X485387Y408808D01*
Y408327D01*
X485881Y407833D01*
X486362D01*
X486858Y407337D01*
Y406856D01*
X487423Y406291D01*
X489951D01*
X493631Y402611D01*
Y400812D01*
X493327Y400284D01*
G03Y398709I1365J-787D01*
G02X493352Y396426I-2015J-1164D01*
G01X493327Y396384D01*
G03Y394810I1365J-787D01*
G02Y392484I-2015J-1163D01*
G03X493308Y390943I1365J-787D01*
G01X493327Y390909D01*
X493352Y390867D01*
G02X493327Y388584I-2040J-1119D01*
G03X493308Y387043I1365J-787D01*
G01X493327Y387009D01*
X493352Y386967D01*
G02X493327Y384684I-2040J-1119D01*
G03X493308Y383143I1365J-787D01*
G01X493327Y383109D01*
X493352Y383067D01*
G02X493327Y380784I-2040J-1119D01*
G03X493308Y379243I1365J-787D01*
G01X493327Y379209D01*
X493352Y379167D01*
G02X493327Y376884I-2040J-1119D01*
G03X493308Y375343I1365J-787D01*
G01X493327Y375309D01*
G02X493352Y373026I-2015J-1164D01*
G01X493327Y372984D01*
G03Y371410I1365J-787D01*
G02Y369084I-2015J-1163D01*
G03X493308Y367543I1365J-787D01*
G01X493327Y367509D01*
X493352Y367467D01*
G02X493327Y365184I-2040J-1119D01*
G03X493308Y363643I1365J-787D01*
G01X493327Y363609D01*
X493352Y363567D01*
G02X493327Y361284I-2040J-1119D01*
G03X493308Y359743I1365J-787D01*
G01X493327Y359709D01*
X493352Y359667D01*
G02X493327Y357384I-2040J-1119D01*
G03X493308Y355843I1365J-787D01*
G01X493327Y355809D01*
X493352Y355767D01*
G02X493327Y353484I-2040J-1119D01*
G03X494648Y351121I1365J-788D01*
G01X494777D01*
G02X496707Y349959I-85J-2325D01*
G03X498013Y349172I1365J788D01*
G01X498142D01*
G02X500087Y348009I-70J-2325D01*
G03X501408Y347221I1365J787D01*
G01X501537D01*
G02X503467Y346059I-85J-2325D01*
G03X504773Y345272I1365J788D01*
G01X504902D01*
G02X506847Y344109I-70J-2325D01*
G03X508168Y343321I1365J787D01*
G01X508297D01*
G02X510227Y342159I-85J-2325D01*
G03X511533Y341372I1365J788D01*
G01X511662D01*
G02X513607Y340209I-70J-2325D01*
G03X514928Y339421I1365J787D01*
G01X515057D01*
G02X516987Y338259I-85J-2325D01*
G03X518293Y337472I1365J788D01*
G01X518422D01*
G02X520367Y336309I-70J-2325D01*
G01X520380Y336286D01*
G03X521731Y335521I1351J810D01*
G01X521816D01*
G02X523746Y334359I-85J-2325D01*
G03X525052Y333572I1365J788D01*
G01X525181D01*
G02X527126Y332409I-70J-2325D01*
G03X528447Y331621I1365J787D01*
G01X528576D01*
G02X530506Y330459I-85J-2325D01*
G03X531812Y329672I1365J788D01*
G01X531930D01*
G03X533236Y330459I-59J1575D01*
G02X535166Y331621I2015J-1163D01*
G01X535295D01*
G03X536616Y332409I-44J1575D01*
G02X538561Y333572I2015J-1162D01*
G01X538690D01*
G03X539996Y334359I-59J1575D01*
G02X541926Y335521I2015J-1163D01*
G01X542055D01*
G03X543376Y336309I-44J1575D01*
G02X545321Y337472I2015J-1162D01*
G01X545450D01*
G03X546756Y338259I-59J1575D01*
G02X548686Y339421I2015J-1163D01*
G01X548815D01*
G03X550136Y340209I-44J1575D01*
G02X552081Y341372I2015J-1162D01*
G01X552210D01*
G03X553535Y343700I-59J1575D01*
G01X553516Y343734D01*
X553491Y343776D01*
G02X553516Y346059I2040J1119D01*
G03X553535Y347600I-1365J787D01*
G01X553516Y347634D01*
X553491Y347676D01*
G02X553516Y349959I2040J1119D01*
G03X553535Y351500I-1365J787D01*
G01X553516Y351534D01*
G02Y353860I2015J1163D01*
G03X553554Y353927I-4424J2554D01*
G01Y353926D01*
G03X553746Y354711I-1384J754D01*
G03X553740Y354828I-1576J-22D01*
G01X553737Y354863D01*
Y362411D01*
G03X553516Y363234I-1644J0D01*
G02X553488Y365509I2015J1162D01*
G01X553491Y365517D01*
G03X553516Y365559I-1560J957D01*
G03X552195Y367922I-1365J788D01*
G01X552066D01*
G02X550136Y369084I85J2325D01*
G03X548830Y369871I-1365J-788D01*
G01X548720D01*
G02X546756Y371034I51J2326D01*
G03X546217Y371589I-1365J-786D01*
G03X545619Y371806I-825J-1342D01*
G01X545391Y371578D01*
Y370247D01*
G01X485209Y418882D02*
X485270Y418821D01*
X485410D01*
X498531Y405700D01*
X498532D01*
X499098Y405134D01*
Y398995D01*
X499450Y398465D01*
Y398464D01*
G02X499692Y397201I-1378J-919D01*
G01X499688Y397195D01*
X499412Y396717D01*
G03X499437Y394434I2040J-1119D01*
G01X499456Y394400D01*
G02X499437Y392859I-1384J-754D01*
G03X499412Y390576I2015J-1164D01*
G01X499437Y390534D01*
X499456Y390500D01*
G02X499437Y388959I-1384J-754D01*
G03X499412Y386676I2015J-1164D01*
G01X499437Y386634D01*
X499456Y386600D01*
G02X499437Y385059I-1384J-754D01*
G03X499412Y382776I2015J-1164D01*
G01X499437Y382734D01*
X499456Y382700D01*
G02X499437Y381159I-1384J-754D01*
G03X499412Y378876I2015J-1164D01*
G01X499437Y378834D01*
X499456Y378800D01*
G02X499437Y377259I-1384J-754D01*
G03Y374933I2015J-1163D01*
G02Y373359I-1365J-787D01*
G01X499412Y373317D01*
G03X499437Y371034I2040J-1119D01*
G01X499456Y371000D01*
G02X499437Y369459I-1384J-754D01*
G03X499412Y367176I2015J-1164D01*
G01X499437Y367134D01*
X499456Y367100D01*
G02X499437Y365559I-1384J-754D01*
G03X499412Y363276I2015J-1164D01*
G01X499437Y363234D01*
X499456Y363200D01*
G02X499437Y361659I-1384J-754D01*
G03X499412Y359376I2015J-1164D01*
G01X499437Y359334D01*
X499456Y359300D01*
G02X499437Y357759I-1384J-754D01*
G03X501382Y354271I2015J-1163D01*
G01X501511D01*
G02X502817Y353484I-59J-1575D01*
G03X504747Y352322I2015J1163D01*
G01X504876D01*
G02X506197Y351534I-44J-1575D01*
G03X508142Y350371I2015J1162D01*
G01X508271D01*
G02X509577Y349584I-59J-1575D01*
G03X511507Y348422I2015J1163D01*
G01X511636D01*
G02X512957Y347634I-44J-1575D01*
G03X514902Y346471I2015J1162D01*
G01X515031D01*
G02X516337Y345684I-59J-1575D01*
G03X518267Y344522I2015J1163D01*
G01X518352D01*
G02X519703Y343757I0J-1575D01*
G01X519716Y343734D01*
G03X521661Y342571I2015J1162D01*
G01X521790D01*
G02X523096Y341784I-59J-1575D01*
G03X525026Y340622I2015J1163D01*
G01X525155D01*
G02X526476Y339834I-44J-1575D01*
G03X528421Y338671I2015J1162D01*
G01X528550D01*
G02X529856Y337884I-59J-1575D01*
G03X531786Y336722I2015J1163D01*
G01X531956D01*
G03X533886Y337884I-85J2325D01*
G02X535192Y338671I1365J-788D01*
G01X535321D01*
G03X537266Y339834I-70J2325D01*
G02X538587Y340622I1365J-787D01*
G01X538716D01*
G03X540646Y341784I-85J2325D01*
G02X541952Y342571I1365J-788D01*
G01X542081D01*
G03X544026Y343734I-70J2325D01*
G02X545347Y344522I1365J-787D01*
G01X545476D01*
G03X547431Y347967I-85J2325D01*
G01X547407Y348007D01*
X547406Y348009D01*
X547387Y348043D01*
G02X547406Y349584I1384J754D01*
G03X547431Y351867I-2015J1164D01*
G01X547407Y351907D01*
X547406Y351909D01*
X547387Y351943D01*
G02X547406Y353484I1384J754D01*
G03X547431Y355767I-2015J1164D01*
G01X547407Y355807D01*
X547406Y355809D01*
X547387Y355843D01*
G02X548712Y358171I1384J753D01*
G01X548841D01*
G03X550645Y359117I-69J2325D01*
G01X550997Y359212D01*
X552151Y358547D01*
G01X545391Y378047D02*
X546545Y377381D01*
X546855Y377465D01*
G03X545343Y379621I-1464J581D01*
G03X544026Y378834I47J-1575D01*
G02X542081Y377671I-2015J1162D01*
G01X541952D01*
G03X540627Y375343I59J-1575D01*
G01X540646Y375309D01*
G02X540671Y373026I-2015J-1164D01*
G01X540646Y372984D01*
G03Y371410I1365J-787D01*
G02Y369084I-2015J-1163D01*
G03X540627Y367543I1365J-787D01*
G01X540646Y367509D01*
X540671Y367467D01*
G02X538716Y364022I-2040J-1120D01*
G01X538587D01*
G03X537266Y361659I44J-1575D01*
G02X537291Y359376I-2015J-1164D01*
G01X537266Y359334D01*
X537247Y359300D01*
G03X537266Y357759I1384J-754D01*
G02X537291Y355476I-2015J-1164D01*
G01X537266Y355434D01*
X537247Y355400D01*
G03X537266Y353859I1384J-754D01*
G02X535321Y350371I-2015J-1163D01*
G01X535192D01*
G03X533886Y349584I59J-1575D01*
G02X531956Y348422I-2015J1163D01*
G01X531786D01*
G02X529856Y349584I85J2325D01*
G03X528550Y350371I-1365J-788D01*
G01X528421D01*
G02X526476Y351534I70J2325D01*
G03X525155Y352322I-1365J-787D01*
G01X525026D01*
G02X523096Y353484I85J2325D01*
G03X521790Y354271I-1365J-788D01*
G01X521661D01*
G02X519716Y355434I70J2325D01*
G01X519703Y355457D01*
G03X518352Y356222I-1351J-810D01*
G01X518267D01*
G02X516337Y357384I85J2325D01*
G03X515031Y358171I-1365J-788D01*
G01X514902D01*
G02X512957Y359334I70J2325D01*
G03X511636Y360122I-1365J-787D01*
G01X511507D01*
G02X509552Y363567I85J2325D01*
G01X509577Y363609D01*
X509596Y363643D01*
G03X509577Y365184I-1384J754D01*
G02X509552Y367467I2015J1164D01*
G01X509577Y367509D01*
X509596Y367543D01*
G03X509577Y369084I-1384J754D01*
G02Y371410I2015J1163D01*
G03Y372984I-1365J787D01*
G01X509552Y373026D01*
G02X509577Y375309I2040J1119D01*
G01X509596Y375343D01*
G03X509577Y376884I-1384J754D01*
G02X509552Y379167I2015J1164D01*
G01X509577Y379209D01*
X509596Y379243D01*
G03X509577Y380784I-1384J754D01*
G02X509552Y383067I2015J1164D01*
G01X509577Y383109D01*
X509596Y383143D01*
G03X509577Y384684I-1384J754D01*
G02X509552Y386967I2015J1164D01*
G01X509577Y387009D01*
X509596Y387043D01*
G03X509577Y388584I-1384J754D01*
G02X509552Y390867I2015J1164D01*
G01X509577Y390909D01*
X509596Y390943D01*
G03X509577Y392484I-1384J754D01*
G02Y394810I2015J1163D01*
G03Y396384I-1365J787D01*
G01Y396385D01*
X509192Y397053D01*
Y398167D01*
X508794Y398565D01*
Y399265D01*
X509192Y399663D01*
Y410909D01*
X509092Y411009D01*
Y411096D01*
G01X491638Y418006D02*
X491699Y417945D01*
X491839D01*
X501360Y408424D01*
Y408425D01*
X502896Y406889D01*
Y402749D01*
X502860Y402687D01*
G03X502794Y396424I5527J-3190D01*
G01X502838Y396349D01*
G02X502818Y394810I-1386J-752D01*
G01X502817D01*
G03Y392484I2015J-1163D01*
G02X502836Y390943I-1365J-787D01*
G01X502817Y390909D01*
X502792Y390867D01*
G03X502817Y388584I2040J-1119D01*
G02X502836Y387043I-1365J-787D01*
G01X502817Y387009D01*
X502792Y386967D01*
G03X502817Y384684I2040J-1119D01*
G02X502836Y383143I-1365J-787D01*
G01X502817Y383109D01*
X502792Y383067D01*
G03X502817Y380784I2040J-1119D01*
G02X502836Y379243I-1365J-787D01*
G01X502817Y379209D01*
X502792Y379167D01*
G03X502817Y376884I2040J-1119D01*
G02X502836Y375343I-1365J-787D01*
G01X502817Y375309D01*
G03X502792Y373026I2015J-1164D01*
G01X502817Y372984D01*
G02Y371410I-1365J-787D01*
G03Y369084I2015J-1163D01*
G02X502836Y367543I-1365J-787D01*
G01X502817Y367509D01*
X502792Y367467D01*
G03X502817Y365184I2040J-1119D01*
G02X502836Y363643I-1365J-787D01*
G01X502817Y363609D01*
X502792Y363567D01*
G03X502817Y361284I2040J-1119D01*
G02X502836Y359743I-1365J-787D01*
G01X502817Y359709D01*
X502792Y359667D01*
G03X504747Y356222I2040J-1120D01*
G01X504876D01*
G02X506197Y355434I-44J-1575D01*
G03X508142Y354271I2015J1162D01*
G01X508271D01*
G02X509577Y353484I-59J-1575D01*
G03X511507Y352322I2015J1163D01*
G01X511636D01*
G02X512957Y351534I-44J-1575D01*
G03X514902Y350371I2015J1162D01*
G01X515031D01*
G02X516337Y349584I-59J-1575D01*
G03X518267Y348422I2015J1163D01*
G01X518352D01*
G02X519703Y347657I0J-1575D01*
G01X519716Y347634D01*
G03X521661Y346471I2015J1162D01*
G01X521790D01*
G02X523096Y345684I-59J-1575D01*
G03X525026Y344522I2015J1163D01*
G01X525155D01*
G02X526476Y343734I-44J-1575D01*
G03X528421Y342571I2015J1162D01*
G01X528550D01*
G02X529856Y341784I-59J-1575D01*
G03X531786Y340622I2015J1163D01*
G01X531956D01*
G03X533886Y341784I-85J2325D01*
G02X535192Y342571I1365J-788D01*
G01X535321D01*
G03X537266Y343734I-70J2325D01*
G02X538587Y344522I1365J-787D01*
G01X538716D01*
G03X540646Y345684I-85J2325D01*
G02X541952Y346471I1365J-788D01*
G01X542081D01*
G03X544026Y349959I-70J2325D01*
G02X544007Y351500I1365J787D01*
G01X544026Y351534D01*
X544051Y351576D01*
G03X544026Y353859I-2040J1119D01*
G02X544007Y355400I1365J787D01*
G01X544026Y355434D01*
X544051Y355476D01*
G03X544026Y357759I-2040J1119D01*
G02X545347Y360122I1365J788D01*
G01X545476D01*
G03X547523Y363380I-85J2325D01*
G01X547617Y363731D01*
X548771Y364396D01*
G01X474829Y410425D02*
X474890Y410364D01*
X475030D01*
X485582Y399812D01*
Y398511D01*
X486921Y397172D01*
X487989D01*
G02X488003Y397171I-105J-1571D01*
G02X489297Y394810I-71J-1574D01*
G03Y392484I2015J-1163D01*
G02X489316Y390943I-1365J-787D01*
G01X489297Y390909D01*
X489272Y390867D01*
G03X489297Y388584I2040J-1119D01*
G02X489316Y387043I-1365J-787D01*
G01X489297Y387009D01*
X489272Y386967D01*
G03X489297Y384684I2040J-1119D01*
G02X489316Y383143I-1365J-787D01*
G01X489297Y383109D01*
X489272Y383067D01*
G03X489297Y380784I2040J-1119D01*
G02X489316Y379243I-1365J-787D01*
G01X489297Y379209D01*
X489272Y379167D01*
G03X489297Y376884I2040J-1119D01*
G02X489316Y375343I-1365J-787D01*
G01X489297Y375309D01*
G03X489272Y373026I2015J-1164D01*
G01X489297Y372984D01*
G02Y371410I-1365J-787D01*
G03Y369084I2015J-1163D01*
G02X489316Y367543I-1365J-787D01*
G01X489297Y367509D01*
X489272Y367467D01*
G03X489297Y365184I2040J-1119D01*
G02X489316Y363643I-1365J-787D01*
G01X489297Y363609D01*
X489272Y363567D01*
G03X489297Y361284I2040J-1119D01*
G02X489316Y359743I-1365J-787D01*
G01X489297Y359709D01*
X489272Y359667D01*
G03X489297Y357384I2040J-1119D01*
G02X489316Y355843I-1365J-787D01*
G01X489297Y355809D01*
X489272Y355767D01*
G03X489297Y353484I2040J-1119D01*
G02X489316Y351943I-1365J-787D01*
G01X489297Y351909D01*
X489272Y351867D01*
G03X491227Y348422I2040J-1120D01*
G01X491356D01*
G02X492677Y347634I-44J-1575D01*
G03X494622Y346471I2015J1162D01*
G01X494751D01*
G02X496057Y345684I-59J-1575D01*
G03X497987Y344522I2015J1163D01*
G01X498116D01*
G02X499437Y343734I-44J-1575D01*
G03X501382Y342571I2015J1162D01*
G01X501511D01*
G02X502817Y341784I-59J-1575D01*
G03X504747Y340622I2015J1163D01*
G01X504876D01*
G02X506197Y339834I-44J-1575D01*
G03X508142Y338671I2015J1162D01*
G01X508271D01*
G02X509577Y337884I-59J-1575D01*
G03X511507Y336722I2015J1163D01*
G01X511636D01*
G02X512957Y335934I-44J-1575D01*
G03X514902Y334771I2015J1162D01*
G01X515031D01*
G02X516337Y333984I-59J-1575D01*
G03X518267Y332822I2015J1163D01*
G01X518352D01*
G02X519703Y332057I0J-1575D01*
G01X519716Y332034D01*
G03X521661Y330871I2015J1162D01*
G01X521790D01*
G02X523096Y330084I-59J-1575D01*
G03X525026Y328922I2015J1163D01*
G01X525155D01*
G02X526476Y328134I-44J-1575D01*
G03X528421Y326971I2015J1162D01*
G01X528550D01*
G02X529856Y326184I-59J-1575D01*
G03X531784Y325022I2015J1163D01*
G03X531958I87J2325D01*
G03X533886Y326184I-87J2325D01*
G02X535192Y326971I1365J-788D01*
G01X535321D01*
G03X537266Y328134I-70J2325D01*
G02X538587Y328922I1365J-787D01*
G01X538716D01*
G03X540646Y330084I-85J2325D01*
G02X541952Y330871I1365J-788D01*
G01X542081D01*
G03X544026Y332034I-70J2325D01*
G02X545347Y332822I1365J-787D01*
G01X545476D01*
G03X547406Y333984I-85J2325D01*
G02X548712Y334771I1365J-788D01*
G01X548841D01*
G03X550786Y335934I-70J2325D01*
G02X552107Y336722I1365J-787D01*
G01X552236D01*
G03X554166Y337884I-85J2325D01*
G02X555472Y338671I1365J-788D01*
G01X555601D01*
G03X557546Y342159I-70J2325D01*
G02X557527Y343700I1365J787D01*
G01X557546Y343734D01*
X557571Y343776D01*
G03X557546Y346059I-2040J1119D01*
G02X557527Y347600I1365J787D01*
G01X557546Y347634D01*
X557571Y347676D01*
G03X557546Y349959I-2040J1119D01*
G02X557527Y351500I1365J787D01*
G01X557546Y351534D01*
G03Y353860I-2015J1163D01*
G01Y353859D01*
G02X557335Y354672I1365J788D01*
G01Y370232D01*
X557703Y371046D01*
G03X557726Y373304I-2172J1151D01*
G01X557703Y373347D01*
G02Y374945I1509J799D01*
G01X557726Y374988D01*
G03X556331Y378421I-2195J1108D01*
G01X555487D01*
G02X554166Y379209I44J1575D01*
G03X552221Y380372I-2015J-1162D01*
G01X552092D01*
G02X550786Y381159I59J1575D01*
G03X549027Y382309I-2015J-1162D01*
G01X548771Y382565D01*
Y383896D01*
G01Y376096D02*
X547617Y376762D01*
X547523Y377114D01*
G03X545320Y380372I-2131J933D01*
G03X543376Y379209I71J-2325D01*
G02X542055Y378421I-1365J787D01*
G01X541926D01*
G03X539996Y374933I85J-2325D01*
G02Y373359I-1365J-787D01*
G01X539971Y373317D01*
G03X539996Y371034I2040J-1119D01*
G01X540015Y371000D01*
G02X539996Y369459I-1384J-754D01*
G03X539971Y367176I2015J-1164D01*
G01X539996Y367134D01*
X540015Y367100D01*
G02X538690Y364772I-1384J-753D01*
G01X538561D01*
G03X536616Y361284I70J-2325D01*
G02X536635Y359743I-1365J-787D01*
G01X536616Y359709D01*
X536591Y359667D01*
G03X536616Y357384I2040J-1119D01*
G02X536635Y355843I-1365J-787D01*
G01X536616Y355809D01*
X536591Y355767D01*
G03X536616Y353484I2040J-1119D01*
G02X535295Y351121I-1365J-788D01*
G01X535166D01*
G03X533236Y349959I85J-2325D01*
G02X531930Y349172I-1365J788D01*
G01X531812D01*
G02X530506Y349959I59J1575D01*
G03X528576Y351121I-2015J-1163D01*
G01X528447D01*
G02X527126Y351909I44J1575D01*
G03X525181Y353072I-2015J-1162D01*
G01X525052D01*
G02X523746Y353859I59J1575D01*
G03X521816Y355021I-2015J-1163D01*
G01X521731D01*
G02X520380Y355786I0J1575D01*
G01X520367Y355809D01*
G03X518422Y356972I-2015J-1162D01*
G01X518293D01*
G02X516987Y357759I59J1575D01*
G03X515057Y358921I-2015J-1163D01*
G01X514928D01*
G02X513607Y359709I44J1575D01*
G03X511662Y360872I-2015J-1162D01*
G01X511533D01*
G02X510208Y363200I59J1575D01*
G01X510227Y363234D01*
X510252Y363276D01*
G03X510227Y365559I-2040J1119D01*
G02X510208Y367100I1365J787D01*
G01X510227Y367134D01*
X510252Y367176D01*
G03X510227Y369459I-2040J1119D01*
G02X510208Y371000I1365J787D01*
G01X510227Y371034D01*
G03X510252Y373317I-2015J1164D01*
G01X510227Y373359D01*
G02Y374933I1365J787D01*
G03Y377259I-2015J1163D01*
G02X510208Y378800I1365J787D01*
G01X510227Y378834D01*
X510252Y378876D01*
G03X510227Y381159I-2040J1119D01*
G02X510208Y382700I1365J787D01*
G01X510227Y382734D01*
X510252Y382776D01*
G03X510227Y385059I-2040J1119D01*
G02X510208Y386600I1365J787D01*
G01X510227Y386634D01*
X510252Y386676D01*
G03X510227Y388959I-2040J1119D01*
G02X510208Y390500I1365J787D01*
G01X510227Y390534D01*
X510252Y390576D01*
G03X510227Y392859I-2040J1119D01*
G02X510208Y394400I1365J787D01*
G01X510227Y394434D01*
G03X510252Y396717I-2015J1164D01*
G01X509942Y397254D01*
Y410909D01*
X510042Y411009D01*
Y411096D01*
G01X492310Y418678D02*
X492371Y418617D01*
Y418475D01*
X493352Y417494D01*
X493905D01*
X494400Y416999D01*
Y416446D01*
X494894Y415952D01*
X495447D01*
X495942Y415457D01*
Y414904D01*
X496436Y414410D01*
X496989D01*
X497484Y413915D01*
Y413362D01*
X497978Y412868D01*
X498531D01*
X499026Y412373D01*
Y411820D01*
X499520Y411326D01*
X500073D01*
X500568Y410831D01*
Y410278D01*
X501062Y409784D01*
X501615D01*
X502110Y409289D01*
Y408736D01*
X503646Y407200D01*
Y402548D01*
X503510Y402312D01*
G03X503448Y396793I4878J-2815D01*
G01X503492Y396717D01*
G02X503467Y394434I-2040J-1119D01*
G01X503448Y394400D01*
G03X503467Y392859I1384J-754D01*
G02X503492Y390576I-2015J-1164D01*
G01X503467Y390534D01*
X503448Y390500D01*
G03X503467Y388959I1384J-754D01*
G02X503492Y386676I-2015J-1164D01*
G01X503467Y386634D01*
X503448Y386600D01*
G03X503467Y385059I1384J-754D01*
G02X503492Y382776I-2015J-1164D01*
G01X503467Y382734D01*
X503448Y382700D01*
G03X503467Y381159I1384J-754D01*
G02X503492Y378876I-2015J-1164D01*
G01X503467Y378834D01*
X503448Y378800D01*
G03X503467Y377259I1384J-754D01*
G02Y374933I-2015J-1163D01*
G03Y373359I1365J-787D01*
G01X503492Y373317D01*
G02X503467Y371034I-2040J-1119D01*
G01X503448Y371000D01*
G03X503467Y369459I1384J-754D01*
G02X503492Y367176I-2015J-1164D01*
G01X503467Y367134D01*
X503448Y367100D01*
G03X503467Y365559I1384J-754D01*
G02X503492Y363276I-2015J-1164D01*
G01X503467Y363234D01*
X503448Y363200D01*
G03X503467Y361659I1384J-754D01*
G02X503492Y359376I-2015J-1164D01*
G01X503467Y359334D01*
X503448Y359300D01*
G03X504773Y356972I1384J-753D01*
G01X504902D01*
G02X506847Y355809I-70J-2325D01*
G03X508168Y355021I1365J787D01*
G01X508297D01*
G02X510227Y353859I-85J-2325D01*
G03X511533Y353072I1365J788D01*
G01X511662D01*
G02X513607Y351909I-70J-2325D01*
G03X514928Y351121I1365J787D01*
G01X515057D01*
G02X516987Y349959I-85J-2325D01*
G03X518293Y349172I1365J788D01*
G01X518422D01*
G02X520367Y348009I-70J-2325D01*
G01X520380Y347986D01*
G03X521731Y347221I1351J810D01*
G01X521816D01*
G02X523746Y346059I-85J-2325D01*
G03X525052Y345272I1365J788D01*
G01X525181D01*
G02X527126Y344109I-70J-2325D01*
G03X528447Y343321I1365J787D01*
G01X528576D01*
G02X530506Y342159I-85J-2325D01*
G03X531812Y341372I1365J788D01*
G01X531930D01*
G03X533236Y342159I-59J1575D01*
G02X535166Y343321I2015J-1163D01*
G01X535295D01*
G03X536616Y344109I-44J1575D01*
G02X538561Y345272I2015J-1162D01*
G01X538690D01*
G03X539996Y346059I-59J1575D01*
G02X541926Y347221I2015J-1163D01*
G01X542055D01*
G03X543376Y349584I-44J1575D01*
G02X543351Y351867I2015J1164D01*
G01X543376Y351909D01*
X543395Y351943D01*
G03X543376Y353484I-1384J754D01*
G02X543351Y355767I2015J1164D01*
G01X543376Y355809D01*
X543395Y355843D01*
G03X543376Y357384I-1384J754D01*
G02X545321Y360872I2015J1163D01*
G01X545450D01*
G03X546855Y363028I-60J1575D01*
G01X546545Y363112D01*
X545391Y362447D01*
G01X479312Y420533D02*
X479373Y420472D01*
Y420330D01*
X483313Y416390D01*
X483866D01*
X484361Y415895D01*
Y415342D01*
X484855Y414848D01*
X485408D01*
X485903Y414353D01*
Y413800D01*
X486397Y413306D01*
X486950D01*
X487445Y412811D01*
Y412258D01*
X487939Y411764D01*
X488492D01*
X488987Y411269D01*
Y410716D01*
X489481Y410222D01*
X490034D01*
X490529Y409727D01*
Y409174D01*
X491023Y408680D01*
X491576D01*
X492071Y408185D01*
Y407632D01*
X492565Y407138D01*
X493118D01*
X493613Y406643D01*
Y406090D01*
X494107Y405596D01*
X494660D01*
X495155Y405101D01*
Y404548D01*
X495649Y404054D01*
X496202D01*
X496697Y403559D01*
Y403006D01*
X497191Y402512D01*
Y399174D01*
X496707Y398333D01*
G03Y396759I1365J-787D01*
G01X496732Y396717D01*
G02X496707Y394434I-2040J-1119D01*
G01X496688Y394400D01*
G03X496707Y392859I1384J-754D01*
G02X496732Y390576I-2015J-1164D01*
G01X496707Y390534D01*
X496688Y390500D01*
G03X496707Y388959I1384J-754D01*
G02X496732Y386676I-2015J-1164D01*
G01X496707Y386634D01*
X496688Y386600D01*
G03X496707Y385059I1384J-754D01*
G02X496732Y382776I-2015J-1164D01*
G01X496707Y382734D01*
X496688Y382700D01*
G03X496707Y381159I1384J-754D01*
G02X496732Y378876I-2015J-1164D01*
G01X496707Y378834D01*
X496688Y378800D01*
G03X496707Y377259I1384J-754D01*
G02Y374933I-2015J-1163D01*
G03Y373359I1365J-787D01*
G01X496732Y373317D01*
G02X496707Y371034I-2040J-1119D01*
G01X496688Y371000D01*
G03X496707Y369459I1384J-754D01*
G02X496732Y367176I-2015J-1164D01*
G01X496707Y367134D01*
X496688Y367100D01*
G03X496707Y365559I1384J-754D01*
G02X496732Y363276I-2015J-1164D01*
G01X496707Y363234D01*
X496688Y363200D01*
G03X496707Y361659I1384J-754D01*
G02X496732Y359376I-2015J-1164D01*
G01X496707Y359334D01*
X496688Y359300D01*
G03X496707Y357759I1384J-754D01*
G02X496732Y355476I-2015J-1164D01*
G01X496707Y355434D01*
X496688Y355400D01*
G03X498013Y353072I1384J-753D01*
G01X498142D01*
G02X500087Y351909I-70J-2325D01*
G03X501408Y351121I1365J787D01*
G01X501537D01*
G02X503467Y349959I-85J-2325D01*
G03X504773Y349172I1365J788D01*
G01X504902D01*
G02X506847Y348009I-70J-2325D01*
G03X508168Y347221I1365J787D01*
G01X508297D01*
G02X510227Y346059I-85J-2325D01*
G03X511533Y345272I1365J788D01*
G01X511662D01*
G02X513607Y344109I-70J-2325D01*
G03X514928Y343321I1365J787D01*
G01X515057D01*
G02X516987Y342159I-85J-2325D01*
G03X518293Y341372I1365J788D01*
G01X518422D01*
G02X520367Y340209I-70J-2325D01*
G01X520380Y340186D01*
G03X521731Y339421I1351J810D01*
G01X521816D01*
G02X523746Y338259I-85J-2325D01*
G03X525052Y337472I1365J788D01*
G01X525181D01*
G02X527126Y336309I-70J-2325D01*
G03X528447Y335521I1365J787D01*
G01X528576D01*
G02X530506Y334359I-85J-2325D01*
G03X531812Y333572I1365J788D01*
G01X531930D01*
G03X533236Y334359I-59J1575D01*
G02X535166Y335521I2015J-1163D01*
G01X535295D01*
G03X536616Y336309I-44J1575D01*
G02X538561Y337472I2015J-1162D01*
G01X538690D01*
G03X539996Y338259I-59J1575D01*
G02X541926Y339421I2015J-1163D01*
G01X542055D01*
G03X543376Y340209I-44J1575D01*
G02X545321Y341372I2015J-1162D01*
G01X545450D01*
G03X546756Y342159I-59J1575D01*
G02X548686Y343321I2015J-1163D01*
G01X548815D01*
G03X550136Y345684I-44J1575D01*
G02X550111Y347967I2015J1164D01*
G03X550155Y348043I-1442J885D01*
G03X550136Y349584I-1384J754D01*
G02X550111Y351867I2015J1164D01*
G01X550136Y351909D01*
X550155Y351943D01*
G03X548999Y354255I-1384J753D01*
G01X548771Y354027D01*
Y352696D01*
G01X475501Y411097D02*
X475533Y411065D01*
Y411005D01*
X475532Y410924D01*
X480120Y406335D01*
X480684D01*
X481179Y405840D01*
Y405277D01*
X481673Y404782D01*
X482237D01*
X482732Y404287D01*
Y403724D01*
X483226Y403229D01*
X483790D01*
X484285Y402734D01*
Y402171D01*
X484779Y401676D01*
X485343D01*
X485838Y401181D01*
Y400617D01*
X486332Y400123D01*
Y398822D01*
X487232Y397922D01*
X488002D01*
G02X489947Y394434I-70J-2325D01*
G01X489928Y394400D01*
G03X489947Y392859I1384J-754D01*
G02X489972Y390576I-2015J-1164D01*
G01X489947Y390534D01*
X489928Y390500D01*
G03X489947Y388959I1384J-754D01*
G02X489972Y386676I-2015J-1164D01*
G01X489947Y386634D01*
X489928Y386600D01*
G03X489947Y385059I1384J-754D01*
G02X489972Y382776I-2015J-1164D01*
G01X489947Y382734D01*
X489928Y382700D01*
G03X489947Y381159I1384J-754D01*
G02X489972Y378876I-2015J-1164D01*
G01X489947Y378834D01*
X489928Y378800D01*
G03X489947Y377259I1384J-754D01*
G02Y374933I-2015J-1163D01*
G03Y373359I1365J-787D01*
G01X489972Y373317D01*
G02X489947Y371034I-2040J-1119D01*
G01X489928Y371000D01*
G03X489947Y369459I1384J-754D01*
G02X489972Y367176I-2015J-1164D01*
G01X489947Y367134D01*
X489928Y367100D01*
G03X489947Y365559I1384J-754D01*
G02X489972Y363276I-2015J-1164D01*
G01X489947Y363234D01*
X489928Y363200D01*
G03X489947Y361659I1384J-754D01*
G02X489972Y359376I-2015J-1164D01*
G01X489947Y359334D01*
X489928Y359300D01*
G03X489947Y357759I1384J-754D01*
G02X489972Y355476I-2015J-1164D01*
G01X489947Y355434D01*
X489928Y355400D01*
G03X489947Y353859I1384J-754D01*
G02X489972Y351576I-2015J-1164D01*
G01X489947Y351534D01*
X489928Y351500D01*
G03X491253Y349172I1384J-753D01*
G01X491382D01*
G02X493327Y348009I-70J-2325D01*
G03X494648Y347221I1365J787D01*
G01X494777D01*
G02X496707Y346059I-85J-2325D01*
G03X498013Y345272I1365J788D01*
G01X498142D01*
G02X500087Y344109I-70J-2325D01*
G03X501408Y343321I1365J787D01*
G01X501537D01*
G02X503467Y342159I-85J-2325D01*
G03X504773Y341372I1365J788D01*
G01X504902D01*
G02X506847Y340209I-70J-2325D01*
G03X508168Y339421I1365J787D01*
G01X508297D01*
G02X510227Y338259I-85J-2325D01*
G03X511533Y337472I1365J788D01*
G01X511662D01*
G02X513607Y336309I-70J-2325D01*
G03X514928Y335521I1365J787D01*
G01X515057D01*
G02X516987Y334359I-85J-2325D01*
G03X518293Y333572I1365J788D01*
G01X518422D01*
G02X520367Y332409I-70J-2325D01*
G01X520380Y332386D01*
G03X521731Y331621I1351J810D01*
G01X521816D01*
G02X523746Y330459I-85J-2325D01*
G03X525052Y329672I1365J788D01*
G01X525181D01*
G02X527126Y328509I-70J-2325D01*
G03X528447Y327721I1365J787D01*
G01X528576D01*
G02X530506Y326559I-85J-2325D01*
G03X531812Y325772I1365J788D01*
G01X531930D01*
G03X533236Y326559I-59J1575D01*
G02X535166Y327721I2015J-1163D01*
G01X535295D01*
G03X536616Y328509I-44J1575D01*
G02X538561Y329672I2015J-1162D01*
G01X538690D01*
G03X539996Y330459I-59J1575D01*
G02X541926Y331621I2015J-1163D01*
G01X542055D01*
G03X543376Y332409I-44J1575D01*
G02X545321Y333572I2015J-1162D01*
G01X545450D01*
G03X546756Y334359I-59J1575D01*
G02X548686Y335521I2015J-1163D01*
G01X548815D01*
G03X550136Y336309I-44J1575D01*
G02X552081Y337472I2015J-1162D01*
G01X552210D01*
G03X553516Y338259I-59J1575D01*
G02X555446Y339421I2015J-1163D01*
G01X555575D01*
G03X556896Y341784I-44J1575D01*
G02X556871Y344067I2015J1164D01*
G01X556896Y344109D01*
X556915Y344143D01*
G03X556896Y345684I-1384J754D01*
G02X556871Y347967I2015J1164D01*
G01X556896Y348009D01*
X556915Y348043D01*
G03X556896Y349584I-1384J754D01*
G02X556871Y351867I2015J1164D01*
G01X556896Y351909D01*
G03X556915Y353450I-1365J787D01*
G01X556896Y353483D01*
G02X556585Y354685I2015J1163D01*
G01Y355867D01*
X556278Y356174D01*
Y356874D01*
X556585Y357181D01*
Y357914D01*
X556245Y358254D01*
Y358954D01*
X556585Y359294D01*
Y359994D01*
X556245Y360334D01*
Y361034D01*
X556585Y361374D01*
Y362074D01*
X556245Y362414D01*
Y363114D01*
X556585Y363454D01*
Y364154D01*
X556245Y364494D01*
Y365194D01*
X556585Y365534D01*
Y366234D01*
X556245Y366574D01*
Y367274D01*
X556585Y367614D01*
Y370394D01*
X557019Y371354D01*
X557018Y371355D01*
X557017D01*
X557040Y371398D01*
G03Y372996I-1509J799D01*
G01X557017Y373039D01*
G02X557040Y375297I2195J1107D01*
G03X556188Y377671I-1509J798D01*
G01X555461D01*
G02X553516Y378834I70J2325D01*
G03X552195Y379622I-1365J-787D01*
G01X552066D01*
G02X550136Y380784I85J2325D01*
G03X548999Y381555I-1365J-789D01*
G01X548771Y381327D01*
Y379996D01*
G01X498072Y241547D02*
X499147D01*
G03X499900Y242300I0J753D01*
G01Y242372D01*
G03X499508Y243031I-750J0D01*
G03X499150Y243122I-358J-659D01*
G01X498028D01*
G03X496707Y242334I44J-1575D01*
G02X494762Y241171I-2015J1162D01*
G01X491551D01*
X489602Y239222D01*
X486768D01*
G03X485447Y238434I44J-1575D01*
G02X483502Y237271I-2015J1162D01*
G01X483373D01*
G03X482067Y236484I59J-1575D01*
G02X480103Y235321I-2015J1163D01*
G01X480008D01*
G03X478687Y232959I44J-1575D01*
G01X478712Y232917D01*
G02X478687Y230634I-2040J-1119D01*
G01X478668Y230600D01*
G03X478687Y229059I1384J-754D01*
G02X478712Y226776I-2015J-1164D01*
G01X478687Y226734D01*
X478668Y226700D01*
G03X478687Y225159I1384J-754D01*
G02X478712Y222876I-2015J-1164D01*
G01X478687Y222834D01*
X478668Y222800D01*
G03X478687Y221259I1384J-754D01*
G02X478712Y218976I-2015J-1164D01*
G01X478687Y218934D01*
X478668Y218900D01*
G03X478687Y217359I1384J-754D01*
G02X476742Y213871I-2015J-1163D01*
G01X476603D01*
G03X475307Y213084I69J-1575D01*
G01X469100Y200766D01*
Y199980D01*
X469200Y199793D01*
G01X1208871Y221791D02*
X1208810Y221994D01*
X1208369Y222435D01*
X1208368D01*
X1207766Y223037D01*
Y223038D01*
X1207166Y223638D01*
X1206504Y224784D01*
G03X1206024Y225300I-1365J-788D01*
G03X1205367Y225555I-884J-1304D01*
G01X1205139Y225327D01*
Y223996D01*
G01X494692Y239596D02*
X495846Y238931D01*
X495929Y238621D01*
G02X494736Y238021I-1238J975D01*
G01X490906D01*
X488956Y236071D01*
X486762D01*
X486761Y236072D01*
G03X484797Y234909I51J-2326D01*
G02X483503Y234122I-1365J787D01*
G01X483362D01*
G03X481417Y230634I70J-2325D01*
G01X481436Y230600D01*
G02X481417Y229059I-1384J-754D01*
G03X481392Y226776I2015J-1164D01*
G01X481417Y226734D01*
X481436Y226700D01*
G02X481417Y225159I-1384J-754D01*
G03X481392Y222876I2015J-1164D01*
G01X481417Y222834D01*
X481436Y222800D01*
G02X481417Y221259I-1384J-754D01*
G03X481392Y218976I2015J-1164D01*
G01X481417Y218934D01*
X481436Y218900D01*
G02X481417Y217359I-1384J-754D01*
G03X481389Y215084I2015J-1162D01*
G01X481412Y215043D01*
X481440Y214996D01*
G02X480052Y212671I-1388J-748D01*
G03X478037Y211509I-2J-2325D01*
G01X477576Y210712D01*
G03X473143Y200737I45084J-26008D01*
G01X472890Y199955D01*
Y198120D01*
X472790Y198020D01*
Y197933D01*
G01X1209331Y208627D02*
X1209296Y208707D01*
X1209165Y208758D01*
X1208725Y209767D01*
X1207237Y212710D01*
X1207394Y213182D01*
X1207077Y213808D01*
X1206604Y213963D01*
X1206287Y214588D01*
X1206444Y215060D01*
X1206127Y215686D01*
X1205654Y215841D01*
X1204780Y217569D01*
X1204775Y217576D01*
X1204774Y217577D01*
X1203755Y219343D01*
G02X1203675Y220678I1385J753D01*
G01X1203985Y220762D01*
X1205139Y220096D01*
G01X501452Y243496D02*
X500636D01*
G02X499866Y243691I0J1617D01*
G03X499150Y243872I-714J-1319D01*
G01X498018D01*
G03X496057Y242709I54J-2325D01*
G02X494736Y241921I-1365J787D01*
G01X491240D01*
X489291Y239972D01*
X486742D01*
G03X484797Y238809I70J-2325D01*
G02X483476Y238021I-1365J787D01*
G01X483347D01*
G03X481417Y236859I85J-2325D01*
G02X480111Y236072I-1365J788D01*
G01X480001D01*
G03X478012Y232626I51J-2326D01*
G01X478037Y232584D01*
G02Y231010I-1365J-787D01*
G03Y228684I2015J-1163D01*
G02X478056Y227143I-1365J-787D01*
G01X478037Y227109D01*
X478012Y227067D01*
G03X478037Y224784I2040J-1119D01*
G02X478056Y223243I-1365J-787D01*
G01X478037Y223209D01*
X478012Y223167D01*
G03X478037Y220884I2040J-1119D01*
G02X478056Y219343I-1365J-787D01*
G01X478037Y219309D01*
X478012Y219267D01*
G03X478037Y216984I2040J-1119D01*
G02X476729Y214621I-1365J-788D01*
G01X476588D01*
G03X474646Y213439I84J-2325D01*
G01X468350Y200945D01*
Y199994D01*
X468250Y199807D01*
G01X1209544Y222463D02*
X1209341Y222524D01*
X1207766Y224099D01*
X1207154Y225159D01*
G03X1206446Y225921I-2015J-1163D01*
G01X1205139Y227896D01*
G01X473740Y197933D02*
Y198020D01*
X473640Y198120D01*
Y199836D01*
X473857Y200505D01*
G02X478226Y210336I48803J-15802D01*
G01X478687Y211133D01*
G02X480051Y211921I1364J-786D01*
G01X480052D01*
G03X482092Y215367I0J2327D01*
G01X482067Y215409D01*
X482048Y215443D01*
G02X482067Y216984I1384J754D01*
G03X482092Y219267I-2015J1164D01*
G01X482067Y219309D01*
X482048Y219343D01*
G02X482067Y220884I1384J754D01*
G03X482092Y223167I-2015J1164D01*
G01X482067Y223209D01*
X482048Y223243D01*
G02X482067Y224784I1384J754D01*
G03X482092Y227067I-2015J1164D01*
G01X482067Y227109D01*
X482048Y227143D01*
G02X482067Y228684I1384J754D01*
G03Y231010I-2015J1163D01*
G02X483361Y233371I1365J787D01*
G01X483517D01*
G03X485447Y234533I-85J2325D01*
G02X486768Y235321I1365J-787D01*
G01X489267D01*
X491217Y237271D01*
X494746D01*
G03X496566Y238217I-53J2326D01*
G01X496918Y238312D01*
X498072Y237647D01*
G01X501452Y239596D02*
X500692Y238500D01*
X500017Y237527D01*
G03X499437Y236859I1435J-1831D01*
G02X498131Y236072I-1365J788D01*
G01X498021D01*
G03X496057Y234909I51J-2326D01*
G02X494763Y234122I-1365J787D01*
G01X491266D01*
X489315Y232171D01*
X486728D01*
X486727Y232172D01*
G03X484797Y228684I85J-2325D01*
G02X484816Y227143I-1365J-787D01*
G01X484797Y227109D01*
X484772Y227067D01*
G03X484797Y224784I2040J-1119D01*
G02X484816Y223243I-1365J-787D01*
G01X484797Y223209D01*
X484772Y223167D01*
G03X484797Y220884I2040J-1119D01*
G02X484816Y219343I-1365J-787D01*
G01X484797Y219309D01*
X484772Y219267D01*
G03X484797Y216984I2040J-1119D01*
G02X484816Y215443I-1365J-787D01*
G01X484797Y215409D01*
X484772Y215367D01*
G03X484797Y213084I2040J-1119D01*
G02X484816Y211543I-1365J-787D01*
G01X484271Y210599D01*
X481867Y205008D01*
Y203506D01*
X481767Y203406D01*
G01X1203599Y207176D02*
X1203453Y207329D01*
X1200945Y216407D01*
X1200394Y217360D01*
G02X1200375Y218900I1365J787D01*
G01X1200394Y218934D01*
X1200419Y218976D01*
G03X1200286Y221430I-2040J1120D01*
G01X1199054Y223191D01*
G03X1198379Y223996I-4925J-3444D01*
G01X508212Y235696D02*
X507058Y236362D01*
X506748Y236278D01*
G03X506712Y235213I1465J-583D01*
G03X506828Y234943I1500J485D01*
G01X506847Y234909D01*
G02X504902Y231421I-2015J-1163D01*
G01X504761D01*
G03X503467Y229059I71J-1574D01*
G02X503492Y226776I-2015J-1164D01*
G01X503467Y226734D01*
X503448Y226700D01*
G03X503467Y225159I1384J-754D01*
G02X501522Y221671I-2015J-1163D01*
G01X501393D01*
G03X500087Y220884I59J-1575D01*
G02X498157Y219722I-2015J1163D01*
G01X498028D01*
G03X498013Y216572I44J-1575D01*
G01X498142D01*
G02X500087Y213084I-70J-2325D01*
G01X500008Y212947D01*
G03X500198Y211328I1444J-651D01*
G01X500756Y210606D01*
Y209229D01*
X500518Y207063D01*
Y205594D01*
X500618Y205494D01*
Y205407D01*
G01X1187128Y197092D02*
X1187121Y197179D01*
X1187212Y197285D01*
X1187211Y197287D01*
X1187212D01*
X1187134Y198233D01*
X1186766Y199684D01*
X1186051Y201449D01*
G02X1186228Y203666I2297J932D01*
G03X1186366Y205039I-1369J831D01*
G01X1186225Y205283D01*
X1186224Y205284D01*
G02Y207610I2015J1163D01*
G03Y209184I-1365J787D01*
G01X1186199Y209226D01*
G02X1186224Y211509I2040J1119D01*
G01X1186243Y211543D01*
G03X1186224Y213084I-1384J754D01*
G02X1186199Y215367I2015J1164D01*
G01X1186224Y215409D01*
X1186243Y215443D01*
G03X1186224Y216984I-1384J754D01*
G02X1185913Y218202I2015J1163D01*
G03X1185319Y219636I-2028J0D01*
G01X1184859Y220096D01*
G01X495005Y205055D02*
Y205142D01*
X495105Y205242D01*
Y208477D01*
X492363Y211219D01*
Y221313D01*
X493471Y222421D01*
X494736D01*
G03X496057Y223209I-44J1575D01*
G02X498002Y224372I2015J-1162D01*
G01X498131D01*
G03X499456Y226700I-59J1575D01*
G01X499437Y226734D01*
X499412Y226776D01*
G02X499178Y227400I2039J1121D01*
G01X498072Y229847D01*
G01X504832Y233746D02*
G03X503924Y234122I-908J-908D01*
G01X501382D01*
G03X499437Y232959I70J-2325D01*
G02X498143Y232172I-1365J787D01*
G01X497987D01*
G03X496057Y228684I85J-2325D01*
G02X494749Y226321I-1365J-788D01*
G01X493595D01*
X490429Y223155D01*
Y204309D01*
X490745Y203993D01*
Y203100D01*
X490645Y203000D01*
G01X494692Y227896D02*
Y228856D01*
X494076Y229472D01*
X492124D01*
X490749Y228097D01*
Y227559D01*
X490254Y227064D01*
X489716D01*
X489160Y226508D01*
Y225687D01*
X489550Y225297D01*
Y224597D01*
X489160Y224207D01*
Y208869D01*
X487106Y205140D01*
Y202449D01*
X487206Y202349D01*
Y202262D01*
G01X1200138Y202903D02*
X1200102Y202982D01*
X1200152Y203112D01*
X1196964Y210094D01*
X1196364Y211133D01*
G02Y213459I2015J1163D01*
G03X1196383Y215000I-1365J787D01*
G01X1196364Y215034D01*
X1196339Y215076D01*
G02X1196247Y217129I2039J1120D01*
G01X1196153Y217481D01*
X1194999Y218147D01*
G01X482717Y203406D02*
X482617Y203506D01*
Y204853D01*
X484943Y210262D01*
X485470Y211175D01*
G03X485447Y213459I-2038J1122D01*
G02X485428Y215000I1365J787D01*
G01X485447Y215034D01*
X485472Y215076D01*
G03X485447Y217359I-2040J1119D01*
G02X485428Y218900I1365J787D01*
G01X485447Y218934D01*
X485472Y218976D01*
G03X485447Y221259I-2040J1119D01*
G02X485428Y222800I1365J787D01*
G01X485447Y222834D01*
X485472Y222876D01*
G03X485447Y225159I-2040J1119D01*
G02X485428Y226700I1365J787D01*
G01X485447Y226734D01*
X485472Y226776D01*
G03X485447Y229059I-2040J1119D01*
G02X486741Y231421I1365J788D01*
G01X489626D01*
X491577Y233372D01*
X494763D01*
X494777Y233371D01*
G03X496707Y234533I-85J2325D01*
G02X498028Y235321I1365J-787D01*
G01X498123D01*
G03X500087Y236484I-51J2326D01*
G02X501224Y237255I1366J-790D01*
G01X501588Y237308D01*
G02X502034Y237160I76J-518D01*
G01X502118Y236849D01*
X501452Y235696D01*
G01X1208460Y208247D02*
X1208425Y208327D01*
X1208477Y208457D01*
X1208045Y209447D01*
X1204124Y217202D01*
X1204116Y217215D01*
X1204114Y217220D01*
X1203100Y218975D01*
G02X1202978Y220955I2040J1119D01*
G01X1202913Y221381D01*
X1201759Y222047D01*
G01X504832Y237647D02*
X505997Y234983D01*
G03X506197Y234533I2214J715D01*
G02X504903Y232172I-1365J-787D01*
G01X504747D01*
G03X502817Y228684I85J-2325D01*
G02X502836Y227143I-1365J-787D01*
G01X502817Y227109D01*
X502792Y227067D01*
G03X502817Y224784I2040J-1119D01*
G02X501496Y222421I-1365J-788D01*
G01X501367D01*
G03X499437Y221259I85J-2325D01*
G02X498131Y220472I-1365J788D01*
G01X498002D01*
G03X497987Y215822I70J-2325D01*
G01X498116D01*
G02X499437Y213459I-44J-1575D01*
G01X499341Y213292D01*
G03X499604Y210870I2111J-996D01*
G01X500006Y210349D01*
Y209271D01*
X499768Y207105D01*
Y205594D01*
X499668Y205494D01*
Y205407D01*
G01X1188075Y197169D02*
X1188068Y197256D01*
X1187960Y197347D01*
X1187877Y198357D01*
X1187481Y199919D01*
X1186746Y201731D01*
G02X1186870Y203277I1602J649D01*
G03X1187046Y205362I-2011J1220D01*
G01X1186874Y205659D01*
G02X1186855Y207200I1365J787D01*
G01X1186874Y207234D01*
G03X1186899Y209517I-2015J1164D01*
G01X1186874Y209559D01*
G02Y211133I1365J787D01*
G03Y213459I-2015J1163D01*
G02X1186855Y215000I1365J787D01*
G01X1186874Y215034D01*
X1186899Y215076D01*
G03X1186874Y217359I-2040J1119D01*
G02X1186664Y218184I1366J787D01*
G02X1186775Y218728I1576J-38D01*
G01X1187085Y218812D01*
X1188239Y218147D01*
G01X1191619Y220096D02*
G02X1191446Y219620I-742J0D01*
G01X1189833Y217689D01*
G03X1189579Y215076I1786J-1492D01*
G01X1189604Y215034D01*
X1189623Y215000D01*
G02X1189604Y213459I-1384J-754D01*
G03Y211133I2015J-1163D01*
G02Y209559I-1365J-787D01*
G01X1189579Y209517D01*
G03X1189604Y207234I2040J-1119D01*
G01X1189623Y207200D01*
G02X1189604Y205659I-1384J-754D01*
G01X1189332Y205188D01*
X1189315Y204326D01*
X1190004Y203129D01*
X1190530Y200203D01*
X1190448Y200087D01*
X1190463Y200001D01*
G01X495955Y205055D02*
Y205142D01*
X495855Y205242D01*
Y208788D01*
X493113Y211530D01*
Y221002D01*
X493782Y221671D01*
X494762D01*
G03X496707Y222834I-70J2325D01*
G02X498028Y223622I1365J-787D01*
G01X498157D01*
G03X500112Y227067I-85J2325D01*
G01X500087Y227109D01*
X500068Y227143D01*
G02X499988Y228478I1385J753D01*
G01X500298Y228562D01*
X501452Y227896D01*
G01Y231797D02*
X502792Y232569D01*
X502848Y232779D01*
G03X502393Y233371I-455J121D01*
G01X501381D01*
G03X500087Y232584I71J-1574D01*
G02X498142Y231421I-2015J1162D01*
G01X498001D01*
G03X496707Y229059I71J-1574D01*
G02X494762Y225571I-2015J-1163D01*
G01X493906D01*
X491179Y222844D01*
Y210620D01*
X491579Y210220D01*
Y209620D01*
X491179Y209220D01*
Y208620D01*
X491579Y208220D01*
Y207620D01*
X491179Y207220D01*
Y206620D01*
X491579Y206220D01*
Y205620D01*
X491179Y205220D01*
Y204620D01*
X491495Y204304D01*
Y203100D01*
X491595Y203000D01*
G01X1194606Y201247D02*
X1194700Y201341D01*
Y202899D01*
X1194630Y203246D01*
X1193814Y207289D01*
X1193328Y208588D01*
X1192959Y209226D01*
G02X1192984Y211509I2040J1119D01*
G01X1193003Y211543D01*
G03X1193160Y212622I-1385J752D01*
G03X1193083Y212878I-1542J-324D01*
G01X1192773Y212962D01*
X1191619Y212296D01*
G01X494692Y231797D02*
X493117Y230222D01*
X491813D01*
X488410Y226819D01*
Y209062D01*
X486356Y205333D01*
Y202449D01*
X486256Y202349D01*
Y202262D01*
G01X1201003Y203297D02*
X1200967Y203376D01*
X1200834Y203425D01*
X1200420Y204334D01*
X1200606Y204824D01*
X1200313Y205462D01*
X1199822Y205644D01*
X1199530Y206282D01*
X1199716Y206772D01*
X1199423Y207410D01*
X1198932Y207592D01*
X1198640Y208230D01*
X1198826Y208720D01*
X1198533Y209358D01*
X1198043Y209540D01*
X1197562Y210591D01*
X1197373Y210887D01*
X1197022Y211494D01*
X1196995Y211543D01*
G02X1197014Y213084I1384J754D01*
G03X1197039Y215367I-2015J1164D01*
G01X1197014Y215409D01*
X1196995Y215443D01*
G02X1196915Y216778I1385J753D01*
G01X1197225Y216862D01*
X1198379Y216196D01*
G01X511592Y229847D02*
X512746Y230512D01*
X513056Y230428D01*
G02X513150Y230077I-1465J-580D01*
G02X512957Y229059I-1559J-232D01*
G03X512932Y226776I2015J-1164D01*
G01X512957Y226734D01*
X512976Y226700D01*
G02X512957Y225159I-1384J-754D01*
G03X512932Y222876I2015J-1164D01*
G01X512957Y222834D01*
X512976Y222800D01*
G02X512957Y221259I-1384J-754D01*
G03X512932Y218976I2015J-1164D01*
G01X512957Y218934D01*
X512976Y218900D01*
G02X512957Y217359I-1384J-754D01*
G03X512932Y215076I2015J-1164D01*
G01X512957Y215034D01*
X512976Y215000D01*
G02X512957Y213459I-1384J-754D01*
G03Y211133I2015J-1163D01*
G02Y209559I-1365J-787D01*
G01X512932Y209517D01*
G03X512957Y207234I2040J-1119D01*
G01X512989Y207178D01*
X512991Y207175D01*
Y207176D01*
X512998Y207165D01*
G02X513299Y205920I-2418J-1243D01*
G01X513300Y205921D01*
Y202500D01*
X513200Y202400D01*
G01X1175920Y197400D02*
X1175909Y197645D01*
X1176450Y199177D01*
X1177043Y201780D01*
Y202642D01*
G03X1176734Y203709I-2324J-95D01*
G01X1176715Y203743D01*
G02X1176734Y205284I1384J754D01*
G03Y207610I-2015J1163D01*
G02Y209184I1365J787D01*
G01X1176759Y209226D01*
G03X1176734Y211509I-2040J1119D01*
G01X1176715Y211543D01*
G02X1178040Y213871I1384J753D01*
G01X1178169D01*
G03X1180114Y215034I-70J2325D01*
G02X1181435Y215822I1365J-787D01*
G01X1182072D01*
G02X1182907Y215476I0J-1180D01*
G02X1182399Y214248I-509J-509D01*
G01X1181479Y214247D01*
G01X509650Y204632D02*
Y204719D01*
X509550Y204819D01*
Y208303D01*
X506618Y211235D01*
Y212687D01*
X506847Y213084D01*
G03X506872Y215367I-2015J1164D01*
G01X506847Y215409D01*
X506828Y215443D01*
G02X508153Y217771I1384J753D01*
G01X508282D01*
G03X510227Y221259I-70J2325D01*
G02X510208Y222800I1365J787D01*
G01X510227Y222834D01*
X510252Y222876D01*
G03X510227Y225159I-2040J1119D01*
G02X510017Y225985I1365J787D01*
G02X510128Y226528I1575J-39D01*
G01X510438Y226612D01*
X511592Y225947D01*
G01X1184859Y208397D02*
Y209728D01*
X1184631Y209956D01*
G03X1183634Y209388I228J-1559D01*
G03X1183494Y207610I1225J-991D01*
G02Y205284I-2015J-1163D01*
G03X1183475Y203743I1365J-787D01*
G01X1183494Y203709D01*
G02X1183784Y202854I-2016J-1160D01*
G02X1183804Y202600I-2305J-309D01*
G01Y202100D01*
X1184174Y201730D01*
Y201170D01*
X1183804Y200800D01*
Y200300D01*
X1184156Y199948D01*
Y199352D01*
X1183804Y199000D01*
Y198189D01*
X1183798Y197588D01*
X1183898Y197488D01*
Y197401D01*
G01X504199Y206468D02*
Y206555D01*
X504299Y206655D01*
Y207605D01*
X503161Y208743D01*
Y212489D01*
X502817Y213084D01*
G02X502791Y215363I2015J1163D01*
G01X502811Y215400D01*
X502817Y215409D01*
X502836Y215443D01*
G03X502817Y216984I-1384J754D01*
G02X504762Y220472I2015J1163D01*
G01X504891D01*
G03X506216Y222800I-59J1575D01*
G01X506197Y222834D01*
X506172Y222876D01*
G02X506197Y225159I2040J1119D01*
G03X506216Y226700I-1365J787D01*
G01X506197Y226734D01*
X506172Y226776D01*
G02X508161Y230222I2040J1120D01*
G01X508256D01*
G03X509577Y232584I-44J1575D01*
G01X509552Y232626D01*
G02X510665Y235880I2040J1120D01*
G01X511592Y237647D01*
G01X543975Y202058D02*
X543932Y202133D01*
X543794Y202169D01*
X540646Y207610D01*
G03X538716Y208772I-2015J-1163D01*
G01X538560D01*
G02X537266Y211133I71J1574D01*
G03Y213459I-2015J1163D01*
G02X537247Y215000I1365J787D01*
G01X537266Y215034D01*
X537291Y215076D01*
G03X535336Y218521I-2040J1120D01*
G01X535207D01*
G02X533886Y219309I44J1575D01*
G03X531941Y220472I-2015J-1162D01*
G01X531812D01*
G02X530487Y222800I59J1575D01*
G01X530506Y222834D01*
X530531Y222876D01*
G03X530506Y225159I-2040J1119D01*
G02X530487Y226700I1365J787D01*
G01X530506Y226734D01*
X530531Y226776D01*
G03X530506Y229059I-2040J1119D01*
G02X530784Y230988I1364J788D01*
G02X531643Y231406I1086J-1141D01*
G01X531991Y231457D01*
G02X532489Y230465I84J-579D01*
G01X531871Y229847D01*
G01X525111Y233746D02*
X525358Y233500D01*
X525533Y233325D01*
G02X526164Y231800I-1525J-1524D01*
G03X526476Y230634I2327J-2D01*
G01X526495Y230600D01*
G02X526476Y229059I-1384J-754D01*
G03X526451Y226776I2015J-1164D01*
G01X526476Y226734D01*
X526495Y226700D01*
G02X526476Y225159I-1384J-754D01*
G03X526451Y222876I2015J-1164D01*
G01X526476Y222834D01*
X526495Y222800D01*
G02X526476Y221259I-1384J-754D01*
G03X528421Y217771I2015J-1163D01*
G01X528550D01*
G02X529875Y215443I-59J-1575D01*
G01X529856Y215409D01*
X529831Y215367D01*
G03X531820Y211921I2040J-1120D01*
G01X531915D01*
G02X531942Y208772I-43J-1575D01*
G01X531786D01*
G03Y204122I85J-2325D01*
G01X531928D01*
G02X533236Y203334I-57J-1575D01*
G01X533861Y202251D01*
X533862D01*
X537908Y198205D01*
Y198064D01*
X537969Y198003D01*
G01X1159361Y200875D02*
X1159422Y200936D01*
Y201078D01*
X1163525Y205180D01*
Y206487D01*
G03X1163215Y207609I-2325J-39D01*
G01Y207610D01*
G02Y209184I1365J787D01*
G01X1163240Y209226D01*
G03X1163215Y211509I-2040J1119D01*
G01X1163196Y211543D01*
G02X1163215Y213084I1383J754D01*
G02X1164101Y213797I1364J-788D01*
G01Y213798D01*
G02X1164851Y212567I226J-707D01*
G01X1164580Y212296D01*
G01X525111Y222047D02*
Y223378D01*
X524883Y223606D01*
G03X523915Y223072I229J-1560D01*
G03X523746Y221259I1197J-1026D01*
G02X523771Y218976I-2015J-1164D01*
G01X523746Y218934D01*
X523727Y218900D01*
G03X525052Y216572I1384J-753D01*
G01X525181D01*
G02X527126Y213084I-70J-2325D01*
G03X527107Y211543I1365J-787D01*
G01X527126Y211509D01*
G02X527151Y209226I-2015J-1164D01*
G01X527126Y209184D01*
G03Y207610I1365J-787D01*
G02Y205284I-2015J-1163D01*
G03X527360Y203398I1365J-788D01*
G01X527968Y202790D01*
X528518D01*
X529013Y202295D01*
Y201745D01*
X529508Y201250D01*
X530058D01*
X530553Y200755D01*
Y200205D01*
X531048Y199710D01*
X531598D01*
X532093Y199215D01*
Y198665D01*
X532624Y198134D01*
X532826Y198073D01*
G01X1162182Y200881D02*
X1162235D01*
X1162372Y201018D01*
X1163477Y202366D01*
X1163431Y202817D01*
X1163918Y203411D01*
X1164370Y203453D01*
X1164948Y204157D01*
X1165423Y205070D01*
X1165637Y206572D01*
G02X1165945Y207609I2323J-126D01*
G01X1165944D01*
X1165945Y207610D01*
G03X1166155Y208398I-1367J786D01*
G03X1165570Y209162I-792J-1D01*
G01X1165378Y209214D01*
X1164694Y208820D01*
X1164580Y208397D01*
G01X521731Y223996D02*
X521000Y224418D01*
X520578Y224661D01*
X520268Y224577D01*
G03X520367Y223209I1463J-582D01*
G01X520402Y223149D01*
G02X520367Y220883I-2050J-1102D01*
G03Y219309I1364J-787D01*
G01X520402Y219249D01*
G02X520367Y216983I-2050J-1102D01*
G03X521731Y214621I1364J-787D01*
G01X521816D01*
G02X523746Y211133I-85J-2325D01*
G03Y209559I1365J-787D01*
G01X523771Y209517D01*
G02X523746Y207234I-2040J-1119D01*
G01X523745D01*
X523222Y206330D01*
Y204441D01*
X523322Y204341D01*
Y204254D01*
G01X1166380Y200418D02*
X1166418Y200496D01*
X1166545Y200539D01*
X1169314Y205060D01*
X1169537Y205854D01*
Y206242D01*
X1169534Y206469D01*
G03X1169324Y207234I-1574J-21D01*
G02X1169299Y209517I2015J1164D01*
G01X1169324Y209559D01*
G03Y211133I-1364J787D01*
G01X1169299Y211175D01*
G02X1169207Y213230I2039J1121D01*
G01X1169113Y213582D01*
X1167960Y214247D01*
G01X517750Y201055D02*
Y201142D01*
X517850Y201242D01*
Y203192D01*
X517849D01*
X517127Y203914D01*
X516312Y205324D01*
G02X518254Y208770I2040J1121D01*
G01X518352D01*
G03X519692Y209518I0J1574D01*
G01X519716Y209559D01*
X519735Y209593D01*
G03X518352Y211921I-1384J753D01*
G01X518301D01*
G02X516312Y215367I51J2326D01*
G01X516337Y215409D01*
X516356Y215443D01*
G03X516337Y216984I-1384J754D01*
G02X516312Y219267I2015J1164D01*
G01X516337Y219309D01*
X516356Y219343D01*
G03X516337Y220884I-1384J754D01*
G02X516312Y223167I2015J1164D01*
G01X516337Y223209D01*
X516356Y223243D01*
G03X516337Y224784I-1384J754D01*
G02X518282Y228272I2015J1163D01*
G01X518352D01*
G03X519703Y229037I0J1575D01*
G01X519707Y229042D01*
X519719Y229062D01*
X519731Y229083D01*
G02X521728Y230220I1998J-1187D01*
G01X523152D01*
X524206Y230222D01*
G02X525111Y229847I0J-1280D01*
G01X514972Y231797D02*
G03X513894Y230188I348J-1398D01*
G02X513607Y228684I-2302J-340D01*
G03X513588Y227143I1365J-787D01*
G01X513607Y227109D01*
X513632Y227067D01*
G02X513607Y224784I-2040J-1119D01*
G03X513588Y223243I1365J-787D01*
G01X513607Y223209D01*
X513632Y223167D01*
G02X513607Y220884I-2040J-1119D01*
G03X513588Y219343I1365J-787D01*
G01X513607Y219309D01*
X513632Y219267D01*
G02X513607Y216984I-2040J-1119D01*
G03X513588Y215443I1365J-787D01*
G01X513607Y215409D01*
X513632Y215367D01*
G02X513607Y213084I-2040J-1119D01*
G03X513588Y211543I1365J-787D01*
G01X513607Y211509D01*
G02X513632Y209226I-2015J-1164D01*
G01X513607Y209184D01*
G03Y207610I1365J-787D01*
G01X513656Y207526D01*
G02X514050Y205920I-3075J-1606D01*
G01Y202450D01*
X514150Y202350D01*
G01X1175040Y197758D02*
X1175201Y197894D01*
X1175728Y199385D01*
X1176293Y201900D01*
Y202625D01*
G03X1176084Y203334I-1574J-79D01*
G01X1176059Y203376D01*
G02X1176084Y205659I2040J1119D01*
G03X1176103Y207200I-1365J787D01*
G01X1176084Y207234D01*
G02X1176059Y209517I2015J1164D01*
G01X1176084Y209559D01*
G03Y211133I-1365J787D01*
G02X1178014Y214621I2015J1163D01*
G01X1178143D01*
G03X1179464Y215409I-44J1575D01*
G02X1181409Y216572I2015J-1162D01*
G01X1182071D01*
G02X1182873Y216399I3J-1931D01*
G03X1183810Y216196I937J2062D01*
G01X1184859D01*
G01X1181479Y210346D02*
X1180325Y211011D01*
X1180015Y210927D01*
G03X1179904Y210313I1464J-582D01*
G03X1180114Y209559I1575J32D01*
G01X1180139Y209517D01*
G02X1180114Y207234I-2040J-1119D01*
G01X1180095Y207200D01*
G03X1180114Y205659I1384J-754D01*
G02X1180139Y203376I-2015J-1164D01*
G01X1180114Y203334D01*
X1180095Y203300D01*
G03X1179904Y202600I1384J-754D01*
G01Y197587D01*
X1180004Y197487D01*
Y197400D01*
G01X508700Y204632D02*
Y204719D01*
X508800Y204819D01*
Y207992D01*
X505868Y210924D01*
Y212888D01*
X506197Y213459D01*
G03X506216Y215000I-1365J787D01*
G01X506197Y215034D01*
X506172Y215076D01*
G02X508127Y218521I2040J1120D01*
G01X508256D01*
G03X509577Y220884I-44J1575D01*
G02X509552Y223167I2015J1164D01*
G01X509577Y223209D01*
X509596Y223243D01*
G03X509577Y224784I-1384J754D01*
G02X509266Y226003I2015J1163D01*
G03X508673Y227436I-2026J1D01*
G01X508212Y227896D01*
G01X505149Y206468D02*
Y206555D01*
X505049Y206655D01*
Y207916D01*
X503911Y209054D01*
Y212690D01*
X503467Y213459D01*
G02X503448Y215000I1365J787D01*
G01X503467Y215034D01*
X503492Y215076D01*
G03X503467Y217359I-2040J1119D01*
G02X504788Y219722I1365J788D01*
G01X504917D01*
G03X506872Y223167I-85J2325D01*
G01X506847Y223209D01*
X506828Y223243D01*
G02X506847Y224784I1384J754D01*
G03X506872Y227067I-2015J1164D01*
G01X506847Y227109D01*
X506828Y227143D01*
G02X508153Y229471I1384J753D01*
G01X508263D01*
G03X510252Y232917I-51J2326D01*
G01X510227Y232959D01*
G02X510964Y235191I1365J787D01*
G02X511364Y235305I628J-1445D01*
G01X511728Y235358D01*
G02X512174Y235210I75J-519D01*
G01X512258Y234899D01*
X511592Y233746D01*
G01X531871Y225947D02*
X533025Y226612D01*
X533335Y226528D01*
G02X533236Y225159I-1465J-582D01*
G03X535181Y221671I2015J-1163D01*
G01X535310D01*
G02X536616Y220884I-59J-1575D01*
G03X538546Y219722I2015J1163D01*
G01X538675D01*
G02X539996Y217359I-44J-1575D01*
G03X539971Y215076I2015J-1164D01*
G01X539996Y215034D01*
X540015Y215000D01*
G02X539996Y213459I-1384J-754D01*
G03X541924Y209972I2015J-1162D01*
G01X542068D01*
G02X543393Y209155I-57J-1575D01*
G02X543880Y207254I-3466J-1901D01*
G01X543881Y207255D01*
Y206409D01*
X545750Y204540D01*
Y204399D01*
X545812Y204337D01*
G01X1153204Y205181D02*
X1153250Y205254D01*
X1153218Y205392D01*
X1156244Y210144D01*
Y212298D01*
G02X1156455Y213084I1576J-2D01*
G03X1156483Y215359I-2015J1162D01*
G01X1156480Y215364D01*
X1156436Y215443D01*
G02X1156455Y216984I1384J754D01*
G03X1154510Y220472I-2015J1163D01*
G01X1154381D01*
G02X1153203Y221071I60J1575D01*
G01X1153286Y221381D01*
X1154440Y222047D01*
G01X531871Y233746D02*
G02X531377Y232593I-1594J1D01*
G01X530265Y231532D01*
G03X529856Y228684I1606J-1684D01*
G02X529875Y227143I-1365J-787D01*
G01X529856Y227109D01*
X529831Y227067D01*
G03X529856Y224784I2040J-1119D01*
G02X529875Y223243I-1365J-787D01*
G01X529856Y223209D01*
X529831Y223167D01*
G03X531786Y219722I2040J-1120D01*
G01X531915D01*
G02X533236Y218934I-44J-1575D01*
G03X535181Y217771I2015J1162D01*
G01X535310D01*
G02X536635Y215443I-59J-1575D01*
G01X536616Y215409D01*
X536591Y215367D01*
G03X536616Y213084I2040J-1119D01*
G02X536635Y211543I-1365J-787D01*
G01X536616Y211509D01*
G03X538561Y208021I2015J-1163D01*
G01X538702D01*
G02X539996Y207234I-71J-1574D01*
G01X543145Y201792D01*
X543108Y201656D01*
X543151Y201581D01*
G01X1151654Y198782D02*
X1151686Y198814D01*
Y198874D01*
X1151651Y198909D01*
Y198923D01*
X1156523Y203795D01*
X1159600Y209428D01*
Y210727D01*
X1159835Y211133D01*
G03Y213459I-2014J1163D01*
G02X1159736Y214828I1366J787D01*
G01X1160046Y214912D01*
X1161200Y214247D01*
G01X528491Y231797D02*
X527337Y232462D01*
X527027Y232378D01*
G03X527126Y231010I1466J-582D01*
G02Y228684I-2015J-1163D01*
G03X527107Y227143I1365J-787D01*
G01X527126Y227109D01*
X527151Y227067D01*
G02X527126Y224784I-2040J-1119D01*
G03X527107Y223243I1365J-787D01*
G01X527126Y223209D01*
X527151Y223167D01*
G02X527126Y220884I-2040J-1119D01*
G03X528447Y218521I1365J-788D01*
G01X528576D01*
G02X530531Y215076I-85J-2325D01*
G01X530506Y215034D01*
X530487Y215000D01*
G03X531812Y212672I1384J-753D01*
G01X531922D01*
G02X531941Y208021I-52J-2326D01*
G01X531800D01*
G03X531812Y204872I70J-1574D01*
G01X531941D01*
G02X533886Y203709I-70J-2325D01*
G01X534462Y202712D01*
X535189Y201985D01*
X535711D01*
X536206Y201490D01*
Y200968D01*
X536701Y200473D01*
X537223D01*
X537718Y199978D01*
Y199456D01*
X538438Y198736D01*
X538580D01*
X538641Y198675D01*
G01X525111Y225947D02*
X523345Y223561D01*
G03X523096Y220884I1766J-1514D01*
G02X523115Y219343I-1365J-787D01*
G01X523096Y219309D01*
X523071Y219267D01*
G03X525026Y215822I2040J-1120D01*
G01X525155D01*
G02X526476Y213459I-44J-1575D01*
G03Y211133I2015J-1163D01*
G02Y209559I-1365J-787D01*
G01X526451Y209517D01*
G03X526476Y207234I2040J-1119D01*
G01X526495Y207200D01*
G02X526476Y205659I-1384J-754D01*
G03X526826Y202871I2015J-1163D01*
G01X532015Y197682D01*
X532076Y197479D01*
G01X1162973Y200354D02*
X1163000Y200381D01*
Y200600D01*
X1165578Y203741D01*
X1166148Y204837D01*
X1166385Y206497D01*
G02X1166595Y207234I1575J-50D01*
G03X1166907Y208400I-2015J1164D01*
G01X1167960Y210346D01*
G01X518352Y225947D02*
G03X518742Y224503I2866J-1D01*
G01X519716Y222834D01*
G02Y221260I-1364J-787D01*
G03X519681Y218994I2015J-1164D01*
G01X519716Y218934D01*
G02Y217360I-1364J-787D01*
G03X521661Y213871I2014J-1164D01*
G01X521790D01*
G02X523115Y211543I-59J-1575D01*
G01X523096Y211509D01*
G03X523071Y209226I2015J-1164D01*
G01X523096Y209184D01*
G02Y207610I-1365J-787D01*
G01X522472Y206532D01*
Y204441D01*
X522372Y204341D01*
Y204254D01*
G01X1167235Y200001D02*
X1167273Y200079D01*
X1167226Y200213D01*
X1167400Y200497D01*
X1170008Y204757D01*
X1170287Y205750D01*
Y206249D01*
X1170285Y206478D01*
G03X1169974Y207609I-2325J-31D01*
G01X1169975Y207610D01*
G02Y209184I1364J787D01*
G01X1170000Y209226D01*
G03X1169975Y211509I-2040J1119D01*
G02X1169876Y212877I1364J786D01*
G01X1170186Y212961D01*
X1171339Y212296D01*
G01X1174719Y214247D02*
G03X1172967Y211964I7801J-7800D01*
G01X1172704Y211509D01*
G03X1172679Y209226I2015J-1164D01*
G01X1172704Y209184D01*
G02Y207610I-1365J-787D01*
G01X1172703Y207609D01*
X1172704D01*
G03X1172394Y206403I2015J-1161D01*
G01Y203553D01*
X1171781Y202941D01*
X1171208Y200922D01*
X1171091Y200857D01*
X1171068Y200773D01*
G01X518700Y201055D02*
Y201142D01*
X518600Y201242D01*
Y203503D01*
X517728Y204375D01*
X516962Y205705D01*
G02X516777Y206399I1381J740D01*
G02X518293Y208020I1575J46D01*
G02X518422I64J-1722D01*
G03X518692Y212647I-70J2325D01*
G03X518352Y212671I-340J-2396D01*
G01X518333D01*
G02X516968Y215000I19J1576D01*
G01X516987Y215034D01*
X517012Y215076D01*
G03X516987Y217359I-2040J1119D01*
G02X516968Y218900I1365J787D01*
G01X516987Y218934D01*
X517012Y218976D01*
G03X516987Y221259I-2040J1119D01*
G02X516968Y222800I1365J787D01*
G01X516987Y222834D01*
X517012Y222876D01*
G03X516987Y225159I-2040J1119D01*
G02X518308Y227522I1365J788D01*
G01X518450D01*
G03X520367Y228683I-98J2325D01*
G01X520380Y228706D01*
G02X521729Y229470I1349J-809D01*
G01X523151D01*
G02X523675Y228946I0J-524D01*
G02X522625Y227896I-1050J0D01*
G01X521731D01*
G01X553427Y209203D02*
X553146D01*
X553046Y209303D01*
X548116D01*
X547403Y210016D01*
X546733Y211175D01*
G02X546756Y213459I2038J1122D01*
G03X545435Y215822I-1365J788D01*
G01X545306D01*
G02X543351Y219267I85J2325D01*
G01X543376Y219309D01*
X543395Y219343D01*
G03X542070Y221671I-1384J753D01*
G01X541941D01*
G02X539996Y222834I70J2325D01*
G03X538675Y223622I-1365J-787D01*
G01X538546D01*
G02X536591Y227067I85J2325D01*
G01X536616Y227109D01*
X536635Y227143D01*
G03X536616Y228684I-1384J754D01*
G02X536304Y229826I2014J1164D01*
G03X535655Y231393I-2216J0D01*
G01X535251Y231797D01*
G01X546484Y205009D02*
X546423Y205070D01*
X546281D01*
X544631Y206720D01*
Y207254D01*
G03X544051Y209517I-4704J0D01*
G03X542081Y210722I-2039J-1120D01*
G01X541940D01*
G02X540646Y213084I71J1574D01*
G03X540671Y215367I-2015J1164D01*
G01X540646Y215409D01*
X540627Y215443D01*
G02X540646Y216984I1384J754D01*
G03X538701Y220472I-2015J1163D01*
G01X538572D01*
G02X537266Y221259I59J1575D01*
G03X535336Y222421I-2015J-1163D01*
G01X535207D01*
G02X533886Y224784I44J1575D01*
G03X534003Y226880I-2015J1164D01*
G01X534097Y227231D01*
X535251Y227896D01*
G01X538631Y233746D02*
X538985Y234100D01*
X539677D01*
X540100Y233677D01*
Y233349D01*
G02X539996Y232959I-782J0D01*
G01X539971Y232917D01*
G03X539996Y230634I2040J-1119D01*
G01X540015Y230600D01*
G02X539996Y229059I-1384J-754D01*
G03X541941Y225571I2015J-1163D01*
G01X542070D01*
G02X543376Y224784I-59J-1575D01*
G03X545306Y223622I2015J1163D01*
G01X545435D01*
G02X546756Y221259I-44J-1575D01*
G03X548701Y217771I2015J-1163D01*
G01X548830D01*
G02X550136Y216984I-59J-1575D01*
G03X552066Y215822I2015J1163D01*
G01X552208D01*
G02X553516Y215034I-57J-1575D01*
G01X554134Y213962D01*
X554826Y213271D01*
X558644D01*
X558744Y213171D01*
G01X1143257Y205237D02*
Y205379D01*
X1146167Y208289D01*
Y210406D01*
X1147682Y211921D01*
X1147731D01*
G03X1149720Y215367I-51J2326D01*
G01X1149695Y215409D01*
X1149676Y215443D01*
G02X1149485Y216199I1385J752D01*
G02X1149596Y216778I1576J-2D01*
G01X1149906Y216862D01*
X1151060Y216196D01*
G01X538631Y229847D02*
Y230269D01*
X538165Y230735D01*
G03X537098Y230354I-443J-443D01*
G01X537063Y230004D01*
G03X537055Y229833I1568J-159D01*
G03X537266Y229059I1576J14D01*
G02X537291Y226776I-2015J-1164D01*
G01X537266Y226734D01*
X537247Y226700D01*
G03X538572Y224372I1384J-753D01*
G01X538701D01*
G02X540646Y223209I-70J-2325D01*
G03X541967Y222421I1365J787D01*
G01X542096D01*
G02X544051Y218976I-85J-2325D01*
G01X544026Y218934D01*
X544007Y218900D01*
G03X545332Y216572I1384J-753D01*
G01X545461D01*
G02X547406Y213084I-70J-2325D01*
G03X547387Y211543I1365J-787D01*
G01X548003Y210477D01*
X548427Y210053D01*
X548894D01*
X549262Y210421D01*
X549962D01*
X550330Y210053D01*
X551030D01*
X551398Y210421D01*
X552098D01*
X552466Y210053D01*
X553046D01*
X553146Y210153D01*
G01X1148399Y207459D02*
X1148540D01*
X1152636Y211555D01*
Y211988D01*
X1152635Y212299D01*
G03X1152425Y213084I-1576J-1D01*
G02X1152561Y215619I2015J1163D01*
G01X1154440Y218147D01*
G01X541260Y409972D02*
Y409885D01*
X541160Y409785D01*
Y403681D01*
X541550Y403291D01*
Y402591D01*
X541160Y402201D01*
Y398406D01*
X537516Y394762D01*
G03X537334Y394543I1117J-1113D01*
G03X537251Y394409I1297J-896D01*
G03X537265Y392860I1380J-762D01*
G01Y392861D01*
G03X537266Y392859I1406J702D01*
G02X537309Y392781I-2015J-1162D01*
G02X537292Y390580I-2058J-1085D01*
G01X537247Y390500D01*
G03X537266Y388959I1384J-754D01*
G02X537291Y386676I-2015J-1164D01*
G01X537266Y386634D01*
X537247Y386600D01*
G03X537266Y385059I1384J-754D01*
G02X537291Y382776I-2015J-1164D01*
G01X537266Y382734D01*
X537247Y382700D01*
G03X537266Y381159I1384J-754D01*
G02X537291Y378876I-2015J-1164D01*
G01X537266Y378834D01*
X537247Y378800D01*
G03X537266Y377259I1384J-754D01*
G02Y374933I-2015J-1163D01*
G03Y373359I1365J-787D01*
G01X537291Y373317D01*
G02X537266Y371034I-2040J-1119D01*
G01X537247Y371000D01*
G03X537266Y369459I1384J-754D01*
G02X535321Y365971I-2015J-1163D01*
G01X535192D01*
G03X533867Y363643I59J-1575D01*
G01X533886Y363609D01*
X533911Y363567D01*
G02X533886Y361284I-2040J-1119D01*
G03X533867Y359743I1365J-787D01*
G01X533886Y359709D01*
X533911Y359667D01*
G02X533886Y357384I-2040J-1119D01*
G03X533867Y355843I1365J-787D01*
G01X533886Y355809D01*
X533911Y355767D01*
G02X533886Y353484I-2040J-1119D01*
G03X533787Y352115I1366J-787D01*
G01X534097Y352031D01*
X535251Y352696D01*
G01X540310Y409972D02*
Y409885D01*
X540410Y409785D01*
Y398717D01*
X536985Y395292D01*
G03X536716Y394969I1646J-1644D01*
G03X536601Y394784I1916J-1320D01*
G01X536599Y394782D01*
G03X536614Y392485I2032J-1135D01*
G01X536645Y392431D01*
G02X536635Y390943I-1394J-735D01*
G01X536625Y390926D01*
X536622Y390920D01*
X536620Y390917D01*
X536616Y390909D01*
X536591Y390867D01*
G03X536616Y388584I2040J-1119D01*
G02X536635Y387043I-1365J-787D01*
G01X536616Y387009D01*
X536591Y386967D01*
G03X536616Y384684I2040J-1119D01*
G02X536635Y383143I-1365J-787D01*
G01X536616Y383109D01*
X536591Y383067D01*
G03X536616Y380784I2040J-1119D01*
G02X536635Y379243I-1365J-787D01*
G01X536616Y379209D01*
X536591Y379167D01*
G03X536616Y376884I2040J-1119D01*
G02X536635Y375343I-1365J-787D01*
G01X536616Y375309D01*
G03X536591Y373026I2015J-1164D01*
G01X536616Y372984D01*
G02Y371410I-1365J-787D01*
G03Y369084I2015J-1163D01*
G02X535295Y366721I-1365J-788D01*
G01X535166D01*
G03X533211Y363276I85J-2325D01*
G01X533236Y363234D01*
X533255Y363200D01*
G02X533236Y361659I-1384J-754D01*
G03X533211Y359376I2015J-1164D01*
G01X533236Y359334D01*
X533255Y359300D01*
G02X533236Y357759I-1384J-754D01*
G03X533211Y355476I2015J-1164D01*
G01X533236Y355434D01*
X533255Y355400D01*
G02X533236Y353859I-1384J-754D01*
G03X533119Y351763I2015J-1164D01*
G01X533025Y351412D01*
X531871Y350747D01*
G01X1191399Y200169D02*
X1191384Y200255D01*
X1191269Y200334D01*
X1190720Y203390D01*
X1190070Y204520D01*
X1190079Y204980D01*
X1190254Y205284D01*
G03Y207610I-2015J1163D01*
G02Y209184I1365J787D01*
G01X1190279Y209226D01*
G03X1190254Y211509I-2040J1119D01*
G01X1190235Y211543D01*
G02X1190254Y213084I1384J754D01*
G03X1190279Y215367I-2015J1164D01*
G01X1190254Y215409D01*
X1190235Y215443D01*
G02X1190410Y217206I1384J753D01*
G02X1191391Y217755I1209J-1010D01*
G01X1191573Y217782D01*
G02X1192118Y216695I92J-634D01*
G01X1191619Y216196D01*
G01X1202683Y206922D02*
X1202753Y207044D01*
X1202294Y208700D01*
X1201849Y208952D01*
X1201661Y209632D01*
X1201914Y210076D01*
X1201727Y210752D01*
X1201282Y211004D01*
X1201095Y211680D01*
X1201348Y212124D01*
X1201161Y212800D01*
X1200716Y213052D01*
X1200529Y213728D01*
X1200782Y214172D01*
X1200247Y216114D01*
X1199743Y216984D01*
X1199744D01*
G02X1199719Y219267I2015J1164D01*
G01X1199744Y219309D01*
X1199763Y219343D01*
G03X1199670Y220999I-1384J753D01*
G01X1199469Y221286D01*
G03X1198379Y220943I-491J-343D01*
G01Y220096D01*
G01X568955Y217743D02*
X568894Y217804D01*
Y217946D01*
X565168Y221672D01*
X561560D01*
X560485Y222747D01*
X560432Y222848D01*
G03X559600Y223622I-1521J-801D01*
G01X558826D01*
G02X556871Y227067I85J2325D01*
G01X556896Y227109D01*
X556915Y227143D01*
G03X555590Y229471I-1384J753D01*
G01X555472D01*
G03X554166Y228684I59J-1575D01*
G02X552236Y227522I-2015J1163D01*
G01X552066D01*
G02X550136Y228684I85J2325D01*
G03X548830Y229471I-1365J-788D01*
G01X548720D01*
G02X546897Y230417I50J2326D01*
G01X546545Y230512D01*
X545391Y229847D01*
G01X1144300Y212296D02*
X1144817D01*
G03Y213871I0J788D01*
G01X1142630D01*
X1141620Y212861D01*
Y209006D01*
X1139580Y206966D01*
Y206462D01*
X1139085Y205967D01*
X1138581D01*
X1137514Y204900D01*
X1137000D01*
X1136029Y203929D01*
Y203810D01*
G01X568319Y213159D02*
Y213300D01*
X566620Y214999D01*
X566114Y214998D01*
X565500Y215612D01*
X565502Y216117D01*
X564469Y217150D01*
X562490Y217146D01*
X560854Y218128D01*
X560420Y218947D01*
G03X559572Y219722I-1509J-800D01*
G01X558826D01*
G02X556896Y220884I85J2325D01*
G03X555590Y221671I-1365J-788D01*
G01X555461D01*
G02X553516Y222834I70J2325D01*
G03X552195Y223622I-1365J-787D01*
G01X552066D01*
G02X550136Y224784I85J2325D01*
G03X548830Y225571I-1365J-788D01*
G01X548701D01*
G02X546756Y226734I70J2325D01*
G03X545435Y227522I-1365J-787D01*
G01X545306D01*
G02X543376Y228684I85J2325D01*
G03X542919Y229184I-1365J-789D01*
G03X542011Y228713I-332J-471D01*
G01Y227896D01*
G01Y235696D02*
X540857Y235031D01*
X540763Y234679D01*
G02X540815Y232966I-2105J-921D01*
G01X540719Y232706D01*
X540646Y232584D01*
G03Y231010I1365J-787D01*
G02Y228684I-2015J-1163D01*
G03X541967Y226321I1365J-788D01*
G01X542096D01*
G02X544026Y225159I-85J-2325D01*
G03X545332Y224372I1365J788D01*
G01X545461D01*
G02X547406Y220884I-70J-2325D01*
G03X548727Y218521I1365J-788D01*
G01X548856D01*
G02X550786Y217359I-85J-2325D01*
G03X552092Y216572I1365J788D01*
G01X552221D01*
G02X554166Y215409I-70J-2325D01*
G01X554735Y214423D01*
X555137Y214021D01*
X555962D01*
X556138Y214197D01*
Y214198D01*
X556314Y214374D01*
X557014D01*
X557190Y214198D01*
Y214197D01*
X557366Y214021D01*
X558644D01*
X558744Y214121D01*
G01X1142584Y205909D02*
X1142726D01*
X1143816Y206999D01*
Y207498D01*
X1144313Y207995D01*
X1144812D01*
X1145417Y208600D01*
Y210717D01*
X1147371Y212671D01*
X1147722D01*
G03X1147739Y212672I-84J1574D01*
G03X1149064Y215000I-59J1575D01*
G01X1149045Y215034D01*
X1149020Y215076D01*
G02X1148733Y216200I2039J1119D01*
G03X1148101Y217726I-2158J0D01*
G01X1147680Y218147D01*
G01X548771Y231797D02*
X547617Y231132D01*
X547534Y230822D01*
G03X548727Y230222I1238J975D01*
G01X548822D01*
G02X550786Y229059I-51J-2326D01*
G03X552092Y228272I1365J788D01*
G01X552210D01*
G03X553516Y229059I-59J1575D01*
G02X555443Y230222I2016J-1162D01*
G02X555618I88J-2325D01*
G02X557571Y226776I-86J-2325D01*
G01X557546Y226734D01*
X557527Y226700D01*
G03X558852Y224372I1384J-753D01*
G01X559743D01*
G02X561096Y223197I-832J-2325D01*
G01X561871Y222422D01*
X565479D01*
X569425Y218476D01*
X569566D01*
X569627Y218415D01*
G01X1128694Y208900D02*
X1128822Y208772D01*
X1131131D01*
X1136146Y208700D01*
X1137099D01*
X1138350Y209951D01*
Y214146D01*
X1142646Y218442D01*
X1143600D01*
X1144300Y219142D01*
Y220096D01*
G01X569022Y213800D02*
X568880D01*
X564779Y217901D01*
X562697Y217897D01*
X561419Y218665D01*
Y218664D01*
X561083Y219298D01*
G03X559709Y220472I-2172J-1151D01*
G01X558852D01*
G02X557546Y221259I59J1575D01*
G03X555616Y222421I-2015J-1163D01*
G01X555487D01*
G02X554166Y223209I44J1575D01*
G03X552221Y224372I-2015J-1162D01*
G01X552092D01*
G02X550786Y225159I59J1575D01*
G03X548856Y226321I-2015J-1163D01*
G01X548727D01*
G02X547406Y227109I44J1575D01*
G03X545461Y228272I-2015J-1162D01*
G01X545332D01*
G02X544026Y229059I59J1575D01*
G01X543765Y229511D01*
G03X542011Y231797I-9565J-5523D01*
G01X562616Y223996D02*
X562004D01*
X561504Y224496D01*
Y225204D01*
X561874Y225574D01*
X566492D01*
X569456Y222610D01*
X585495D01*
X586785Y223900D01*
X586929D01*
G01X1203460Y315668D02*
X1203560Y315568D01*
Y314325D01*
X1203376Y314141D01*
X1203375D01*
X1203191Y313957D01*
Y313257D01*
X1203375Y313073D01*
X1203376D01*
X1203560Y312889D01*
Y312096D01*
X1202080Y309770D01*
X1199480Y308370D01*
X1198466Y308221D01*
G03X1196364Y307059I-87J-2325D01*
G02X1195058Y306272I-1365J788D01*
G01X1194929D01*
G03X1192984Y305109I70J-2325D01*
G02X1191663Y304321I-1365J787D01*
G01X1191534D01*
G03X1189604Y303159I85J-2325D01*
G02X1188298Y302372I-1365J788D01*
G01X1188169D01*
G03X1186224Y301209I70J-2325D01*
G02X1184903Y300421I-1365J787D01*
G01X1184774D01*
G03X1182844Y299259I85J-2325D01*
G02X1181538Y298472I-1365J788D01*
G01X1181409D01*
G03X1179464Y294984I70J-2325D01*
G02X1179483Y293443I-1365J-787D01*
G01X1179464Y293409D01*
X1179439Y293367D01*
G03X1179464Y291084I2040J-1119D01*
G02X1179483Y289543I-1365J-787D01*
G01X1179464Y289509D01*
X1179439Y289467D01*
G03X1179464Y287184I2040J-1119D01*
G02X1179483Y285643I-1365J-787D01*
G01X1179464Y285609D01*
X1179439Y285567D01*
G03X1179464Y283284I2040J-1119D01*
G02X1179563Y281915I-1366J-787D01*
G01X1179253Y281831D01*
X1178099Y282496D01*
G01X555531Y259096D02*
X556935Y260500D01*
X557839D01*
X558289Y260050D01*
X568350D01*
X573050Y264750D01*
X574481D01*
X574606Y264625D01*
G01X1209657Y267372D02*
X1209570D01*
X1209470Y267272D01*
X1208517D01*
G02X1207154Y268059I0J1573D01*
G03X1205147Y269218I-2007J-1158D01*
G01X1205131D01*
G03X1203124Y268059I0J-2317D01*
G02X1201818Y267272I-1365J788D01*
G01X1201700D01*
G02X1200394Y268059I59J1575D01*
G03X1198464Y269221I-2015J-1163D01*
G01X1198294D01*
G03X1196364Y268059I85J-2325D01*
G02X1195058Y267272I-1365J788D01*
G01X1194929D01*
G03X1192984Y266109I70J-2325D01*
G02X1191663Y265321I-1365J787D01*
G01X1191534D01*
G03X1189604Y264159I85J-2325D01*
G02X1188308Y263372I-1365J788D01*
G01X1185767D01*
G03X1184859Y262996I0J-1284D01*
G01X575056Y269775D02*
X574976D01*
X574851Y269650D01*
X573490D01*
X567040Y263200D01*
X558401D01*
X557688Y263913D01*
X557546Y264159D01*
G03X555616Y265321I-2015J-1163D01*
G01X554679D01*
G02X554200Y265800I0J479D01*
G02X555296Y266896I1096J0D01*
G01X555531D01*
G01X1194999Y261047D02*
X1196153Y260381D01*
X1196505Y260476D01*
G02X1198294Y261421I1873J-1380D01*
G01X1198464D01*
G02X1200394Y260259I-85J-2325D01*
G03X1201700Y259472I1365J788D01*
G01X1201818D01*
G03X1203124Y260259I-59J1575D01*
G02X1205054Y261421I2015J-1163D01*
G01X1211380D01*
X1212101Y260700D01*
X1217908D01*
X1222001Y264793D01*
X1223560Y265631D01*
X1223676Y265805D01*
G01X575776Y273325D02*
X575651Y273450D01*
X574821D01*
X566926Y265555D01*
G01X574776Y278775D02*
X574666Y278665D01*
X573765D01*
X571592Y276492D01*
X571126D01*
X570672Y276038D01*
Y275572D01*
X570100Y275000D01*
X569634D01*
X569100Y274466D01*
Y274000D01*
X568500Y273400D01*
X568034D01*
X567500Y272866D01*
Y272400D01*
X566300Y271200D01*
X563599D01*
X560208Y267809D01*
G02X558911Y267272I-1297J1299D01*
G01X558852D01*
G02X557336Y268837I60J1575D01*
G02X557447Y269428I1576J10D01*
G01X557757Y269512D01*
X558911Y268847D01*
G01X552151D02*
Y270178D01*
X552407Y270434D01*
G03X554166Y271584I-256J2312D01*
G02X555472Y272371I1365J-788D01*
G01X555590D01*
G02X556896Y271584I-59J-1575D01*
G03X558827Y270422I2015J1163D01*
G01X559922D01*
X563050Y273550D01*
X565211D01*
X574061Y282400D01*
X574681D01*
X574756Y282325D01*
X574800D01*
G01X1223200Y252531D02*
X1223100Y252431D01*
X1215569D01*
X1214300Y253700D01*
X1211700D01*
X1209828Y255572D01*
X1208449D01*
G03X1206504Y252084I70J-2325D01*
G02X1205210Y249722I-1365J-788D01*
G01X1205068D01*
G02X1203774Y250509I71J1574D01*
G03X1201829Y251672I-2015J-1162D01*
G01X1201700D01*
G02X1200394Y252459I59J1575D01*
G03X1198464Y253621I-2015J-1163D01*
G01X1198335D01*
G02X1197014Y254409I44J1575D01*
G03X1192984I-2015J-1162D01*
G02X1191663Y253621I-1365J787D01*
G01X1191534D01*
G03X1189711Y252629I84J-2325D01*
G01X1189438Y252555D01*
X1188239Y253247D01*
G01X575492Y289137D02*
Y288993D01*
X566787Y280288D01*
X566289D01*
X565690Y279689D01*
Y279190D01*
X564750Y278250D01*
X563303D01*
X562188Y277788D01*
X560650Y276250D01*
X557713D01*
X557578Y276385D01*
G03X557510Y276431I-2058J-2969D01*
G03X555531Y277021I-1978J-3022D01*
G01X555446D01*
G03X553516Y275859I85J-2325D01*
G02X552222Y275072I-1365J787D01*
G01X551472D01*
G02X550786Y275758I0J686D01*
G02X551674Y276646I888J0D01*
G01X552151D01*
G01X571841Y288989D02*
X571780Y288928D01*
X571640Y288929D01*
X562861Y280150D01*
X561648Y279647D01*
X560223Y278222D01*
X558851D01*
G02X557684Y278705I0J1651D01*
G01X557130Y279260D01*
G02X557068Y279343I247J249D01*
G01X557040Y279397D01*
G03X556193Y280171I-1509J-801D01*
G01X555472D01*
G03X554294Y279572I60J-1575D01*
G01X554377Y279262D01*
X555531Y278596D01*
G01X562640Y231735D02*
X562637Y230485D01*
X563137Y229985D01*
X566866D01*
X570991Y225860D01*
X583261D01*
X584720Y227319D01*
Y227459D01*
G01X1208948Y309642D02*
X1208807D01*
X1206570Y307405D01*
X1204744Y307511D01*
X1203052Y306782D01*
X1199061Y303540D01*
X1198762Y303559D01*
X1198450Y303571D01*
X1198320D01*
G03X1197014Y302784I59J-1575D01*
G02X1195084Y301622I-2015J1163D01*
G01X1194955D01*
G03X1193634Y300834I44J-1575D01*
G02X1191689Y299671I-2015J1162D01*
G01X1191560D01*
G03X1190254Y298884I59J-1575D01*
G02X1188324Y297722I-2015J1163D01*
G01X1188195D01*
G03X1186874Y296934I44J-1575D01*
G02X1184929Y295771I-2015J1162D01*
G01X1184800D01*
G03X1183475Y293443I59J-1575D01*
G01X1183494Y293409D01*
X1183519Y293367D01*
G02X1183494Y291084I-2040J-1119D01*
G03X1183475Y289543I1365J-787D01*
G01X1183494Y289509D01*
X1183519Y289467D01*
G02X1183494Y287184I-2040J-1119D01*
G03X1183284Y286400I1366J-786D01*
G03X1184859Y286396I788J0D01*
G01X570404Y229015D02*
X571315Y229840D01*
X571324Y229837D01*
X573633D01*
X575850Y227620D01*
X581470D01*
X584135Y230285D01*
X584278D01*
G01X555531Y243496D02*
G02X556444Y243874I913J-913D01*
G01X558899D01*
G02X560926Y242709I11J-2326D01*
G01X566439Y237196D01*
X568296D01*
X568400Y237300D01*
G01X1212528Y298819D02*
X1212441D01*
X1212341Y298919D01*
X1211607D01*
X1206514Y295771D01*
X1204855D01*
X1200993Y294072D01*
X1200394Y293034D01*
G02X1198449Y291871I-2015J1162D01*
G01X1198320D01*
G03X1197014Y291084I59J-1575D01*
G02X1195084Y289922I-2015J1163D01*
G01X1194955D01*
G03X1193634Y289134I44J-1575D01*
G02X1191876Y287984I-2015J1162D01*
G01X1191619Y287727D01*
Y286396D01*
G01X567868Y243482D02*
X567182D01*
X566600Y242900D01*
Y242300D01*
X567100Y241800D01*
X571050D01*
X571450Y242200D01*
X571950D01*
X572350Y241800D01*
X572850D01*
X573250Y242200D01*
X573750D01*
X574150Y241800D01*
X574744D01*
X574900Y241956D01*
G01X552151Y253247D02*
X553216Y251062D01*
G03X555461Y248971I2314J234D01*
G01X555590D01*
G02X556896Y248184I-59J-1575D01*
G03X560895Y245875I3999J2308D01*
G01X561125D01*
X561200Y245800D01*
X561294D01*
G01X1211164Y290240D02*
X1211103Y290179D01*
Y290039D01*
X1210364Y289300D01*
X1209801D01*
X1209300Y288801D01*
Y288236D01*
X1208664Y287600D01*
X1208100D01*
X1207600Y287100D01*
Y286535D01*
X1206857Y285792D01*
X1206589Y285372D01*
G02X1205317Y284921I-1150J1224D01*
G01X1204808Y284958D01*
G02X1203923Y285711I631J1638D01*
G03X1202695Y286772I-2164J-1264D01*
G01X1201689D01*
G03X1199744Y285609I70J-2325D01*
G02X1198423Y284821I-1365J787D01*
G01X1198294D01*
G03X1196364Y283659I85J-2325D01*
G02X1195058Y282872I-1365J788D01*
G01X1194929D01*
G03X1192984Y281709I70J-2325D01*
G02X1191663Y280921I-1365J787D01*
G01X1189142D01*
G03X1188239Y280547I0J-1277D01*
G01X558911Y249347D02*
Y250678D01*
X559155Y250922D01*
X559711D01*
G03X561083Y252095I-800J2325D01*
G02X561934Y252871I1508J-799D01*
G01X563704D01*
X565682Y250893D01*
X568890D01*
X568990Y250793D01*
G01X558911Y257147D02*
X558450D01*
G03Y255572I0J-787D01*
G01X558970D01*
G03X560276Y256359I-59J1575D01*
G02X562347Y257556I2073J-1196D01*
G01X564145D01*
X565955Y255746D01*
X567147D01*
X567251Y255850D01*
G01X1221789Y283536D02*
X1221580Y283569D01*
X1220335Y283141D01*
X1217411Y282550D01*
X1214273D01*
X1208573Y276850D01*
X1206690D01*
X1206111Y276271D01*
X1205054D01*
G02X1203124Y277433I85J2325D01*
G03X1200394I-1365J-787D01*
G02X1198464Y276271I-2015J1163D01*
G01X1198335D01*
G03X1197014Y275483I44J-1575D01*
G02X1195084Y274321I-2015J1163D01*
G01X1194928D01*
G03X1193634Y273534I71J-1574D01*
G02X1191689Y272371I-2015J1162D01*
G01X1191560D01*
G03X1190254Y271584I59J-1575D01*
G02X1188495Y270434I-2015J1162D01*
G01X1188239Y270178D01*
Y268847D01*
G01X558911Y225947D02*
X561186D01*
X561563Y226324D01*
X566803D01*
X569767Y223360D01*
X585184D01*
X586300Y224476D01*
Y224616D01*
G01X1204410Y315668D02*
X1204310Y315568D01*
Y311877D01*
X1202608Y309202D01*
X1199720Y307646D01*
X1198507Y307468D01*
X1198438Y307471D01*
G03X1197014Y306684I-59J-1575D01*
G02X1195084Y305522I-2015J1163D01*
G01X1194955D01*
G03X1193634Y304734I44J-1575D01*
G02X1191689Y303571I-2015J1162D01*
G01X1191560D01*
G03X1190254Y302784I59J-1575D01*
G02X1188324Y301622I-2015J1163D01*
G01X1188195D01*
G03X1186874Y300834I44J-1575D01*
G02X1184929Y299671I-2015J1162D01*
G01X1184800D01*
G03X1183494Y298884I59J-1575D01*
G02X1181564Y297722I-2015J1163D01*
G01X1181435D01*
G03X1180114Y295359I44J-1575D01*
G02X1180139Y293076I-2015J-1164D01*
G01X1180114Y293034D01*
X1180095Y293000D01*
G03X1180114Y291459I1384J-754D01*
G02X1180139Y289176I-2015J-1164D01*
G01X1180114Y289134D01*
X1180095Y289100D01*
G03X1180114Y287559I1384J-754D01*
G02X1180139Y285276I-2015J-1164D01*
G01X1180114Y285234D01*
X1180095Y285200D01*
G03X1180114Y283659I1384J-754D01*
G02X1180231Y281563I-2015J-1164D01*
G01X1180325Y281212D01*
X1181479Y280547D01*
G01X574606Y265575D02*
X574576D01*
X574501Y265500D01*
X572739D01*
X568039Y260800D01*
X558600D01*
X558150Y261250D01*
X557277D01*
X555531Y262996D01*
G01X1209657Y266422D02*
X1209570D01*
X1209470Y266522D01*
X1208518D01*
G02X1206504Y267684I-2J2323D01*
G03X1205146Y268468I-1358J-783D01*
G01X1205132D01*
G03X1203774Y267684I0J-1567D01*
G02X1201831Y266522I-2015J1163D01*
G01X1201674D01*
G02X1199744Y267684I85J2325D01*
G03X1198438Y268471I-1365J-788D01*
G01X1198320D01*
G03X1197014Y267684I59J-1575D01*
G02X1195084Y266522I-2015J1163D01*
G01X1194955D01*
G03X1193634Y265734I44J-1575D01*
G02X1191689Y264571I-2015J1162D01*
G01X1191560D01*
G03X1190254Y263784I59J-1575D01*
G02X1188324Y262622I-2015J1163D01*
G01X1187850D01*
G03Y261047I0J-788D01*
G01X1188239D01*
G01X552151Y264947D02*
G03X553059Y264571I908J908D01*
G01X555600D01*
G02X556896Y263784I-69J-1575D01*
G01X557087Y263452D01*
X558090Y262450D01*
X567351D01*
X573801Y268900D01*
X574981D01*
X575056Y268825D01*
G01X1222001Y268645D02*
X1222000Y268644D01*
Y268452D01*
X1220557Y267009D01*
X1220091D01*
X1219600Y266518D01*
Y266052D01*
X1219048Y265500D01*
X1218600D01*
X1218100Y265000D01*
Y264552D01*
X1216748Y263200D01*
X1213100D01*
X1212928Y263372D01*
X1207836D01*
X1207301Y263907D01*
X1207154Y264159D01*
G03X1205224Y265321I-2015J-1163D01*
G01X1205054D01*
G03X1203124Y264159I85J-2325D01*
G02X1201818Y263372I-1365J788D01*
G01X1201700D01*
G02X1200394Y264159I59J1575D01*
G03X1198464Y265321I-2015J-1163D01*
G01X1198294D01*
G03X1196364Y264159I85J-2325D01*
G02X1195058Y263372I-1365J788D01*
G01X1194929D01*
G03X1192984Y262209I70J-2325D01*
G02X1191847Y261437I-1365J787D01*
G01X1191619Y261665D01*
Y262996D01*
G01X575776Y274275D02*
X575732D01*
X575657Y274200D01*
X574510D01*
X572910Y272600D01*
X572400D01*
X571900Y272100D01*
Y271600D01*
X571200Y270900D01*
X570701D01*
X570200Y270399D01*
Y269890D01*
X569638Y269328D01*
X569127D01*
X568718Y268919D01*
Y268408D01*
X568365Y268055D01*
X566926D01*
G01X1191619Y255196D02*
X1192773Y255862D01*
X1192867Y256214D01*
G02X1194929Y259472I2131J933D01*
G01X1195069D01*
G02X1197014Y258309I-70J-2325D01*
G03X1198335Y257521I1365J787D01*
G01X1198464D01*
G02X1200394Y256359I-85J-2325D01*
G03X1201700Y255572I1365J788D01*
G01X1201818D01*
G03X1203124Y256359I-59J1575D01*
G02X1205054Y257521I2015J-1163D01*
G01X1205183D01*
G03X1206504Y258309I-44J1575D01*
G01X1206941Y259066D01*
X1208031Y259472D01*
X1209828D01*
X1212469Y256831D01*
X1221803D01*
X1221903Y256931D01*
X1221990D01*
G01X574884Y277825D02*
X574789Y277915D01*
X574076D01*
X566611Y270450D01*
X563910D01*
X560739Y267279D01*
Y267278D01*
G02X558911Y266522I-1827J1830D01*
G01X558826D01*
G02X556584Y268832I85J2325D01*
G03X555940Y270387I-2199J0D01*
G01X555531Y270796D01*
G01X574800Y283275D02*
X574675Y283150D01*
X573750D01*
X564900Y274300D01*
X562739D01*
X559611Y271172D01*
X558842D01*
G02X557546Y271959I69J1575D01*
G03X555616Y273121I-2015J-1163D01*
G01X555446D01*
G03X553516Y271959I85J-2325D01*
G02X552379Y271188I-1365J789D01*
G01X552151Y271416D01*
Y272747D01*
G01X548771Y274696D02*
G03X549676Y274321I905J905D01*
G01X552236D01*
G03X554166Y275483I-85J2325D01*
G02X555487Y276271I1365J-787D01*
G01X555531D01*
G02X557099Y275803I0J-2862D01*
G01X557402Y275500D01*
X560961D01*
X562613Y277152D01*
X563453Y277500D01*
X565061D01*
X576026Y288465D01*
X576165D01*
G01X1224995Y248135D02*
X1224908D01*
X1224808Y248035D01*
X1223027D01*
X1222239Y248823D01*
X1210633D01*
X1209582Y247772D01*
X1201700D01*
G02X1200394Y248559I59J1575D01*
G03X1198464Y249721I-2015J-1163D01*
G01X1198335D01*
G02X1197014Y250509I44J1575D01*
G03X1195256Y251659I-2015J-1162D01*
G01X1194999Y251916D01*
Y253247D01*
G01Y245447D02*
X1196153Y246112D01*
X1196505Y246017D01*
G03X1198309Y245071I1873J1379D01*
G01X1198438D01*
G02X1199744Y244284I-59J-1575D01*
G03X1201674Y243122I2015J1163D01*
G01X1201844D01*
G03X1203774Y244284I-85J2325D01*
G02X1205120Y245072I1365J-788D01*
G01X1221017D01*
X1223202Y242887D01*
X1224153D01*
X1224253Y242787D01*
X1224340D01*
G01X571170Y289662D02*
X571109Y289601D01*
Y289459D01*
X562436Y280786D01*
X561223Y280283D01*
X559912Y278972D01*
X558851D01*
G02X558215Y279236I1J901D01*
G01X557703Y279748D01*
G03X556331Y280921I-2172J-1152D01*
G01X555446D01*
G03X553657Y279976I84J-2325D01*
G01X553305Y279881D01*
X552151Y280547D01*
G01X585392Y226787D02*
X585249D01*
X583572Y225110D01*
X570680D01*
X566555Y229235D01*
X563336D01*
X562632Y228531D01*
X562630Y227896D01*
G01X1208276Y310314D02*
Y310172D01*
X1206278Y308174D01*
X1204610Y308271D01*
X1202660Y307430D01*
X1198815Y304308D01*
X1198799Y304309D01*
X1198464Y304321D01*
X1198294D01*
G03X1196364Y303159I85J-2325D01*
G02X1195058Y302372I-1365J788D01*
G01X1194929D01*
G03X1192984Y301209I70J-2325D01*
G02X1191663Y300421I-1365J787D01*
G01X1191534D01*
G03X1189604Y299259I85J-2325D01*
G02X1188298Y298472I-1365J788D01*
G01X1188169D01*
G03X1186224Y297309I70J-2325D01*
G02X1184903Y296521I-1365J787D01*
G01X1184774D01*
G03X1182819Y293076I85J-2325D01*
G01X1182844Y293034D01*
X1182863Y293000D01*
G02X1182844Y291459I-1384J-754D01*
G03X1182819Y289176I2015J-1164D01*
G01X1182844Y289134D01*
X1182863Y289100D01*
G02X1182844Y287559I-1384J-754D01*
G03X1181479Y284447I13451J-7755D01*
G01X570528Y231543D02*
X570518Y231332D01*
X571082Y230708D01*
X571446Y230587D01*
X573944D01*
X574431Y230100D01*
X574900D01*
X575400Y229600D01*
Y229131D01*
X576161Y228370D01*
X581159D01*
X583574Y230785D01*
Y230925D01*
X583606Y230957D01*
G01X558911Y241547D02*
X558319D01*
G02X557800Y242800I0J734D01*
G02X558580Y243123I780J-780D01*
G01X558902D01*
G02X560275Y242334I8J-1575D01*
G01X560325Y242248D01*
X566128Y236446D01*
X568254D01*
X568350Y236350D01*
X568377D01*
G01X565124Y243496D02*
X565850Y242764D01*
Y241989D01*
X566789Y241050D01*
X574812D01*
X574856Y241006D01*
X574900D01*
G01X555531Y251296D02*
Y251949D01*
G03X554196Y252204I-692J0D01*
G01X554067Y251878D01*
G03X555487Y249721I1465J-581D01*
G01X555603D01*
G02X557546Y248559I-72J-2325D01*
G03X560895Y246625I3349J1933D01*
G01X561125D01*
X561250Y246750D01*
X561294D01*
G01X568990Y251743D02*
X568890Y251643D01*
X565993D01*
X564015Y253621D01*
X561797D01*
G03X560420Y252447I793J-2325D01*
G01X560419Y252448D01*
G02X559568Y251672I-1508J799D01*
G01X559155D01*
X558911Y251916D01*
Y253247D01*
G01X555531Y255196D02*
G03X556434Y254822I903J903D01*
G01X558983D01*
G03X560926Y255984I-72J2325D01*
G02X562348Y256806I1423J-821D01*
G01X563834D01*
X565644Y254996D01*
X567104D01*
X567200Y254900D01*
X567240D01*
G01X1217849Y278850D02*
X1217749Y278750D01*
X1212889D01*
X1209289Y275150D01*
X1207589D01*
X1206718Y274279D01*
X1206504Y273909D01*
G02X1205152Y273127I-1353J780D01*
G01X1205127D01*
G02X1203774Y273909I0J1562D01*
G03X1201846Y275071I-2015J-1162D01*
G01X1201690D01*
X1201689Y275072D01*
G03X1199744Y273909I70J-2325D01*
G02X1198423Y273121I-1365J787D01*
G01X1198294D01*
G03X1196364Y271959I85J-2325D01*
G02X1195058Y271172I-1365J788D01*
G01X1194929D01*
G03X1192984Y270009I70J-2325D01*
G02X1191663Y269221I-1365J787D01*
G01X1191534D01*
G03X1189324Y267279I85J-2325D01*
G01X1189269Y266947D01*
G02X1188239Y264947I-3637J608D01*
G01X1223200Y239250D02*
X1223100Y239150D01*
X1219641D01*
X1216870Y241921D01*
X1211405D01*
G03X1210028Y240747I793J-2325D01*
G01X1210027Y240748D01*
G02X1209176Y239972I-1508J799D01*
G01X1208460D01*
G02X1207154Y240759I59J1575D01*
G03X1205224Y241921I-2015J-1163D01*
G01X1205054D01*
G03X1203124Y240759I85J-2325D01*
G02X1201818Y239972I-1365J788D01*
G01X1201700D01*
G02X1200394Y240759I59J1575D01*
G03X1198464Y241921I-2015J-1163D01*
G01X1198335D01*
G02X1197014Y242709I44J1575D01*
G03X1195069Y243872I-2015J-1162D01*
G01X1194929D01*
G03X1193125Y242926I69J-2325D01*
G01X1192773Y242831D01*
X1191619Y243496D01*
G01X569812Y293801D02*
X569776Y293722D01*
X569644Y293674D01*
X567116Y288216D01*
X561511Y282611D01*
X560330Y282122D01*
X557817D01*
X557443Y282496D01*
X555531D01*
G01X1223260Y233900D02*
X1223160Y234000D01*
X1216470D01*
X1214590Y235880D01*
X1210270D01*
X1209711Y235321D01*
X1208468D01*
G02X1206504Y236484I51J2326D01*
G03X1205198Y237271I-1365J-788D01*
G01X1205080D01*
G03X1203774Y236484I59J-1575D01*
G02X1201846Y235322I-2015J1163D01*
G02X1201672I-87J2325D01*
G02X1199744Y236484I87J2325D01*
G03X1198438Y237271I-1365J-788D01*
G01X1198309D01*
G02X1196364Y238434I70J2325D01*
G03X1195043Y239222I-1365J-787D01*
G01X1194914D01*
G02X1192984Y240384I85J2325D01*
G03X1191678Y241171I-1365J-788D01*
G01X1191549D01*
G02X1189604Y242334I70J2325D01*
G03X1188467Y243106I-1365J-787D01*
G01X1188239Y242878D01*
Y241547D01*
G01X1223200Y229530D02*
X1223013Y229630D01*
X1216590D01*
X1212830Y233390D01*
X1211486D01*
X1210691Y232595D01*
G02X1209317Y231421I-2172J1151D01*
G01X1208449D01*
G02X1206504Y232584I70J2325D01*
G03X1205210Y233371I-1365J-787D01*
G01X1205068D01*
G03X1203774Y232584I71J-1574D01*
G02X1201829Y231421I-2015J1162D01*
G01X1201689D01*
G02X1199744Y232584I70J2325D01*
G03X1198450Y233371I-1365J-787D01*
G01X1198294D01*
G02X1196364Y234533I85J2325D01*
G03X1195043Y235321I-1365J-787D01*
G01X1194948D01*
G02X1192984Y236484I51J2326D01*
G03X1191678Y237271I-1365J-788D01*
G01X1191549D01*
G02X1189604Y238434I70J2325D01*
G03X1188283Y239222I-1365J-787D01*
G01X1188154D01*
G02X1186224Y240384I85J2325D01*
G03X1184918Y241171I-1365J-788D01*
G01X1184789D01*
G02X1182555Y243820I71J2327D01*
G01X1181479Y245447D01*
G01X1223200Y251581D02*
X1223100Y251681D01*
X1221900D01*
X1221500Y251281D01*
X1220820D01*
X1220420Y251681D01*
X1218100D01*
X1217700Y251281D01*
X1217120D01*
X1216720Y251681D01*
X1215258D01*
X1213989Y252950D01*
X1211389D01*
X1209517Y254822D01*
X1208475D01*
G03X1207154Y252459I44J-1575D01*
G02X1205237Y248972I-2015J-1163D01*
G01X1205041D01*
G02X1203124Y250134I98J2324D01*
G03X1201803Y250922I-1365J-787D01*
G01X1201674D01*
G02X1199744Y252084I85J2325D01*
G03X1198438Y252871I-1365J-788D01*
G01X1198309D01*
G02X1196364Y254034I70J2325D01*
G03X1193634I-1365J-787D01*
G02X1191689Y252871I-2015J1162D01*
G01X1191560D01*
G03X1190354Y252235I60J-1575D01*
G01X1190420Y251988D01*
X1191619Y251296D01*
G01X559211Y284447D02*
X557947D01*
X557600Y284100D01*
Y283400D01*
X558128Y282872D01*
X560180D01*
X561086Y283247D01*
X566491Y288652D01*
X568963Y293989D01*
X568949Y294199D01*
G01X1223200Y238300D02*
X1223100Y238400D01*
X1219330D01*
X1218115Y239615D01*
X1217584D01*
X1217053Y240146D01*
Y240677D01*
X1216559Y241171D01*
X1214950D01*
X1214550Y240771D01*
X1213850D01*
X1213450Y241171D01*
X1211542D01*
G03X1210691Y240395I657J-1575D01*
G02X1209319Y239222I-2172J1152D01*
G01X1208434D01*
G02X1206504Y240384I85J2325D01*
G03X1205198Y241171I-1365J-788D01*
G01X1205080D01*
G03X1203774Y240384I59J-1575D01*
G02X1201844Y239222I-2015J1163D01*
G01X1201674D01*
G02X1199744Y240384I85J2325D01*
G03X1198438Y241171I-1365J-788D01*
G01X1198309D01*
G02X1196364Y242334I70J2325D01*
G03X1195047Y243122I-1365J-786D01*
G03X1194952I-47J-1574D01*
G03X1193762Y242522I48J-1574D01*
G01X1193845Y242212D01*
X1194630Y241760D01*
X1194999Y241547D01*
G01X1223200Y234850D02*
X1223113D01*
X1223013Y234750D01*
X1216781D01*
X1214901Y236630D01*
X1209959D01*
X1209400Y236071D01*
X1208478D01*
G02X1208460Y236072I78J1574D01*
G02X1207154Y236859I59J1575D01*
G03X1205224Y238021I-2015J-1163D01*
G01X1205054D01*
G03X1203124Y236859I85J-2325D01*
G02X1201818Y236072I-1365J788D01*
G01X1201700D01*
G02X1200394Y236859I59J1575D01*
G03X1198464Y238021I-2015J-1163D01*
G01X1198335D01*
G02X1197014Y238809I44J1575D01*
G03X1195069Y239972I-2015J-1162D01*
G01X1194940D01*
G02X1193634Y240759I59J1575D01*
G03X1191704Y241921I-2015J-1163D01*
G01X1191575D01*
G02X1190254Y242709I44J1575D01*
G03X1188496Y243859I-2015J-1162D01*
G01X1188239Y244116D01*
Y245447D01*
G01X1223200Y230480D02*
X1223013Y230380D01*
X1221301D01*
X1220901Y230780D01*
X1220201D01*
X1219801Y230380D01*
X1219101D01*
X1218701Y230780D01*
X1218001D01*
X1217601Y230380D01*
X1216901D01*
X1216253Y231028D01*
Y231495D01*
X1215658Y232090D01*
X1215191D01*
X1214697Y232584D01*
Y233051D01*
X1214102Y233646D01*
X1213635D01*
X1213141Y234140D01*
X1211175D01*
X1210081Y233046D01*
X1210028Y232946D01*
G02X1209180Y232171I-1509J800D01*
G01X1209177D01*
Y232172D01*
X1208448D01*
G02X1207154Y232959I71J1574D01*
G03X1205209Y234122I-2015J-1162D01*
G01X1205069D01*
G03X1203124Y232959I70J-2325D01*
G02X1201830Y232172I-1365J787D01*
G01X1201688D01*
G02X1200394Y232959I71J1574D01*
G03X1198449Y234122I-2015J-1162D01*
G01X1198308D01*
G02X1197014Y234909I71J1574D01*
G03X1195050Y236072I-2015J-1163D01*
G01X1194940D01*
G02X1193634Y236859I59J1575D01*
G03X1191704Y238021I-2015J-1163D01*
G01X1191575D01*
G02X1190254Y238809I44J1575D01*
G03X1188309Y239972I-2015J-1162D01*
G01X1188180D01*
G02X1186874Y240759I59J1575D01*
G03X1184944Y241921I-2015J-1163D01*
G01X1184815D01*
G02X1183299Y243715I45J1575D01*
G02X1183395Y244078I1561J-219D01*
G01X1183705Y244162D01*
X1184859Y243496D01*
G01X1191619Y259096D02*
Y260427D01*
X1191876Y260684D01*
G03X1193634Y261834I-257J2312D01*
G02X1194955Y262622I1365J-787D01*
G01X1195084D01*
G03X1197014Y263784I-85J2325D01*
G02X1198320Y264571I1365J-788D01*
G01X1198438D01*
G02X1199744Y263784I-59J-1575D01*
G03X1201674Y262622I2015J1163D01*
G01X1201844D01*
G03X1203774Y263784I-85J2325D01*
G02X1205080Y264571I1365J-788D01*
G01X1205208D01*
G02X1206504Y263784I-69J-1575D01*
G01X1206505Y263783D01*
Y263782D01*
X1206506Y263781D01*
X1206702Y263445D01*
X1207525Y262622D01*
X1212617D01*
X1212789Y262450D01*
X1217059D01*
X1222582Y267973D01*
X1222673D01*
G01X1194999Y257147D02*
X1193845Y256481D01*
X1193535Y256565D01*
G02X1194952Y258721I1464J581D01*
G02X1195047I47J-1575D01*
G02X1196364Y257934I-47J-1575D01*
G03X1198309Y256771I2015J1162D01*
G01X1198438D01*
G02X1199744Y255984I-59J-1575D01*
G03X1201674Y254822I2015J1163D01*
G01X1201844D01*
G03X1203774Y255984I-85J2325D01*
G02X1205080Y256771I1365J-788D01*
G01X1205193D01*
G03X1207154Y257934I-54J2325D01*
G01X1207456Y258457D01*
X1208167Y258722D01*
X1209517D01*
X1210196Y258043D01*
Y257491D01*
X1210691Y256996D01*
X1211243D01*
X1212158Y256081D01*
X1213803D01*
X1214203Y255681D01*
X1214803D01*
X1215203Y256081D01*
X1215803D01*
X1216203Y255681D01*
X1216803D01*
X1217203Y256081D01*
X1217803D01*
X1218203Y255681D01*
X1218803D01*
X1219203Y256081D01*
X1219803D01*
X1220203Y255681D01*
X1220803D01*
X1221203Y256081D01*
X1221803D01*
X1221903Y255981D01*
X1221990D01*
G01X1224995Y247185D02*
X1224908D01*
X1224808Y247285D01*
X1222716D01*
X1221928Y248073D01*
X1210944D01*
X1209893Y247022D01*
X1201687D01*
G02X1199744Y248184I72J2325D01*
G03X1198438Y248971I-1365J-788D01*
G01X1198309D01*
G02X1196364Y250134I70J2325D01*
G03X1195227Y250906I-1365J-787D01*
G01X1194999Y250678D01*
Y249347D01*
G01X1224340Y243737D02*
X1224253D01*
X1224153Y243637D01*
X1223513D01*
X1221328Y245822D01*
X1216706D01*
X1216531Y245997D01*
Y245998D01*
X1216356Y246173D01*
X1215656D01*
X1215492Y246008D01*
X1215481Y245998D01*
Y245997D01*
X1215306Y245822D01*
X1214606D01*
X1214431Y245997D01*
Y245998D01*
X1214256Y246173D01*
X1213556D01*
X1213381Y245998D01*
Y245997D01*
X1213206Y245822D01*
X1212506D01*
X1212331Y245997D01*
Y245998D01*
X1212156Y246173D01*
X1211456D01*
X1211281Y245998D01*
Y245997D01*
X1211106Y245822D01*
X1205088D01*
G03X1203124Y244659I51J-2326D01*
G02X1201818Y243872I-1365J788D01*
G01X1201700D01*
G02X1200394Y244659I59J1575D01*
G03X1198464Y245821I-2015J-1163D01*
G01X1198335D01*
G02X1197142Y246421I45J1575D01*
G01X1197225Y246731D01*
X1198379Y247396D01*
G01Y259096D02*
X1197225Y259762D01*
X1197142Y260072D01*
G02X1198320Y260671I1238J-976D01*
G01X1198438D01*
G02X1199744Y259884I-59J-1575D01*
G03X1201674Y258722I2015J1163D01*
G01X1201844D01*
G03X1203774Y259884I-85J2325D01*
G02X1205080Y260671I1365J-788D01*
G01X1211069D01*
X1211790Y259950D01*
X1212800D01*
X1213200Y259550D01*
X1213800D01*
X1214200Y259950D01*
X1218219D01*
X1222454Y264184D01*
X1223915Y264970D01*
X1223916D01*
X1224130Y264969D01*
G01X1179054Y197400D02*
Y197487D01*
X1179154Y197587D01*
Y202612D01*
G02Y202625I2326J6D01*
G01X1179153D01*
G02X1179429Y203649I2326J-78D01*
G01X1179464Y203709D01*
X1179483Y203743D01*
G03X1179464Y205284I-1384J754D01*
G02Y207610I2015J1163D01*
G03Y209184I-1365J787D01*
G01X1179439Y209226D01*
G02X1179152Y210297I2039J1120D01*
G03X1178483Y211912I-2284J0D01*
G01X1178099Y212296D01*
G01X1195556Y201235D02*
X1195450Y201341D01*
Y202974D01*
X1194630Y207040D01*
X1194538Y207496D01*
X1194009Y208909D01*
X1193634Y209559D01*
G02Y211133I1365J787D01*
G03X1193896Y212778I-2014J1164D01*
G01Y213144D01*
X1194999Y214247D01*
G01X1174719Y210346D02*
Y211677D01*
X1174491Y211905D01*
G03X1173354Y209559I227J-1559D01*
G01X1173379Y209517D01*
G02X1173354Y207234I-2040J-1119D01*
G03X1173144Y206411I1365J-787D01*
G01Y205350D01*
X1173483Y205011D01*
Y204389D01*
X1173144Y204050D01*
Y203242D01*
X1172450Y202548D01*
X1171933Y200727D01*
X1172006Y200598D01*
X1171982Y200513D01*
G01X1182948Y197409D02*
Y197496D01*
X1183048Y197594D01*
X1183054Y198195D01*
Y202590D01*
G03X1183040Y202755I-1575J-51D01*
G03X1182844Y203334I-1562J-206D01*
G01X1182819Y203376D01*
G02X1182844Y205659I2040J1119D01*
G03X1182863Y207200I-1365J787D01*
G01X1182844Y207234D01*
G02X1183050Y209860I2015J1163D01*
G01X1184734Y211942D01*
G03X1184859Y212296I-438J354D01*
G01X1144300Y216196D02*
Y217209D01*
X1143817Y217692D01*
X1142957D01*
X1139100Y213835D01*
Y209640D01*
X1137410Y207950D01*
X1136140D01*
X1131125Y208022D01*
X1128722D01*
X1128650Y207950D01*
G01X1149071Y206787D02*
Y206929D01*
X1153386Y211244D01*
Y212299D01*
G03X1153075Y213459I-2326J-2D01*
G02X1153167Y215176I1365J788D01*
G02X1154212Y215806I1273J-929D01*
G02X1154486Y215822I229J-1565D01*
G01X1154671Y215558D01*
X1154440Y214247D01*
G01X1152401Y205692D02*
X1152447Y205765D01*
X1152585Y205795D01*
X1153355Y207007D01*
X1153245Y207500D01*
X1153623Y208093D01*
X1154116Y208202D01*
X1154493Y208793D01*
X1154383Y209286D01*
X1154761Y209879D01*
X1155254Y209988D01*
X1155494Y210363D01*
Y212299D01*
G02X1155805Y213459I2326J-2D01*
G03X1155824Y215000I-1365J787D01*
G01X1155805Y215034D01*
X1155780Y215076D01*
G02X1155805Y217359I2040J1119D01*
G03X1154484Y219722I-1365J788D01*
G01X1154355D01*
G02X1152566Y220667I84J2325D01*
G03X1151696Y220733I-463J-341D01*
G01X1151060Y220096D01*
G01X1158689Y201547D02*
X1158750Y201608D01*
X1158890Y201607D01*
X1162775Y205491D01*
Y206480D01*
G03X1162565Y207234I-1575J-32D01*
G02X1162540Y209517I2015J1164D01*
G01X1162565Y209559D01*
G03Y211133I-1365J787D01*
G02Y213459I2015J1163D01*
G01X1162823Y213906D01*
G02X1164580Y216196I9573J-5526D01*
G01X1214300Y286400D02*
X1214162D01*
X1212291Y284529D01*
X1212290D01*
X1209883Y282122D01*
X1208158D01*
G03X1207310Y281347I661J-1575D01*
G02X1205359Y280172I-1952J1034D01*
G01X1205135D01*
G02X1203124Y281334I1J2323D01*
G03X1201760Y282122I-1364J-786D01*
G01X1201758D01*
G03X1200394Y281334I0J-1574D01*
G02X1198433Y280171I-2015J1162D01*
G01X1198320D01*
G03X1197014Y279384I59J-1575D01*
G02X1195050Y278221I-2015J1163D01*
G01X1194955D01*
G03X1193634Y277433I44J-1575D01*
G02X1191704Y276271I-2015J1163D01*
G01X1191575D01*
G03X1190254Y275483I44J-1575D01*
G02X1188324Y274321I-2015J1163D01*
G01X1188168D01*
G03X1186874Y273534I71J-1574D01*
G02X1184929Y272371I-2015J1162D01*
G01X1184800D01*
G03X1184116Y272185I61J-1575D01*
G01X1183807Y272019D01*
G03X1184114Y270796I307J-573D01*
G01X1184859D01*
G01X1217900Y277900D02*
X1217804Y277996D01*
X1217096D01*
X1216704Y277604D01*
X1215996D01*
X1215600Y278000D01*
X1215000D01*
X1214600Y277600D01*
X1214100D01*
X1213700Y278000D01*
X1213200D01*
X1212500Y277300D01*
Y276800D01*
X1212000Y276300D01*
X1211500D01*
X1209600Y274400D01*
X1207900D01*
X1207318Y273818D01*
X1207154Y273534D01*
G02X1205151Y272377I-2003J1155D01*
G01X1205127D01*
G02X1203124Y273534I0J2312D01*
G03X1201830Y274321I-1365J-787D01*
G01X1201688D01*
G03X1200394Y273534I71J-1574D01*
G02X1198449Y272371I-2015J1162D01*
G01X1198320D01*
G03X1197014Y271584I59J-1575D01*
G02X1195084Y270422I-2015J1163D01*
G01X1194955D01*
G03X1193634Y269634I44J-1575D01*
G02X1191689Y268471I-2015J1162D01*
G01X1191560D01*
G03X1190065Y267156I59J-1574D01*
G03X1190155Y266315I1554J-259D01*
G01X1190465Y266231D01*
X1191619Y266896D01*
G01X1150982Y199454D02*
X1151121D01*
X1155916Y204249D01*
X1158850Y209620D01*
Y210930D01*
X1159185Y211509D01*
G03X1159186Y213083I-1364J788D01*
G01X1159185Y213084D01*
G02X1159068Y215180I2015J1164D01*
G01X1158974Y215531D01*
X1157820Y216196D01*
G01X1147680Y214247D02*
G03X1146777Y214621I-903J-903D01*
G01X1142319D01*
X1140870Y213172D01*
Y209317D01*
X1137203Y205650D01*
X1136689D01*
X1135521Y204482D01*
X1135357D01*
G01X964786Y349509D02*
X961044D01*
X959094Y347559D01*
X957167D01*
X955077Y349649D01*
X953817D01*
X952003Y351463D01*
X950596D01*
X948804Y349671D01*
X946903D01*
X945111Y351463D01*
X943660D01*
X941782Y349585D01*
X940225D01*
X938645Y351165D01*
X936831D01*
X935187Y349521D01*
X933289D01*
X931496Y351314D01*
X930412D01*
X928545Y349447D01*
X926537D01*
X924150Y351834D01*
X923295D01*
X921649Y353480D01*
X920016D01*
X918255Y351719D01*
G01X916789Y359197D02*
X924725D01*
X926798Y357124D01*
X928217D01*
X930387Y359294D01*
X931754D01*
X933674Y357374D01*
X934998D01*
X936918Y359294D01*
X938412D01*
X940332Y357374D01*
X941692D01*
X943563Y359245D01*
X945416D01*
X947201Y357460D01*
X948931D01*
X950617Y359146D01*
X951726D01*
X953721Y357151D01*
X955557D01*
X957361Y355347D01*
X958888D01*
X960826Y353409D01*
X964786D01*
G01X961406Y347560D02*
X959762Y345916D01*
Y344859D01*
X958812Y343909D01*
X957169D01*
X955526Y345552D01*
X953989D01*
X952324Y347217D01*
X950405D01*
X948722Y345534D01*
X947049D01*
X945377Y347206D01*
X943437D01*
X941996Y345765D01*
X940417D01*
X938891Y347291D01*
X936991D01*
X935243Y345543D01*
X933356D01*
X931533Y347366D01*
X930089D01*
X928532Y345809D01*
X926653D01*
X924527Y347935D01*
X922865D01*
X921666Y349134D01*
X919354D01*
X918520Y348300D01*
G01X961406Y351460D02*
X957491D01*
X955589Y353362D01*
X954165D01*
X952158Y355369D01*
X950490D01*
X948697Y353576D01*
X947097D01*
X945561Y355112D01*
X943618D01*
X941974Y353468D01*
X940332D01*
X938582Y355218D01*
X936960D01*
X935112Y353370D01*
X933392D01*
X931414Y355348D01*
X930302D01*
X928424Y353470D01*
X926824D01*
X924839Y355455D01*
X923559D01*
X921721Y357293D01*
X916789D01*
G01X1167960Y261047D02*
Y260256D01*
X1170926Y257290D01*
X1172030D01*
X1173335Y255985D01*
Y254535D01*
X1173000Y254200D01*
Y252700D01*
X1174200Y251500D01*
X1174849D01*
X1176400Y249949D01*
Y246791D01*
X1176787Y246404D01*
Y244753D01*
X1176490Y244456D01*
Y242886D01*
X1177716Y241660D01*
X1178829D01*
X1181039Y239450D01*
X1182550D01*
X1184370Y237630D01*
X1185670D01*
X1187604Y235696D01*
X1188304D01*
G02X1189929Y234721I-65J-1950D01*
G03X1191554Y233746I1690J975D01*
G01X1191710D01*
G02X1193309Y232772I-91J-1949D01*
G03X1194951Y231796I1690J974D01*
G01X1195090D01*
G02X1196689Y230822I-91J-1949D01*
G03X1198361Y229846I1690J975D01*
G01X1198458D01*
G02X1199856Y229171I-79J-1950D01*
G03X1201700Y228272I1844J1442D01*
G01X1201818D01*
G03X1203124Y229059I-59J1575D01*
G02X1207154I2015J-1163D01*
G03X1208460Y228272I1365J788D01*
G01X1210022D01*
X1211300Y229550D01*
X1212899D01*
X1215699Y226750D01*
X1217277D01*
G01X1200472Y227522D02*
X1201844D01*
G03X1203774Y228684I-85J2325D01*
G02X1205080Y229471I1365J-788D01*
G01X1205198D01*
G02X1206504Y228684I-59J-1575D01*
G03X1208434Y227522I2015J1163D01*
G01X1209174D01*
G02X1210027Y226745I-655J-1575D01*
G01X1210837Y307493D02*
Y307351D01*
X1209515Y306029D01*
X1205757Y304088D01*
X1202537Y303860D01*
X1196061Y298472D01*
X1194929D01*
G03X1192984Y297309I70J-2325D01*
G02X1191663Y296521I-1365J787D01*
G01X1191534D01*
G03X1189604Y295359I85J-2325D01*
G02X1188298Y294572I-1365J788D01*
G01X1188169D01*
G03X1186224Y291084I70J-2325D01*
G02X1186243Y289543I-1365J-787D01*
G01X1186224Y289509D01*
X1186199Y289467D01*
G03X1186224Y287184I2040J-1119D01*
G02X1184903Y284821I-1365J-788D01*
G01X1184774D01*
G03X1182819Y281376I85J-2325D01*
G01X1183219Y280704D01*
G03X1184859Y278596I9261J5513D01*
G01X1212788Y302949D02*
X1212701D01*
X1212601Y303049D01*
X1211171D01*
X1210543Y302891D01*
X1210051Y302652D01*
X1209889Y302182D01*
X1209258Y301874D01*
X1208788Y302040D01*
X1208157Y301733D01*
X1207995Y301262D01*
X1207364Y300954D01*
X1206894Y301120D01*
X1206263Y300813D01*
X1206101Y300342D01*
X1205470Y300034D01*
X1205000Y300200D01*
X1203806Y299624D01*
X1203052Y298631D01*
X1200951Y297188D01*
X1200858Y296685D01*
X1200280Y296287D01*
X1199777Y296382D01*
X1198866Y295756D01*
X1198451Y295770D01*
X1198450Y295771D01*
X1198320D01*
G03X1197014Y294984I59J-1575D01*
G02X1195084Y293822I-2015J1163D01*
G01X1194955D01*
G03X1193634Y293034I44J-1575D01*
G02X1191689Y291871I-2015J1162D01*
G01X1191560D01*
G03X1190235Y289543I59J-1575D01*
G01X1190254Y289509D01*
X1190279Y289467D01*
G02X1190254Y287184I-2040J-1119D01*
G03X1190235Y285643I1365J-787D01*
G01X1190254Y285609D01*
X1190279Y285567D01*
G02X1188324Y282122I-2040J-1120D01*
G01X1188195D01*
G03X1186874Y279759I44J-1575D01*
G02Y277433I-2015J-1163D01*
G03X1186775Y276065I1365J-786D01*
G01X1187085Y275981D01*
X1188239Y276646D01*
G01X1213700Y287144D02*
Y287000D01*
X1213033Y286333D01*
X1212567D01*
X1212113Y285879D01*
Y285413D01*
X1211760Y285060D01*
X1211293D01*
X1210840Y284607D01*
Y284140D01*
X1209572Y282872D01*
X1208021D01*
G03X1206647Y281698I798J-2325D01*
G02X1205358Y280922I-1289J683D01*
G01X1205136D01*
G02X1203774Y281709I0J1572D01*
G03X1201761Y282872I-2013J-1161D01*
G01X1201757D01*
G03X1199744Y281709I0J-2324D01*
G02X1198423Y280921I-1365J787D01*
G01X1198294D01*
G03X1196364Y279759I85J-2325D01*
G02X1195058Y278972I-1365J788D01*
G01X1194948D01*
G03X1192984Y277809I51J-2326D01*
G02X1191663Y277021I-1365J787D01*
G01X1191534D01*
G03X1189604Y275859I85J-2325D01*
G02X1188310Y275072I-1365J787D01*
G01X1188169D01*
G03X1186224Y273909I70J-2325D01*
G02X1184903Y273121I-1365J787D01*
G01X1182382D01*
G03X1181479Y272747I0J-1277D01*
G01X1212788Y303899D02*
X1212701D01*
X1212601Y303799D01*
X1211078D01*
X1210284Y303600D01*
X1203316Y300221D01*
X1202527Y299181D01*
X1198644Y296515D01*
X1198476Y296521D01*
X1198294D01*
G03X1196364Y295359I85J-2325D01*
G02X1195058Y294572I-1365J788D01*
G01X1194929D01*
G03X1192984Y293409I70J-2325D01*
G02X1191663Y292621I-1365J787D01*
G01X1191534D01*
G03X1189579Y289176I85J-2325D01*
G01X1189604Y289134D01*
X1189623Y289100D01*
G02X1189604Y287559I-1384J-754D01*
G03X1189579Y285276I2015J-1164D01*
G01X1189604Y285234D01*
X1189623Y285200D01*
G02X1188298Y282872I-1384J-753D01*
G01X1188169D01*
G03X1186224Y279384I70J-2325D01*
G02X1186243Y277843I-1365J-787D01*
G01X1185186Y275952D01*
G03X1184859Y274696I2247J-1256D01*
G01X1211836Y289568D02*
X1211775Y289507D01*
X1211633D01*
X1209363Y287237D01*
Y287236D01*
X1207446Y285319D01*
Y285320D01*
X1207174Y284892D01*
G02X1205261Y284171I-1735J1704D01*
G01X1204655Y284216D01*
G02X1203275Y285332I784J2380D01*
G03X1202534Y286022I-1516J-885D01*
G01X1201715D01*
G03X1200394Y285234I44J-1575D01*
G02X1198449Y284071I-2015J1162D01*
G01X1198320D01*
G03X1197014Y283284I59J-1575D01*
G02X1195084Y282122I-2015J1163D01*
G01X1194955D01*
G03X1193634Y281334I44J-1575D01*
G02X1191689Y280171I-2015J1162D01*
G01X1191150D01*
G03Y278596I0J-787D01*
G01X1191619D01*
G01X1221480Y284436D02*
X1221338Y284279D01*
X1220138Y283867D01*
X1217335Y283300D01*
X1216438D01*
X1216072Y283666D01*
X1215288D01*
X1214922Y283300D01*
X1213962D01*
X1208262Y277600D01*
X1206379D01*
X1205800Y277021D01*
X1205095D01*
G02X1203774Y277809I44J1575D01*
G03X1199744I-2015J-1163D01*
G02X1198423Y277021I-1365J787D01*
G01X1198294D01*
G03X1196364Y275859I85J-2325D01*
G02X1195070Y275072I-1365J787D01*
G01X1194929D01*
G03X1192984Y273909I70J-2325D01*
G02X1191663Y273121I-1365J787D01*
G01X1191534D01*
G03X1189604Y271959I85J-2325D01*
G02X1188467Y271188I-1365J789D01*
G01X1188239Y271416D01*
Y272747D01*
G01X1194999Y284447D02*
X1193845Y283781D01*
X1193535Y283865D01*
G02X1193464Y284801I1465J582D01*
G02X1194955Y286022I1536J-354D01*
G01X1195084D01*
G03X1197014Y287184I-85J2325D01*
G02X1198320Y287971I1365J-788D01*
G01X1198449D01*
G03X1200394Y289134I-70J2325D01*
G02X1201715Y289922I1365J-787D01*
G01X1202559D01*
G03X1203931Y291095I-800J2325D01*
G02X1204782Y291871I1508J-799D01*
G01X1206832D01*
X1207761Y292800D01*
X1208201D01*
X1208800Y293401D01*
Y293838D01*
X1209833Y294871D01*
X1210333D01*
X1210733Y294471D01*
X1211233D01*
X1211633Y294871D01*
X1212433D01*
X1212823Y294481D01*
X1213623D01*
X1214013Y294871D01*
X1214912D01*
X1216865Y295819D01*
X1216999Y295772D01*
X1217077Y295810D01*
X1217078Y295811D01*
G01X1211509Y306821D02*
X1211368D01*
X1209963Y305416D01*
X1205964Y303350D01*
X1204975Y303280D01*
X1204648Y302902D01*
X1203948Y302851D01*
X1203571Y303181D01*
X1202831Y303128D01*
X1201293Y301846D01*
X1201250Y301354D01*
X1200710Y300904D01*
X1200217Y300952D01*
X1199677Y300502D01*
X1199634Y300010D01*
X1199094Y299560D01*
X1198601Y299608D01*
X1198061Y299158D01*
X1198018Y298666D01*
X1197478Y298216D01*
X1196985Y298264D01*
X1196333Y297722D01*
X1194942D01*
G03X1193634Y296934I57J-1575D01*
G02X1191689Y295771I-2015J1162D01*
G01X1191560D01*
G03X1190254Y294984I59J-1575D01*
G02X1188324Y293822I-2015J1163D01*
G01X1188195D01*
G03X1186874Y291459I44J-1575D01*
G02X1186899Y289176I-2015J-1164D01*
G01X1186874Y289134D01*
X1186855Y289100D01*
G03X1186874Y287559I1384J-754D01*
G02X1184929Y284071I-2015J-1163D01*
G01X1184800D01*
G03X1183477Y281737I58J-1575D01*
G03X1184631Y280937I1381J759D01*
G01X1184859Y281165D01*
Y282496D01*
G01X1191619Y290296D02*
Y288965D01*
X1191847Y288737D01*
G03X1192984Y289509I-228J1559D01*
G02X1194929Y290672I2015J-1162D01*
G01X1195058D01*
G03X1196364Y291459I-59J1575D01*
G02X1198294Y292621I2015J-1163D01*
G01X1198436D01*
G03X1199744Y293409I-57J1575D01*
G01X1200466Y294660D01*
X1204697Y296521D01*
X1206300D01*
X1211393Y299669D01*
X1212341D01*
X1212441Y299769D01*
X1212528D01*
G01X1191619Y282496D02*
G03X1192546Y284169I-2453J2453D01*
G01X1192731Y284970D01*
G02X1194929Y286772I2267J-523D01*
G01X1195058D01*
G03X1196364Y287559I-59J1575D01*
G02X1198294Y288721I2015J-1163D01*
G01X1198423D01*
G03X1199744Y289509I-44J1575D01*
G02X1201689Y290672I2015J-1162D01*
G01X1202416D01*
G03X1203267Y291448I-657J1575D01*
G02X1204639Y292621I2172J-1152D01*
G01X1206521D01*
X1209521Y295621D01*
X1214739D01*
X1216539Y296495D01*
X1216585Y296628D01*
X1216663Y296666D01*
G01X1469343Y469289D02*
X1469430D01*
X1469530Y469189D01*
X1471084D01*
X1471434Y469539D01*
X1472534D01*
X1472884Y469189D01*
X1473984D01*
X1474334Y469539D01*
X1475434D01*
X1475784Y469189D01*
X1476884D01*
X1477234Y469539D01*
X1478334D01*
X1478684Y469189D01*
X1479784D01*
X1480757Y468216D01*
X1487655D01*
X1488448Y469009D01*
X1489476D01*
G03X1490262Y469220I1J1567D01*
G01Y469221D01*
G02X1492588I1163J-2015D01*
G03X1494162I787J1365D01*
G02X1496488I1163J-2015D01*
G03X1498062I787J1365D01*
G02X1500388I1163J-2015D01*
G03X1501962I787J1365D01*
G02X1504288I1163J-2015D01*
G03X1505862I787J1365D01*
G03X1506650Y470542I-787J1365D01*
G01Y470671D01*
G02X1507812Y472601I2325J-85D01*
G03X1508600Y473922I-787J1365D01*
G01Y474010D01*
G03X1507812Y475331I-1575J-44D01*
G03X1506238I-787J-1365D01*
G02X1503912I-1163J2015D01*
G02X1502750Y477261I1163J2015D01*
G01Y477390D01*
G03X1501962Y478711I-1575J-44D01*
G02X1500800Y480641I1163J2015D01*
G01Y480811D01*
G02X1501962Y482741I2325J-85D01*
G03X1502734Y483878I-787J1365D01*
G01X1502506Y484106D01*
X1501175D01*
G01X1482734Y381715D02*
X1483715Y382696D01*
X1487524D01*
G03X1488312Y382909I-3J1577D01*
G03X1489100Y384230I-787J1365D01*
G01Y384359D01*
G02X1490262Y386289I2325J-85D01*
G03X1491050Y387610I-787J1365D01*
G01Y387739D01*
G02X1492212Y389669I2325J-85D01*
G02X1494538I1163J-2015D01*
G03X1496112I787J1365D01*
G03X1496900Y390990I-787J1365D01*
G01Y391119D01*
G02X1498062Y393049I2325J-85D01*
G02X1500388I1163J-2015D01*
G03X1501962I787J1365D01*
G03X1502750Y394370I-787J1365D01*
G01Y394499D01*
G02X1503912Y396429I2325J-85D01*
G02X1506238I1163J-2015D01*
G03X1507812I787J1365D01*
G02X1510925Y397794I7749J-13440D01*
G01X1491425Y453686D02*
X1490760Y454840D01*
X1490408Y454934D01*
G02X1488312Y455051I-932J2132D01*
G03X1487750Y455262I-928J-1619D01*
G03X1487381Y455300I-375J-1829D01*
G01X1485838D01*
X1485138Y456000D01*
X1479812D01*
X1469363Y451672D01*
X1448487D01*
X1448387Y451572D01*
X1448300D01*
G01X1493375Y457066D02*
X1494039Y458219D01*
X1494444Y458327D01*
G02X1494950Y457110I-1208J-1216D01*
G01Y457015D01*
G02X1494188Y455716I-1488J0D01*
G03X1494068Y451728I1135J-2030D01*
G01X1494076Y451720D01*
X1494162Y451671D01*
G02X1492588Y448941I-787J-1365D01*
G03X1490262I-1163J-2015D01*
G02X1488819Y448874I-786J1365D01*
G02X1488688Y448941I651J1435D01*
G01X1488687D01*
G03X1486363I-1162J-2015D01*
G02X1485871Y448809I-492J852D01*
G01X1482614D01*
X1482262Y449161D01*
X1481212D01*
X1480860Y448809D01*
X1480298D01*
X1479682Y448193D01*
X1479172D01*
X1478429Y447450D01*
Y446940D01*
X1477686Y446197D01*
X1477176D01*
X1476433Y445454D01*
Y444944D01*
X1474673Y443184D01*
X1474285D01*
X1473927Y443542D01*
X1472877D01*
X1472519Y443184D01*
X1471469D01*
X1471111Y443542D01*
X1470061D01*
X1469703Y443184D01*
X1468653D01*
X1468295Y443542D01*
X1467245D01*
X1466887Y443184D01*
X1464891D01*
X1464791Y443284D01*
X1464704D01*
G01X1478500Y439713D02*
Y439800D01*
X1478400Y439900D01*
Y440700D01*
X1479326Y441626D01*
X1479826D01*
X1480569Y442369D01*
Y442869D01*
X1481700Y444000D01*
X1483601D01*
X1483726Y444125D01*
Y444137D01*
X1484739Y445150D01*
X1486497D01*
X1486677Y444970D01*
Y444969D01*
X1486857Y444789D01*
X1487907D01*
X1488087Y444969D01*
Y444970D01*
X1488267Y445150D01*
X1489848D01*
X1490262Y444911D01*
G03X1492588I1163J2015D01*
G02X1494162I787J-1365D01*
G01X1494163Y444910D01*
Y444911D01*
G03X1497650Y446872I1162J2015D01*
G01Y446995D01*
G02X1498422Y448280I1571J-70D01*
G01X1498424Y448281D01*
X1498467Y448306D01*
G03X1499612Y450479I-1165J2002D01*
G03X1498679Y452182I-2337J-173D01*
G01X1498438Y452320D01*
Y452321D01*
G02X1497650Y453642I787J1365D01*
G01Y453730D01*
G02X1498438Y455051I1575J-44D01*
G03X1499600Y456981I-1163J2015D01*
G01Y457151D01*
G03X1498438Y459081I-2325J-85D01*
G02X1497650Y460402I787J1365D01*
G01Y460490D01*
G02X1498250Y461683I1575J-45D01*
G01X1498560Y461600D01*
X1499225Y460446D01*
G01X1493375Y450306D02*
X1492044D01*
X1491788Y450562D01*
G03X1488506Y452421I-2313J-256D01*
G01Y452420D01*
G03X1488317Y452323I966J-2115D01*
G01X1488243Y452281D01*
X1488237Y452278D01*
G02X1486813I-712J1235D01*
G01X1486811Y452279D01*
X1486736Y452322D01*
G03X1485023Y452780I-1711J-2968D01*
G01X1478280D01*
X1472900Y447400D01*
X1472287D01*
X1472187Y447500D01*
X1472100D01*
G01X1448300Y452522D02*
X1448387D01*
X1448487Y452422D01*
X1469213D01*
X1479662Y456750D01*
X1480545D01*
X1480901Y457106D01*
X1481951D01*
X1482307Y456750D01*
X1485449D01*
X1486149Y456050D01*
X1487382D01*
G02X1487899Y455998I-2J-2617D01*
G02X1488687Y455701I-517J-2565D01*
G01X1488688D01*
G03X1490056Y455602I786J1365D01*
G01X1490083Y455700D01*
X1490140Y455912D01*
X1489475Y457066D01*
G01X1464704Y442334D02*
X1464791D01*
X1464891Y442434D01*
X1474984D01*
X1480609Y448059D01*
X1485872D01*
G03X1486738Y448291I0J1734D01*
G02X1488312I787J-1365D01*
G01X1488486Y448191D01*
X1488507D01*
G03X1490637Y448291I968J2115D01*
G02X1492213I788J-1365D01*
G03X1494537Y452321I1162J2015D01*
G01X1494536Y452322D01*
G02X1494473Y452360I782J1368D01*
G02X1494554Y455061I850J1326D01*
G01X1494584Y455078D01*
G03X1495700Y456981I-1065J1903D01*
G01Y457109D01*
G03X1495107Y458716I-2465J3D01*
G01X1494823Y459047D01*
X1494660Y459292D01*
X1495325Y460446D01*
G01X1457666Y462230D02*
X1457753D01*
X1457853Y462330D01*
X1467814D01*
X1470010Y464526D01*
X1483015D01*
X1483892Y465403D01*
X1489474D01*
G02X1490262Y465191I-2J-1576D01*
G03X1492588I1163J2015D01*
G02X1494162I787J-1365D01*
G03X1496488I1163J2015D01*
G02X1498062I787J-1365D01*
G03X1500388I1163J2015D01*
G02X1501962I787J-1365D01*
G03X1504288I1163J2015D01*
G02X1505862I787J-1365D01*
G03X1508188I1163J2015D01*
G03X1509350Y467121I-1163J2015D01*
G01Y467250D01*
G02X1510138Y468571I1575J-44D01*
G03X1511300Y470501I-1163J2015D01*
G01Y470630D01*
G02X1512088Y471951I1575J-44D01*
G03X1513250Y473881I-1163J2015D01*
G01Y474051D01*
G03X1512088Y475981I-2325J-85D01*
G02X1511300Y477302I787J1365D01*
G01Y477431D01*
G03X1510138Y479361I-2325J-85D01*
G03X1507812I-1163J-2015D01*
G02X1506238I-787J1365D01*
G03X1504142Y479478I-1164J-2015D01*
G01X1503790Y479572D01*
X1503125Y480726D01*
G01X1457666Y463180D02*
X1457753D01*
X1457853Y463080D01*
X1458803D01*
X1459153Y463430D01*
X1460253D01*
X1460603Y463080D01*
X1461703D01*
X1462053Y463430D01*
X1463153D01*
X1463503Y463080D01*
X1464603D01*
X1464953Y463430D01*
X1466053D01*
X1466403Y463080D01*
X1467503D01*
X1469699Y465276D01*
X1471104D01*
X1471454Y465626D01*
X1472554D01*
X1472904Y465276D01*
X1474004D01*
X1474354Y465626D01*
X1475454D01*
X1475804Y465276D01*
X1476904D01*
X1477254Y465626D01*
X1478354D01*
X1478704Y465276D01*
X1479804D01*
X1480154Y465626D01*
X1481254D01*
X1481604Y465276D01*
X1482704D01*
X1483581Y466153D01*
X1484631D01*
X1484981Y466503D01*
X1486031D01*
X1486381Y466153D01*
X1489475D01*
G02X1490638Y465841I-1J-2327D01*
G03X1492212I787J1365D01*
G02X1494538I1163J-2015D01*
G03X1496112I787J1365D01*
G02X1498438I1163J-2015D01*
G03X1500012I787J1365D01*
G02X1502338I1163J-2015D01*
G03X1503912I787J1365D01*
G02X1506238I1163J-2015D01*
G03X1507812I787J1365D01*
G03X1508600Y467162I-787J1365D01*
G01Y467291D01*
G02X1509762Y469221I2325J-85D01*
G03X1510550Y470542I-787J1365D01*
G01Y470671D01*
G02X1511712Y472601I2325J-85D01*
G03X1512500Y473922I-787J1365D01*
G01Y474010D01*
G03X1511712Y475331I-1575J-44D01*
G02X1510550Y477261I1163J2015D01*
G01Y477390D01*
G03X1509762Y478711I-1575J-44D01*
G03X1508188I-787J-1365D01*
G02X1505862I-1163J2015D01*
G03X1504494Y478810I-786J-1365D01*
G01X1504410Y478500D01*
X1505075Y477346D01*
G01X1468822Y475049D02*
X1468909D01*
X1469009Y474949D01*
X1472613D01*
X1472963Y475299D01*
X1474063D01*
X1474413Y474949D01*
X1475513D01*
X1475863Y475299D01*
X1476963D01*
X1477313Y474949D01*
X1478413D01*
X1481115Y472247D01*
X1482794D01*
X1482936Y472389D01*
X1484625D01*
X1484975Y472739D01*
X1486075D01*
X1486425Y472389D01*
X1487525D01*
G03X1488312Y472601I0J1567D01*
G02X1490638I1163J-2015D01*
G03X1492212I787J1365D01*
G02X1494538I1163J-2015D01*
G03X1496112I787J1365D01*
G02X1498438I1163J-2015D01*
G03X1500012I787J1365D01*
G02X1502338I1163J-2015D01*
G03X1503912I787J1365D01*
G03X1504684Y473738I-787J1365D01*
G01X1504322Y474100D01*
X1503259D01*
X1503125Y473966D01*
G01X1468822Y474099D02*
X1468909D01*
X1469009Y474199D01*
X1478102D01*
X1480804Y471497D01*
X1483106D01*
X1483248Y471639D01*
X1487525D01*
G03X1488688Y471951I2J2317D01*
G02X1490262I787J-1365D01*
G03X1492588I1163J2015D01*
G02X1494162I787J-1365D01*
G03X1496488I1163J2015D01*
G02X1498062I787J-1365D01*
G03X1500388I1163J2015D01*
G02X1501962I787J-1365D01*
G03X1504288I1163J2015D01*
G03X1505438Y473710I-1162J2015D01*
G01X1505694Y473966D01*
X1507025D01*
G01X1469343Y468339D02*
X1469430D01*
X1469530Y468439D01*
X1479473D01*
X1480446Y467466D01*
X1487966D01*
X1488759Y468259D01*
X1489475D01*
G03X1490638Y468571I2J2317D01*
G02X1492212I787J-1365D01*
G03X1494538I1163J2015D01*
G02X1496112I787J-1365D01*
G03X1498438I1163J2015D01*
G02X1500012I787J-1365D01*
G03X1502338I1163J2015D01*
G02X1503912I787J-1365D01*
G03X1506238I1163J2015D01*
G03X1507400Y470501I-1163J2015D01*
G01Y470630D01*
G02X1508188Y471951I1575J-44D01*
G03X1509350Y473881I-1163J2015D01*
G01Y474051D01*
G03X1508188Y475981I-2325J-85D01*
G03X1505862I-1163J-2015D01*
G02X1504288I-787J1365D01*
G02X1503500Y477302I787J1365D01*
G01Y477431D01*
G03X1502338Y479361I-2325J-85D01*
G02X1501550Y480682I787J1365D01*
G01Y480770D01*
G02X1502338Y482091I1575J-44D01*
G03X1503488Y483850I-1162J2015D01*
G01X1503744Y484106D01*
X1505075D01*
G01X1477353Y489000D02*
X1477440D01*
X1477540Y488900D01*
X1478590D01*
X1478940Y489250D01*
X1479990D01*
X1480340Y488900D01*
X1481390D01*
X1481740Y489250D01*
X1482790D01*
X1483140Y488900D01*
X1483681D01*
X1484670Y487911D01*
X1485165D01*
X1485908Y487168D01*
Y486673D01*
X1486274Y486307D01*
X1486283Y486299D01*
G03X1487407Y485849I1043J977D01*
G03X1488312Y486121I-120J2042D01*
G02X1490638I1163J-2015D01*
G03X1492984Y487258I787J1365D01*
G01X1492756Y487486D01*
X1491425D01*
G01X1518725Y384274D02*
X1518060Y383120D01*
X1518155Y382768D01*
G02X1519100Y380979I-1380J-1873D01*
G01Y380809D01*
G02X1517938Y378879I-2325J85D01*
G03X1517150Y377558I787J-1365D01*
G01Y369051D01*
G01X1500134Y374434D02*
X1501550Y375850D01*
Y377558D01*
G02X1502338Y378879I1575J-44D01*
G03X1503500Y380809I-1163J2015D01*
G01Y380938D01*
G02X1504288Y382259I1575J-44D01*
G03X1505450Y384189I-1163J2015D01*
G01Y384318D01*
G02X1506238Y385639I1575J-44D01*
G03X1507400Y387569I-1163J2015D01*
G01Y387739D01*
G03X1506455Y389528I-2325J-84D01*
G01X1506360Y389880D01*
X1507025Y391034D01*
G01X1493375Y380894D02*
X1494040Y382048D01*
X1494350Y382131D01*
G02X1494950Y380938I-975J-1238D01*
G01Y380850D01*
G02X1494162Y379529I-1575J44D01*
G03X1493000Y377599I1163J-2015D01*
G01Y376841D01*
X1491802Y375643D01*
G01X1505075Y387654D02*
X1505740Y388808D01*
X1506050Y388891D01*
G02X1506650Y387698I-975J-1238D01*
G01Y387610D01*
G02X1505862Y386289I-1575J44D01*
G03X1504700Y384359I1163J-2015D01*
G01Y384230D01*
G02X1503912Y382909I-1575J44D01*
G03X1502750Y380979I1163J-2015D01*
G01Y380850D01*
G02X1501962Y379529I-1575J44D01*
G03X1500800Y377599I1163J-2015D01*
G01Y376436D01*
X1499457Y375093D01*
G01X1522625Y397794D02*
X1523290Y396640D01*
X1523195Y396288D01*
G03X1522250Y394499I1380J-1873D01*
G01Y394370D01*
G02X1521462Y393049I-1575J44D01*
G03X1520300Y391119I1163J-2015D01*
G01Y390949D01*
G03X1521462Y389019I2325J85D01*
G02X1522250Y387698I-787J-1365D01*
G01Y387610D01*
G02X1521462Y386289I-1575J44D01*
G03X1520300Y384359I1163J-2015D01*
G01Y384189D01*
G03X1521462Y382259I2325J85D01*
G02X1522250Y380938I-787J-1365D01*
G01Y380850D01*
G02X1521462Y379529I-1575J44D01*
G03X1520300Y377599I1163J-2015D01*
G01Y375800D01*
X1519500Y375000D01*
G01X1528475Y401174D02*
X1527039D01*
X1524611Y398746D01*
Y396611D01*
X1524056Y396056D01*
G02X1523600Y395651I-3649J3650D01*
G03X1523000Y394458I975J-1238D01*
G01Y394329D01*
G02X1521838Y392399I-2325J85D01*
G03X1521050Y391078I787J-1365D01*
G01Y390990D01*
G03X1521838Y389669I1575J44D01*
G02X1523000Y387739I-1163J-2015D01*
G01Y387569D01*
G02X1521838Y385639I-2325J85D01*
G03X1521050Y384318I787J-1365D01*
G01Y384230D01*
G03X1521838Y382909I1575J44D01*
G02X1523000Y380979I-1163J-2015D01*
G01Y380809D01*
G02X1521838Y378879I-2325J85D01*
G03X1521050Y377558I787J-1365D01*
G01Y374500D01*
G01X1515860Y375320D02*
X1516400Y375860D01*
Y377599D01*
G02X1517562Y379529I2325J-85D01*
G03X1518350Y380850I-787J1365D01*
G01Y380938D01*
G03X1517750Y382131I-1575J-45D01*
G01X1517440Y382048D01*
X1516775Y380894D01*
G01X1485789Y375791D02*
Y378008D01*
X1486410Y378629D01*
G02X1486738Y378879I1111J-1118D01*
G02X1488312I787J-1365D01*
G03X1490638I1163J2015D01*
G03X1491800Y380809I-1163J2015D01*
G01Y380938D01*
G02X1492588Y382259I1575J-44D01*
G03X1493750Y384189I-1163J2015D01*
G01Y384318D01*
G02X1494538Y385639I1575J-44D01*
G02X1496112I787J-1365D01*
G03X1498438I1163J2015D01*
G03X1499600Y387569I-1163J2015D01*
G01Y387698D01*
G02X1500388Y389019I1575J-44D01*
G02X1501962I787J-1365D01*
G03X1504288I1163J2015D01*
G03X1505450Y390949I-1163J2015D01*
G01Y391078D01*
G02X1506238Y392399I1575J-44D01*
G02X1507812I787J-1365D01*
G03X1510138I1163J2015D01*
G02X1511712I787J-1365D01*
G03X1514038I1163J2015D01*
G03X1515200Y394329I-1163J2015D01*
G01Y394414D01*
G02X1515988Y395779I1576J0D01*
G03X1518725Y397794I-7666J13279D01*
G01X1513250Y374794D02*
Y377599D01*
G03X1512088Y379529I-2325J-85D01*
G02X1511300Y380850I787J1365D01*
G01Y380938D01*
G02X1512088Y382259I1575J-44D01*
G03X1513250Y384189I-1163J2015D01*
G01Y384318D01*
G02X1514038Y385639I1575J-44D01*
G03X1515200Y387569I-1163J2015D01*
G01Y387698D01*
G02X1515988Y389019I1575J-44D01*
G03X1517150Y390949I-1163J2015D01*
G01Y391078D01*
G02X1517750Y392271I1575J-45D01*
G01X1518060Y392188D01*
X1518622Y391212D01*
X1518725Y391034D01*
G01X1483497Y376500D02*
Y376777D01*
X1485880Y379160D01*
G02X1486041Y379306I1641J-1648D01*
G02X1488688Y379529I1484J-1792D01*
G03X1491050Y380850I787J1365D01*
G01Y380979D01*
G02X1492212Y382909I2325J-85D01*
G03X1493000Y384230I-787J1365D01*
G01Y384359D01*
G02X1494162Y386289I2325J-85D01*
G02X1496488I1163J-2015D01*
G03X1498062I787J1365D01*
G03X1498850Y387610I-787J1365D01*
G01Y387739D01*
G02X1500012Y389669I2325J-85D01*
G02X1502338I1163J-2015D01*
G03X1503912I787J1365D01*
G03X1504700Y390990I-787J1365D01*
G01Y391119D01*
G02X1505862Y393049I2325J-85D01*
G02X1508188I1163J-2015D01*
G03X1509762I787J1365D01*
G02X1512088I1163J-2015D01*
G03X1513662I787J1365D01*
G03X1514450Y394370I-787J1365D01*
G01Y394414D01*
G03X1513662Y395779I-1576J0D01*
G02X1512500Y397709I1163J2015D01*
G01Y397879D01*
G02X1512875Y401174I14664J0D01*
G01X1483552Y381301D02*
X1484033Y381782D01*
X1486909D01*
G03X1488688Y382259I0J3557D01*
G03X1489850Y384189I-1163J2015D01*
G01Y384318D01*
G02X1490638Y385639I1575J-44D01*
G03X1491800Y387569I-1163J2015D01*
G01Y387698D01*
G02X1492588Y389019I1575J-44D01*
G02X1494162I787J-1365D01*
G03X1496488I1163J2015D01*
G03X1497650Y390949I-1163J2015D01*
G01Y391078D01*
G02X1498438Y392399I1575J-44D01*
G02X1500012I787J-1365D01*
G03X1502338I1163J2015D01*
G03X1503500Y394329I-1163J2015D01*
G01Y394458D01*
G02X1504288Y395779I1575J-44D01*
G02X1505862I787J-1365D01*
G03X1508188I1163J2015D01*
G02X1509762I787J-1365D01*
G03X1512875Y394414I7749J13440D01*
G01X1493449Y375496D02*
X1493750Y375797D01*
Y377558D01*
G02X1494538Y378879I1575J-44D01*
G03X1495700Y380809I-1163J2015D01*
G01Y380979D01*
G03X1494755Y382768I-2325J-84D01*
G01X1494660Y383120D01*
X1495325Y384274D01*
G01X1511800Y375089D02*
X1512500Y375789D01*
Y377558D01*
G03X1511712Y378879I-1575J-44D01*
G02X1510550Y380809I1163J2015D01*
G01Y380979D01*
G02X1511712Y382909I2325J-85D01*
G03X1512500Y384230I-787J1365D01*
G01Y384359D01*
G02X1513662Y386289I2325J-85D01*
G03X1514450Y387610I-787J1365D01*
G01Y387739D01*
G02X1515612Y389669I2325J-85D01*
G03X1516400Y390990I-787J1365D01*
G01Y391119D01*
G02X1517345Y392908I2325J-84D01*
G01X1517440Y393260D01*
X1516775Y394414D01*
G01X1507880Y376048D02*
X1508600Y376768D01*
Y377558D01*
G03X1507812Y378879I-1575J-44D01*
G02X1506650Y380809I1163J2015D01*
G01Y380979D01*
G02X1507812Y382909I2325J-85D01*
G03X1508600Y384230I-787J1365D01*
G01Y384359D01*
G02X1509762Y386289I2325J-85D01*
G03X1510550Y387610I-787J1365D01*
G01Y387739D01*
G02X1511495Y389528I2325J-84D01*
G01X1511590Y389880D01*
X1510925Y391034D01*
G01X1508507Y374405D02*
X1509350Y375248D01*
Y377599D01*
G03X1508188Y379529I-2325J-85D01*
G02X1507400Y380850I787J1365D01*
G01Y380938D01*
G02X1508188Y382259I1575J-44D01*
G03X1509350Y384189I-1163J2015D01*
G01Y384318D01*
G02X1510138Y385639I1575J-44D01*
G03X1511300Y387569I-1163J2015D01*
G01Y387698D01*
G02X1511900Y388891I1575J-45D01*
G01X1512210Y388808D01*
X1512875Y387654D01*
G01X1489475Y450306D02*
X1490806D01*
X1491034Y450534D01*
G03X1488819Y451738I-1559J-228D01*
G03X1488688Y451671I651J-1435D01*
G01X1488612Y451628D01*
G02X1486438I-1087J1885D01*
G01X1486363Y451671D01*
G03X1485024Y452030I-1339J-2317D01*
G01X1481200D01*
X1480800Y451630D01*
X1480000D01*
X1479600Y452030D01*
X1478591D01*
X1478026Y451465D01*
Y450899D01*
X1477460Y450332D01*
X1476893D01*
X1476328Y449767D01*
Y449201D01*
X1475762Y448634D01*
X1475195D01*
X1473211Y446650D01*
X1472287D01*
X1472187Y446550D01*
X1472100D01*
G01X1497275Y463826D02*
X1497940Y462672D01*
X1497845Y462320D01*
G03X1496900Y460531I1380J-1873D01*
G01Y460361D01*
G03X1498062Y458431I2325J85D01*
G02X1498850Y457110I-787J-1365D01*
G01Y457022D01*
G02X1498062Y455701I-1575J44D01*
G03X1496900Y453771I1163J-2015D01*
G01Y453601D01*
G03X1498062Y451671I2325J85D01*
G01X1498261Y451556D01*
G02X1498863Y450424I-986J-1250D01*
G02X1498085Y448953I-1561J-115D01*
G01X1498040Y448926D01*
G03X1496900Y447011I1182J-2000D01*
G01Y446882D01*
G02X1494538Y445561I-1575J44D01*
G03X1492212I-1163J-2015D01*
G02X1490638I-787J1365D01*
G01X1490637D01*
X1490049Y445900D01*
X1484428D01*
X1484088Y445560D01*
X1484087D01*
X1483277Y444750D01*
X1481389D01*
X1477650Y441011D01*
Y439900D01*
X1477550Y439800D01*
Y439713D01*
G01X1505075Y463826D02*
X1506406D01*
X1506662Y463570D01*
G03X1511300Y463741I2313J256D01*
G01Y463870D01*
G02X1512088Y465191I1575J-44D01*
G03X1513250Y467121I-1163J2015D01*
G01Y467250D01*
G02X1514038Y468571I1575J-44D01*
G03X1515200Y470501I-1163J2015D01*
G01Y470630D01*
G02X1516028Y472948I3659J0D01*
G03X1516400Y473922I-1089J974D01*
G01Y474051D01*
G02X1517562Y475981I2325J-85D01*
G03Y478711I-787J1365D01*
G02X1516400Y480641I1163J2015D01*
G01Y480811D01*
G02X1517562Y482741I2325J-85D01*
G03Y485471I-787J1365D01*
G02X1516400Y487401I1163J2015D01*
G01Y487571D01*
G02X1517562Y489501I2325J-85D01*
G03X1518350Y490822I-787J1365D01*
G01Y491628D01*
G01X1520675Y463826D02*
X1520010Y464980D01*
X1520105Y465332D01*
G03X1521050Y467121I-1380J1873D01*
G01Y467291D01*
G03X1519888Y469221I-2325J-85D01*
G02X1519100Y470542I787J1365D01*
G01Y470671D01*
G03X1517938Y472601I-2325J-85D01*
G02X1517150Y473881I646J1280D01*
G01Y474010D01*
G02X1517938Y475331I1575J-44D01*
G03X1519100Y477261I-1163J2015D01*
G01Y477431D01*
G03X1517938Y479361I-2325J-85D01*
G02Y482091I787J1365D01*
G03X1519100Y484021I-1163J2015D01*
G01Y484191D01*
G03X1517938Y486121I-2325J-85D01*
G02Y488851I787J1365D01*
G03X1519100Y490781I-1163J2015D01*
G01Y491131D01*
X1520300Y492331D01*
G01X1490283Y492420D02*
X1490370D01*
X1490470Y492520D01*
X1496379D01*
X1496900Y491999D01*
Y490949D01*
X1496550Y490599D01*
Y489549D01*
X1496900Y489199D01*
Y487432D01*
G03Y487401I2325J-16D01*
G03X1497845Y485612I2325J84D01*
G01X1497940Y485260D01*
X1497275Y484106D01*
G01X1490283Y493370D02*
X1490370D01*
X1490470Y493270D01*
X1496690D01*
X1497650Y492310D01*
Y487442D01*
G03X1498250Y486249I1575J45D01*
G01X1498560Y486332D01*
X1499225Y487486D01*
G01X1488903Y495800D02*
X1488990D01*
X1489090Y495900D01*
X1490130D01*
X1490480Y495550D01*
X1491530D01*
X1491880Y495900D01*
X1492930D01*
X1493280Y495550D01*
X1494380D01*
X1494730Y495900D01*
X1495830D01*
X1496180Y495550D01*
X1497280D01*
X1497630Y495900D01*
X1498730D01*
X1499080Y495550D01*
X1500180D01*
X1500530Y495900D01*
X1501630D01*
X1501980Y495550D01*
X1503080D01*
X1503430Y495900D01*
X1504530D01*
X1504880Y495550D01*
X1505980D01*
X1506330Y495900D01*
X1507430D01*
X1508600Y494730D01*
Y493630D01*
X1508250Y493280D01*
Y492180D01*
X1508600Y491830D01*
Y490730D01*
X1508250Y490380D01*
Y489280D01*
X1508600Y488930D01*
Y487401D01*
G03X1509762Y485471I2325J85D01*
G02X1510549Y484164I-788J-1365D01*
G02Y484049I-1575J-58D01*
G02X1509762Y482742I-1575J58D01*
G02X1508394Y482642I-787J1365D01*
G01X1508220Y483000D01*
X1508975Y484106D01*
G01X1488903Y496750D02*
X1488990D01*
X1489090Y496650D01*
X1507741D01*
X1509350Y495041D01*
Y487442D01*
G03X1510138Y486121I1575J44D01*
G02X1511300Y484191I-1163J-2015D01*
G01Y484021D01*
G02X1510138Y482091I-2325J85D01*
G02X1508042Y481974I-1164J2015D01*
G01X1507690Y481880D01*
X1507025Y480726D01*
G01X1491873Y500370D02*
X1491960D01*
X1492060Y500470D01*
X1494050D01*
X1494400Y500120D01*
X1495500D01*
X1495850Y500470D01*
X1496950D01*
X1497300Y500120D01*
X1498400D01*
X1498750Y500470D01*
X1499850D01*
X1500200Y500120D01*
X1501300D01*
X1501650Y500470D01*
X1502750D01*
X1503100Y500120D01*
X1504200D01*
X1504550Y500470D01*
X1505650D01*
X1506000Y500120D01*
X1507100D01*
X1507450Y500470D01*
X1513279D01*
X1513820Y499929D01*
Y496851D01*
X1512500Y495531D01*
Y494201D01*
X1512150Y493851D01*
Y492751D01*
X1512500Y492401D01*
Y491301D01*
X1512150Y490951D01*
Y489851D01*
X1512500Y489501D01*
Y487442D01*
G02X1511900Y486249I-1575J45D01*
G01X1511590Y486332D01*
X1510925Y487486D01*
G01X1491873Y501320D02*
X1491960D01*
X1492060Y501220D01*
X1513590D01*
X1514570Y500240D01*
Y496540D01*
X1513250Y495220D01*
Y487401D01*
G02X1512305Y485612I-2325J84D01*
G01X1512210Y485260D01*
X1512875Y484106D01*
G01X1479054Y484335D02*
X1479141D01*
X1479241Y484235D01*
X1479242D01*
X1485884Y484233D01*
X1486084D01*
X1488686Y482742D01*
X1488688Y482741D01*
G03X1490262I787J1365D01*
G02X1492588I1163J-2015D01*
G03X1493956Y482642I786J1365D01*
G01X1494141Y483326D01*
X1493750Y484005D01*
X1493375Y484106D01*
G01X1479054Y483385D02*
X1479141D01*
X1479241Y483485D01*
X1485883Y483483D01*
X1485884D01*
X1488312Y482091D01*
G03X1490638I1163J2015D01*
G02X1492212I787J-1365D01*
G03X1494308Y481974I1164J2015D01*
G01X1494660Y481880D01*
X1495325Y480726D01*
G01X1477353Y488050D02*
X1477441D01*
Y488150D01*
X1483370D01*
X1485735Y485785D01*
G03X1487450Y485100I1590J1492D01*
G03X1488688Y485471I-162J2791D01*
G02X1490262I787J-1365D01*
G03X1493738Y487230I1163J2015D01*
G01X1493994Y487486D01*
X1495325D01*
G01X1540175Y380894D02*
X1541619Y379450D01*
X1542386D01*
X1543900Y377936D01*
Y375056D01*
X1543651Y374807D01*
Y373807D01*
G01X1540175Y401174D02*
Y397325D01*
X1542000Y395500D01*
Y393182D01*
X1540518Y391700D01*
Y390368D01*
X1541782Y389104D01*
Y386204D01*
X1540500Y384922D01*
Y384000D01*
G02X1539388Y382259I-2231J199D01*
G03X1538693Y381430I787J-1365D01*
G03X1538379Y380099I2003J-1175D01*
G01X1539800Y378678D01*
Y375960D01*
G01X1534325Y384274D02*
X1534990Y383120D01*
X1534895Y382768D01*
G03X1533950Y380979I1380J-1873D01*
G01Y380809D01*
G03X1535112Y378879I2325J85D01*
G02X1535900Y377558I-787J-1365D01*
G01Y376626D01*
X1534679Y375405D01*
G01X1536275Y380894D02*
X1535610Y382048D01*
X1535300Y382131D01*
G03X1534700Y380938I975J-1238D01*
G01Y380850D01*
G03X1535488Y379529I1575J44D01*
G02X1536650Y377599I-1163J-2015D01*
G01Y376350D01*
X1537286Y375714D01*
G01X1534325Y397794D02*
G02X1535829Y397171I0J-2127D01*
G01X1537348Y395652D01*
G02X1537834Y394186I-1217J-1217D01*
G02X1537062Y393049I-1559J228D01*
G03X1535900Y391119I1163J-2015D01*
G01Y390990D01*
G02X1535112Y389669I-1575J44D01*
G03X1533950Y387739I1163J-2015D01*
G01Y387610D01*
G02X1533162Y386289I-1575J44D01*
G03X1532000Y384359I1163J-2015D01*
G01Y384230D01*
G02X1531212Y382909I-1575J44D01*
G03X1530050Y380979I1163J-2015D01*
G01Y380809D01*
G03X1531212Y378879I2325J85D01*
G02X1532000Y377558I-787J-1365D01*
G01Y376500D01*
X1531301Y375801D01*
Y375301D01*
X1530814Y374814D01*
G01X1540175Y394414D02*
X1538844D01*
X1538588Y394158D01*
G02X1537438Y392399I-2312J256D01*
G03X1536650Y391078I787J-1365D01*
G01Y390949D01*
G02X1535488Y389019I-2325J85D01*
G03X1534700Y387698I787J-1365D01*
G01Y387569D01*
G02X1533538Y385639I-2325J85D01*
G03X1532750Y384318I787J-1365D01*
G01Y384189D01*
G02X1531588Y382259I-2325J85D01*
G03X1530800Y380938I787J-1365D01*
G01Y380850D01*
G03X1531588Y379529I1575J44D01*
G02X1532750Y377599I-1163J-2015D01*
G01Y373550D01*
X1532278Y373078D01*
G01X1559479Y533380D02*
X1559392D01*
X1559292Y533480D01*
X1557283D01*
G03X1557037Y533377I2J-350D01*
G01X1556747Y533087D01*
G03X1556623Y532716I426J-348D01*
G02X1556499Y532344I-549J-24D01*
G01X1555757Y531602D01*
G02X1555386Y531478I-348J426D01*
G03X1555014Y531354I-24J-549D01*
G01X1554272Y530612D01*
G03X1554148Y530241I426J-348D01*
G02X1554024Y529869I-549J-24D01*
G01X1553282Y529127D01*
G02X1552911Y529003I-348J426D01*
G03X1552539Y528879I-24J-549D01*
G01X1551797Y528137D01*
G03X1551673Y527766I426J-348D01*
G02X1551549Y527394I-549J-24D01*
G01X1550807Y526652D01*
G02X1550436Y526528I-348J426D01*
G03X1550064Y526404I-24J-549D01*
G01X1549322Y525662D01*
G03X1549198Y525291I426J-348D01*
G02X1549074Y524919I-549J-24D01*
G01X1548332Y524177D01*
G02X1547961Y524053I-348J426D01*
G03X1547589Y523929I-24J-549D01*
G01X1546847Y523187D01*
G03X1546723Y522816I426J-348D01*
G02X1546599Y522444I-549J-24D01*
G01X1545857Y521702D01*
G02X1545486Y521578I-348J426D01*
G03X1545114Y521454I-24J-549D01*
G01X1544372Y520712D01*
G03X1544248Y520341I426J-348D01*
G02X1544124Y519969I-549J-24D01*
G01X1543382Y519227D01*
G02X1543011Y519103I-348J426D01*
G03X1542639Y518979I-24J-549D01*
G01X1541897Y518237D01*
G03X1541773Y517866I426J-348D01*
G02X1541649Y517494I-549J-24D01*
G01X1540907Y516752D01*
G02X1540536Y516628I-348J426D01*
G03X1540164Y516504I-24J-549D01*
G01X1539422Y515762D01*
G03X1539175Y515168I593J-595D01*
G01Y512863D01*
G03X1539350Y512513I547J55D01*
G02X1539525Y512163I-372J-405D01*
G01Y511113D01*
G02X1539350Y510763I-547J55D01*
G03X1539175Y510413I372J-405D01*
G01Y509363D01*
G03X1539350Y509013I547J55D01*
G02X1539525Y508663I-372J-405D01*
G01Y507613D01*
G02X1539350Y507263I-547J55D01*
G03X1539175Y506913I372J-405D01*
G01Y505863D01*
G03X1539350Y505513I547J55D01*
G02X1539525Y505163I-372J-405D01*
G01Y504113D01*
G02X1539350Y503763I-547J55D01*
G03X1539175Y503413I372J-405D01*
G01Y502363D01*
G03X1539350Y502013I547J55D01*
G02X1539525Y501663I-372J-405D01*
G01Y500613D01*
G02X1539350Y500263I-547J55D01*
G03X1539175Y499913I372J-405D01*
G01Y498863D01*
G03X1539350Y498513I547J55D01*
G02X1539525Y498163I-372J-405D01*
G01Y497113D01*
G02X1539350Y496763I-547J55D01*
G03X1539175Y496413I372J-405D01*
G01Y495363D01*
G03X1539350Y495013I547J55D01*
G02X1539525Y494663I-372J-405D01*
G01Y493613D01*
G02X1539350Y493263I-547J55D01*
G03X1539175Y492913I372J-405D01*
G01Y491524D01*
G02X1538852Y490744I-1100J-1D01*
G01X1536753Y488644D01*
G03X1536651Y488397I247J-247D01*
G01X1536650Y488398D01*
Y487442D01*
G03X1537438Y486121I1575J44D01*
G02X1538600Y484191I-1163J-2015D01*
G01Y484021D01*
G02X1537438Y482091I-2325J85D01*
G03X1536650Y480770I787J-1365D01*
G01Y480682D01*
G03X1537438Y479361I1575J44D01*
G02X1538600Y477431I-1163J-2015D01*
G01Y477302D01*
G03X1539388Y475981I1575J44D01*
G02X1540550Y474051I-1163J-2015D01*
G01Y473922D01*
G03X1541338Y472601I1575J44D01*
G03X1542912I787J1365D01*
G02X1545238I1163J-2015D01*
G03X1546812I787J1365D01*
G03X1547600Y473922I-787J1365D01*
G01Y474051D01*
G03X1547568Y474987I-13913J-7D01*
G01Y474989D01*
G03X1546711Y475736I-802J-55D01*
G01X1546710D01*
G03X1545963Y474880I54J-801D01*
G01X1546025Y473966D01*
G01X1559479Y534330D02*
X1559392D01*
X1559292Y534230D01*
X1557284D01*
G03X1556506Y533908I0J-1100D01*
G01X1538891Y516293D01*
G03X1538425Y515168I1125J-1125D01*
G01Y491523D01*
G02X1538322Y491275I-350J0D01*
G01X1536222Y489175D01*
G03X1535900Y488397I778J-778D01*
G01Y487401D01*
G03X1537062Y485471I2325J85D01*
G02X1537850Y484150I-787J-1365D01*
G01Y484062D01*
G02X1537062Y482741I-1575J44D01*
G03X1535900Y480811I1163J-2015D01*
G01Y480641D01*
G03X1537062Y478711I2325J85D01*
G02X1537850Y477390I-787J-1365D01*
G01Y477261D01*
G03X1539012Y475331I2325J85D01*
G02X1539800Y474010I-787J-1365D01*
G01Y473881D01*
G03X1540962Y471951I2325J85D01*
G03X1543288I1163J2015D01*
G02X1544862I787J-1365D01*
G03X1547188I1163J2015D01*
G03X1548350Y473881I-1163J2015D01*
G01Y474051D01*
G03X1547975Y477346I-14664J0D01*
G01X1573387Y499693D02*
X1573300D01*
X1573200Y499793D01*
X1571454D01*
X1569012Y497351D01*
X1567572D01*
X1567182Y496961D01*
X1566482D01*
X1566092Y497351D01*
X1565157D01*
X1564518Y496712D01*
Y496159D01*
X1564023Y495664D01*
X1563470D01*
X1562976Y495170D01*
Y494617D01*
X1562481Y494122D01*
X1561928D01*
X1561434Y493628D01*
Y493075D01*
X1560939Y492580D01*
X1560386D01*
X1559892Y492086D01*
Y491533D01*
X1559397Y491038D01*
X1558844D01*
X1558350Y490544D01*
Y489992D01*
X1557855Y489497D01*
X1557303D01*
X1556150Y488344D01*
Y487417D01*
G03X1556937Y486121I1575J69D01*
G01X1556938D01*
G02X1558100Y484191I-1163J-2015D01*
G01Y484062D01*
G03X1559575Y482534I1575J44D01*
G03X1560499Y483196I57J896D01*
G01Y483671D01*
X1560354Y483923D01*
X1559675Y484106D01*
G01X1573387Y500643D02*
X1573300D01*
X1573200Y500543D01*
X1571143D01*
X1568701Y498101D01*
X1564846D01*
X1555400Y488655D01*
Y487401D01*
G03X1556562Y485471I2325J85D01*
G02X1557350Y484150I-787J-1365D01*
G01Y484052D01*
G03X1559527Y481785I2325J54D01*
G01Y481784D01*
X1561625Y480726D01*
G01X1557725Y487486D02*
X1558613D01*
X1559069Y487942D01*
Y488770D01*
X1563091Y492792D01*
X1569543D01*
X1570056Y493305D01*
X1571665D01*
X1572956Y494596D01*
G01X1561625Y487486D02*
X1560131D01*
X1559819Y487798D01*
Y488459D01*
X1563402Y492042D01*
X1564726D01*
X1565126Y491642D01*
X1565826D01*
X1566226Y492042D01*
X1566926D01*
X1567326Y491642D01*
X1568026D01*
X1568426Y492042D01*
X1569854D01*
X1570367Y492555D01*
X1571497D01*
X1572956Y491096D01*
G54D224*
G01X471651Y523134D02*
Y519933D01*
G01X461612Y523134D02*
Y520269D01*
X460645Y519302D01*
Y515981D01*
X460912Y515714D01*
G01X643390Y329500D02*
X644890Y331000D01*
Y332000D01*
G01X1121261Y523134D02*
X1121259Y523133D01*
Y519933D01*
G01X1111222Y523134D02*
X1111220Y523133D01*
Y520269D01*
X1110253Y519302D01*
Y515981D01*
X1110520Y515714D01*
G01X1510925Y404554D02*
X1513996D01*
X1515050Y403500D01*
G01X1522625Y404554D02*
X1521571Y403500D01*
X1518200D01*
G01X1509200Y454550D02*
X1509150Y454500D01*
X1506800D01*
G01X1530350Y411300D02*
X1528850D01*
X1528100Y410550D01*
G01X1546025Y404554D02*
X1546000Y404579D01*
Y406800D01*
G01X1539125Y412025D02*
X1540700Y410450D01*
G01X1551875Y414694D02*
X1551308Y414127D01*
X1548127D01*
G01X1544150Y409900D02*
Y410150D01*
X1545900Y411900D01*
G01X1736689Y162219D02*
Y159550D01*
G01X1732189Y162219D02*
Y159550D01*
G01X1723189Y162219D02*
Y159550D01*
G01X1727689D02*
Y162219D01*
G01X1741189Y159550D02*
Y162219D01*
G01X1745689D02*
Y159550D01*
G01X1750189Y162219D02*
Y159550D01*
G01X1718689Y162219D02*
X1718600Y162130D01*
Y159639D01*
X1718689Y159550D01*
G54D161*
X1616849Y104338D03*
G54D152*
X1548127Y414127D03*
X1545900Y411900D03*
G54D215*
X1912342Y481228D03*
G54D125*
X1371387Y353950D03*
X1369812D03*
X1368237D03*
X1366662D03*
X1365087D03*
X1363513D03*
X1361938D03*
X1360363D03*
X1358788D03*
X1357213D03*
G54D32*
X44291Y178386D03*
G54D206*
X1954041Y156109D03*
X1948921D03*
X1951481D03*
X1948921Y163364D03*
X1954041D03*
X1968871Y156309D03*
X1963751D03*
X1966311D03*
X1963751Y163564D03*
X1968871D03*
G54D116*
X1263600Y483540D03*
X1281600D03*
X1263600Y478420D03*
X1281600D03*
X1263600Y480980D03*
X1281600D03*
X1263600Y475860D03*
X1281600D03*
G54D41*
X28700Y484000D03*
Y480064D03*
X20600D03*
Y484000D03*
X28700Y482032D03*
Y478096D03*
X20600Y482032D03*
Y478096D03*
G54D143*
X1490300Y22700D03*
X1478300D03*
X1906000Y564600D03*
X1918000D03*
X1906000Y582000D03*
X1918000D03*
X1906000Y573300D03*
X1918000D03*
X1906000Y590700D03*
X1918000D03*
G54D170*
X1673296Y115832D03*
G54D134*
X1450182Y275181D03*
Y278331D03*
X1459628Y281473D03*
Y284623D03*
X1462777Y294072D03*
Y297222D03*
X1462775Y281470D03*
Y284620D03*
X1465949Y294050D03*
Y297200D03*
X1484822Y275177D03*
Y278327D03*
X1478523Y303521D03*
Y306671D03*
X1469000Y294100D03*
Y297250D03*
X1472226Y294076D03*
Y297226D03*
X1475373Y284626D03*
Y287776D03*
X1523375Y443525D03*
Y446675D03*
X1510775Y415175D03*
Y418325D03*
X1507625Y415175D03*
Y418325D03*
X1539125Y443525D03*
Y446675D03*
X1535975Y443525D03*
Y446675D03*
X1549805Y416465D03*
Y419615D03*
X1535975Y421475D03*
Y424625D03*
X1539125Y412025D03*
Y415175D03*
G54D50*
X72800Y105000D03*
G54D107*
X1223453Y336318D03*
G54D23*
X40500Y-42250D03*
Y-52250D03*
X10512Y467244D03*
X20512D03*
X30512D03*
X40512D03*
X60500Y-42250D03*
X80500D03*
X100500D03*
X60500Y-52250D03*
X80500D03*
X100500D03*
X50512Y467244D03*
X120500Y-42250D03*
X140500D03*
X120500Y-52250D03*
X140500D03*
X467246Y-52301D03*
Y-42301D03*
X487246Y-52301D03*
Y-42301D03*
X507246Y-52301D03*
Y-42301D03*
X527246Y-52301D03*
Y-42301D03*
X547246Y-52301D03*
Y-42301D03*
X567246Y-52301D03*
Y-42301D03*
X798984Y-52057D03*
Y-42057D03*
X818984Y-52057D03*
Y-42057D03*
X838984Y-52057D03*
Y-42057D03*
X858984Y-52057D03*
Y-42057D03*
X878984Y-52057D03*
Y-42057D03*
X898984Y-52057D03*
Y-42057D03*
X1135583Y-52285D03*
Y-42285D03*
X1155583Y-52285D03*
Y-42285D03*
X1392258Y-52257D03*
Y-42257D03*
X1412258Y-52257D03*
Y-42257D03*
X1432258Y-52257D03*
Y-42257D03*
X1452258Y-52257D03*
Y-42257D03*
X1884100Y493000D03*
X1894100D03*
X1891086Y612105D03*
Y602105D03*
G54D14*
X-15250Y71330D03*
X-5210D03*
G54D234*
G01X1504500Y587600D02*
X1501200Y590900D01*
Y619201D01*
X1500445Y619956D01*
G54D225*
G01X19800Y257900D02*
X21920Y255780D01*
X29000D01*
G01X41000Y274647D02*
Y271400D01*
G01X37000Y275000D02*
Y271400D01*
G01X57444Y257456D02*
X55768Y255780D01*
X48700D01*
G01X62000Y278000D02*
Y276800D01*
X63300Y275500D01*
X66200D01*
X67500Y276800D01*
G01X68300Y281600D02*
X68700Y281200D01*
Y278000D01*
X67500Y276800D01*
G01X70900Y281600D02*
X70700Y281400D01*
Y277100D01*
X66600Y273000D01*
X62500D01*
X61200Y274300D01*
G01X59500Y278000D02*
Y276000D01*
X61200Y274300D01*
G01X61625Y283201D02*
X63601D01*
X66250Y285850D01*
X66300D01*
G01X69000Y289000D02*
Y288600D01*
X66300Y285900D01*
Y285850D01*
G01X72502Y285300D02*
X68888D01*
X66100Y282512D01*
Y282499D01*
X64051Y280450D01*
X60543D01*
X58700Y282293D01*
Y283000D01*
G01X72502Y285300D02*
X72904Y284898D01*
G01X72500Y289000D02*
Y285302D01*
X72502Y285300D01*
G01X123620Y35983D02*
X123604D01*
X123392Y35771D01*
Y31978D01*
G01X123620Y-1801D02*
X123392Y-2029D01*
Y-6000D01*
G01X120273Y41823D02*
Y36057D01*
X119892Y35676D01*
Y31978D01*
G01Y-6000D02*
Y-2124D01*
X120273Y-1743D01*
Y4023D01*
G01D02*
Y9157D01*
G01X123392Y69778D02*
Y73571D01*
X123620Y73799D01*
G01X120273Y79623D02*
Y74181D01*
X119892Y73800D01*
Y69778D01*
G01Y84700D02*
X120273Y84319D01*
Y79623D01*
G01Y46957D02*
Y41823D01*
G01X130824Y241333D02*
Y243533D01*
X130324Y244033D01*
G01X120273Y505024D02*
Y509719D01*
X119892Y510100D01*
G01X120273Y542824D02*
Y547519D01*
X119892Y547900D01*
G01X248200Y366800D02*
Y363800D01*
X249200Y362800D01*
G01X300992Y112300D02*
X302282Y113590D01*
X306380D01*
X307492Y112478D01*
Y109500D01*
G01X324492Y103500D02*
X323292Y104700D01*
Y104900D01*
G01X361058Y50742D02*
X359975Y49659D01*
X357762D01*
G01X385244Y504027D02*
X383580Y502363D01*
Y497770D01*
G01X360962Y532800D02*
X359762Y534000D01*
X357661D01*
G01X363760Y529293D02*
X362807D01*
X360962Y531138D01*
Y532800D01*
G01X360870Y551820D02*
X359579Y553111D01*
X357539D01*
G01X367911Y580624D02*
Y584979D01*
G01Y580624D02*
Y575319D01*
G01Y584979D02*
X366890Y586000D01*
G01X367911Y575319D02*
X367334Y574742D01*
X367192D01*
G01X360090Y589680D02*
X358831Y590939D01*
X356798D01*
G01X448292Y13700D02*
X445700D01*
X445200Y13200D01*
X442508D01*
G01X448292Y31900D02*
X448092Y32100D01*
G01D02*
X442508D01*
G01Y51000D02*
X448492D01*
G01X442508Y69900D02*
X443708Y71100D01*
X448447D01*
G01D02*
X448651Y70896D01*
G01X644000Y328200D02*
Y328890D01*
X643390Y329500D01*
G01X638790D02*
X643390D01*
G01X644400Y307000D02*
Y308500D01*
X643400Y309500D01*
G01X644400Y312000D02*
Y310500D01*
X643400Y309500D01*
G01X639045Y299555D02*
X643338D01*
X644400Y300617D01*
Y302000D01*
G01X643400Y309500D02*
X639100D01*
G01X702000Y223500D02*
Y226300D01*
X701700Y226600D01*
G01X699000Y226500D02*
X699100Y226600D01*
X701700D01*
G01X690420Y325500D02*
Y320500D01*
G01D02*
Y319380D01*
X691800Y318000D01*
G01X691100Y308000D02*
X690000Y306900D01*
Y305500D01*
G01Y300500D02*
Y299400D01*
X692331Y297069D01*
G01X696500Y361311D02*
X699244Y358567D01*
X717566D01*
G01X668118Y507500D02*
Y510296D01*
X665604Y512810D01*
X664610D01*
G01X773000Y31978D02*
Y35771D01*
X773212Y35983D01*
X773228D01*
G01Y-1801D02*
X773000Y-2029D01*
Y-6000D01*
G01X769881Y41823D02*
Y36057D01*
X769500Y35676D01*
Y31978D01*
G01X769883Y4023D02*
X769881D01*
G01Y9157D02*
Y4023D01*
G01D02*
Y-1743D01*
X769500Y-2124D01*
Y-6000D01*
G01X773000Y69778D02*
Y73571D01*
X773228Y73799D01*
G01X769500Y69778D02*
Y73800D01*
X769881Y74181D01*
Y79623D01*
G01X769500Y84700D02*
X769881Y84319D01*
Y79623D01*
G01D02*
X769883D01*
G01Y41823D02*
X769881D01*
G01Y46957D02*
Y41823D01*
G01X769883Y505024D02*
X769881D01*
Y509719D01*
X769500Y510100D01*
G01X769883Y542824D02*
X769881D01*
Y547519D01*
X769500Y547900D01*
G01X961850Y51000D02*
X957829D01*
X957558Y50729D01*
G01X1038200Y104500D02*
Y106700D01*
X1036700Y108200D01*
X1026542D01*
X1025725Y107383D01*
X1022483D01*
X1020800Y105700D01*
Y104233D01*
G01X1017521Y580624D02*
X1017519D01*
G01D02*
Y575319D01*
G01Y580624D02*
Y583620D01*
X1019277Y585378D01*
G01X1017519Y575319D02*
X1016942Y574742D01*
X1016800D01*
G01X1019277Y585378D02*
Y585714D01*
G01X1025450Y593650D02*
X1027070Y592030D01*
Y589650D01*
G01X1006406Y590966D02*
X1008534D01*
X1009800Y589700D01*
G01X1025450Y593650D02*
X1022950D01*
G01X1070976Y32100D02*
X1066758D01*
G01Y13200D02*
X1070976D01*
G01X1092116D02*
X1094800D01*
X1095300Y13700D01*
X1097900D01*
G01X1083116Y32100D02*
X1079758D01*
G01Y13200D02*
X1083116D01*
G01X1054308D02*
X1057792D01*
G01Y32100D02*
X1054308D01*
G01X1097352Y-7180D02*
Y-12048D01*
X1094400Y-15000D01*
X1086000D01*
G01X1058500D02*
Y-15300D01*
X1062000Y-18800D01*
X1070700D01*
X1072500Y-17000D01*
Y-16000D01*
G01X1086000Y-15000D02*
X1082100Y-18900D01*
X1075400D01*
X1072500Y-16000D01*
G01X1097700Y32100D02*
X1092116D01*
G01X1070976Y69900D02*
X1066758D01*
G01X1079758D02*
X1083116D01*
G01X1066758Y51000D02*
X1070976D01*
G01X1092116D02*
X1098100D01*
G01X1079758D02*
X1083116D01*
G01X1057792Y69900D02*
X1054308D01*
G01Y51000D02*
X1057792D01*
G01X1098055Y71100D02*
X1093316D01*
X1092116Y69900D01*
G01X1038200Y104500D02*
Y101100D01*
X1035900Y98800D01*
G01X1084450Y523134D02*
Y529022D01*
G01X1084448Y518157D02*
X1084450Y518159D01*
G01X1091143Y529005D02*
Y523134D01*
G01X1084450Y518159D02*
Y523134D01*
G01X1091141Y529007D02*
X1091143Y529005D01*
G01X1081532Y617956D02*
X1077788Y621700D01*
X1071776D01*
X1068032Y617956D01*
G01X1095532D02*
X1091688Y621800D01*
X1085376D01*
X1081532Y617956D01*
G01X1097900Y31900D02*
X1097700Y32100D01*
G01X1098259Y70896D02*
X1098055Y71100D01*
G01X1267960Y30400D02*
X1266360Y32000D01*
X1266108D01*
G01X1228835Y116162D02*
X1227000Y117997D01*
Y141684D01*
X1240248Y154932D01*
X1240927D01*
G01X1233953Y109162D02*
Y111893D01*
X1233086Y112760D01*
X1229726D01*
X1228835Y113651D01*
Y116162D01*
G01X1247326Y122802D02*
X1245837Y121313D01*
X1241519D01*
X1239213Y119007D01*
Y116188D01*
G01X1370900Y34700D02*
Y35876D01*
X1369700Y37076D01*
Y37800D01*
G01X1457814Y13466D02*
X1457966D01*
X1460500Y16000D01*
Y20500D01*
X1456450Y24550D01*
X1455100D01*
G01X1450973Y112225D02*
X1451089Y112341D01*
X1453211D01*
X1453552Y112000D01*
X1457000D01*
G01X1428500Y521000D02*
X1427900D01*
X1425600Y523300D01*
Y523700D01*
G01X1481600Y5300D02*
X1489089Y12789D01*
Y16511D01*
X1482900Y22700D01*
X1478300D01*
G01D02*
X1474800D01*
X1473250Y24250D01*
X1471500D01*
G01X1492700Y12300D02*
X1491701Y13299D01*
Y18599D01*
X1490300Y20000D01*
Y22700D01*
G01X1505000Y-15000D02*
Y-8500D01*
X1496200Y300D01*
Y8800D01*
X1492700Y12300D01*
G01X1578000Y113000D02*
X1576414Y114586D01*
Y117787D01*
G01X1580364Y116549D02*
Y115364D01*
X1578000Y113000D01*
G01X1585064Y122049D02*
X1580364D01*
G01X1580164D02*
X1580364D01*
G01X1537700Y610897D02*
Y613386D01*
X1537711Y613397D01*
G01X1620900Y81300D02*
Y83400D01*
X1622000Y84500D01*
G01X1624500Y90800D02*
Y93100D01*
X1626250Y94850D01*
Y96000D01*
G01X1622000Y84500D02*
X1624500Y87000D01*
Y90800D01*
G01X1648500Y128750D02*
X1645750D01*
X1645378Y128378D01*
G01X1648500Y131750D02*
Y128750D01*
G01Y135250D02*
X1650674D01*
X1651536Y134388D01*
G01X1648500Y135250D02*
Y138250D01*
G01X1649097Y147750D02*
Y144754D01*
X1649101Y144750D01*
G01D02*
X1650623D01*
X1651536Y143837D01*
G01X1626250Y99500D02*
Y96000D01*
G01Y103000D02*
Y99500D01*
G01X1638674Y556178D02*
X1640102Y554750D01*
X1640610D01*
X1640860Y554500D01*
X1641756D01*
G01X1700710Y73292D02*
Y73282D01*
X1702749Y71243D01*
Y69233D01*
G01X1699249D02*
Y71347D01*
X1697300Y73296D01*
G01X1703250Y62680D02*
Y64500D01*
X1701750Y66000D01*
X1700749D01*
X1699249Y67500D01*
Y69233D01*
G01X1708250Y164950D02*
X1708700Y165400D01*
X1710811D01*
G01X1711535Y172070D02*
Y173734D01*
X1713596Y175795D01*
G01X1748425Y116600D02*
X1751625D01*
G01X1748425Y119190D02*
Y116600D01*
G01X1761035D02*
Y113400D01*
G01X1758025Y116600D02*
X1761035D01*
G01X1754825D02*
X1758025D01*
G01X1751625D02*
X1754825D01*
G01X1761035Y113400D02*
Y109735D01*
X1760200Y108900D01*
G01X1743500Y96400D02*
X1742700Y95600D01*
X1740300D01*
G01X1719048Y175948D02*
X1719100Y176000D01*
G01X1745920Y228410D02*
Y231172D01*
X1744603Y232489D01*
G01X1734930Y228440D02*
X1733880Y229490D01*
Y232810D01*
G01X1834540Y513800D02*
Y519600D01*
G01X1805100Y567500D02*
X1806148D01*
X1807958Y565690D01*
G01X1802400Y562600D02*
X1801600Y563400D01*
Y567500D01*
G01X1925135Y115400D02*
X1927079D01*
X1928928Y117249D01*
X1931971D01*
X1933379Y115841D01*
Y105370D01*
G01X1921620Y115400D02*
X1925135D01*
G01X1919790Y119000D02*
X1920220D01*
X1921620Y117600D01*
Y115400D01*
G01X1957250Y512050D02*
X1955420Y513880D01*
X1954120D01*
G54D216*
X1912342Y477628D03*
G54D135*
X1462770Y287777D03*
X1459620D03*
X1456477Y303528D03*
X1453327D03*
X1525900Y452400D03*
X1520225Y424625D03*
X1517075D03*
X1520225Y427775D03*
X1517075D03*
X1523550Y411600D03*
X1520400D03*
X1520225Y421475D03*
X1517075D03*
X1529050Y452400D03*
X1554875Y434075D03*
X1551725D03*
X1542275Y424625D03*
X1539125D03*
X1542275Y427775D03*
X1539125D03*
X1546000Y406800D03*
X1542850D03*
G54D180*
X1750315Y560887D03*
Y566793D03*
X1803950Y538954D03*
Y533048D03*
G54D42*
X24650Y481048D03*
G54D126*
X1402430Y483176D03*
G54D144*
X1527233Y57198D03*
Y41018D03*
X1551107Y65716D03*
X1548547D03*
X1545987D03*
X1543427D03*
Y49536D03*
X1545987D03*
X1548547D03*
X1551107D03*
X1534913Y57198D03*
X1532353D03*
X1529793D03*
Y41018D03*
X1532353D03*
X1534913D03*
G54D51*
X89100Y124700D03*
X85350Y116200D03*
X81600Y124700D03*
X72750Y354750D03*
X80250D03*
X76500Y363250D03*
X1526900Y257200D03*
X1519400D03*
X1523150Y248700D03*
X1472781Y330195D03*
X1476531Y338695D03*
X1480281Y330195D03*
X1774250Y75500D03*
X1716000Y79500D03*
X1719750Y88000D03*
X1723500Y79500D03*
X1781750Y75500D03*
X1778000Y84000D03*
X1882250Y463250D03*
X1874750D03*
X1878500Y454750D03*
X1940000Y532600D03*
X1947500D03*
X1943750Y541100D03*
G54D60*
X94500Y299000D03*
X89000D03*
X353500Y13200D03*
X348000D03*
X324642D03*
X330142D03*
X312342D03*
X317842D03*
X337642D03*
X343142D03*
X353500Y51000D03*
X348000D03*
X312342D03*
X317842D03*
X324642D03*
X330142D03*
X337642D03*
X343142D03*
X353500Y552000D03*
X348000D03*
X312342D03*
X317842D03*
X324642D03*
X330142D03*
X337642D03*
X343142D03*
X353500Y589800D03*
X348000D03*
X312342D03*
X317842D03*
X324642D03*
X330142D03*
X337642D03*
X343142D03*
X417150Y13200D03*
X411650D03*
X361042Y13078D03*
X366542D03*
X404700Y13200D03*
X399200D03*
X417150Y51000D03*
X411650D03*
X361058Y50742D03*
X366558D03*
X404700Y51000D03*
X399200D03*
X417150Y552000D03*
X411650D03*
X360870Y551820D03*
X366370D03*
X404700Y552000D03*
X399200D03*
X417150Y589800D03*
X411650D03*
X360090Y589680D03*
X365590D03*
X404700Y589800D03*
X399200D03*
X430150Y13200D03*
X424650D03*
X442508D03*
X437008D03*
X442508Y51000D03*
X437008D03*
X430150D03*
X424650D03*
X430150Y552000D03*
X424650D03*
X442508D03*
X437008D03*
X430150Y589800D03*
X424650D03*
X442508D03*
X437008D03*
X600000Y-6700D03*
X599000Y32000D03*
Y70000D03*
X600892Y532978D03*
Y570778D03*
X599992Y609378D03*
X616500Y32000D03*
X611000D03*
X616500Y-6700D03*
X611000D03*
X605500D03*
X604500Y32000D03*
X616500Y70000D03*
X611000D03*
X604500D03*
X616892Y570778D03*
X611392D03*
X616892Y532978D03*
X611392D03*
X606392D03*
Y570778D03*
X615992Y609378D03*
X610492D03*
X605492D03*
X671000Y13600D03*
X665500D03*
X677550Y21856D03*
X683050D03*
X671000Y18500D03*
X665500D03*
X670569Y577612D03*
X665069D03*
X961950Y13200D03*
X967450D03*
X961850Y51000D03*
X967350D03*
X961950Y552000D03*
X967450D03*
X961950Y589800D03*
X967450D03*
X1010900Y13078D03*
X1016400D03*
X1003108Y13200D03*
X997608D03*
X987250D03*
X992750D03*
X974250D03*
X979750D03*
X1003108Y51000D03*
X997608D03*
X1010800Y50500D03*
X1016300D03*
X974250Y51000D03*
X979750D03*
X987250D03*
X992750D03*
X1003108Y552000D03*
X997608D03*
X1011100Y551900D03*
X1016600D03*
X974250Y552000D03*
X979750D03*
X987250D03*
X992750D03*
X1009800Y589700D03*
X1015300D03*
X974250Y589800D03*
X979750D03*
X987250D03*
X992750D03*
X1003108D03*
X997608D03*
X1092116Y13200D03*
X1086616D03*
X1079758D03*
X1074258D03*
X1066758D03*
X1061258D03*
X1054308D03*
X1048808D03*
X1092116Y51000D03*
X1086616D03*
X1079758D03*
X1074258D03*
X1066758D03*
X1061258D03*
X1054308D03*
X1048808D03*
X1092116Y552000D03*
X1086616D03*
X1079758D03*
X1074258D03*
X1066758D03*
X1061258D03*
X1054308D03*
X1048808D03*
X1079758Y589800D03*
X1074258D03*
X1092116D03*
X1086616D03*
X1066758D03*
X1061258D03*
X1054308D03*
X1048808D03*
X1249608Y-6700D03*
X1255108D03*
X1266108D03*
X1260608D03*
X1248608Y32000D03*
X1254108D03*
X1266108D03*
X1260608D03*
X1248608Y70000D03*
X1254108D03*
X1266108D03*
X1260608D03*
X1248608Y533000D03*
X1254108D03*
X1266108D03*
X1260608D03*
X1248608Y571000D03*
X1254108D03*
X1266108D03*
X1260608D03*
X1248374Y609456D03*
X1253874D03*
X1266500Y609500D03*
X1261000D03*
X1337500Y47000D03*
X1332000D03*
X1444047Y402285D03*
X1449547D03*
X1462850Y407900D03*
X1457350D03*
X1462850Y412900D03*
X1457350D03*
X1447000Y408000D03*
X1452500D03*
X1447000Y413000D03*
X1452500D03*
X1462800Y526800D03*
X1460750Y543500D03*
X1466250D03*
X1468300Y526800D03*
X1483200Y527200D03*
X1488700D03*
X1482700Y542700D03*
X1488200D03*
X1553300Y614500D03*
X1547800D03*
X1592250Y90500D03*
X1597750D03*
X1608349Y90538D03*
X1613849D03*
X1599193Y70229D03*
X1604193D03*
X1641099Y156438D03*
X1635599D03*
X1644750Y122000D03*
X1639250D03*
X1606250Y102500D03*
X1611750D03*
X1598500Y124750D03*
X1604000D03*
X1639171Y134592D03*
X1644671D03*
X1606500Y371948D03*
X1601000D03*
X1606500Y367248D03*
X1601000D03*
X1616300Y486700D03*
X1610800D03*
X1623750Y514200D03*
X1618250D03*
X1623750Y509500D03*
X1618250D03*
X1797650Y163440D03*
X1803150D03*
X1881150Y142800D03*
X1875650D03*
X1881150Y147800D03*
X1875650D03*
X1884689Y137717D03*
X1890189D03*
X1838363Y143448D03*
X1843863D03*
X1890750Y183300D03*
X1896250D03*
X1894900Y163500D03*
X1889400D03*
X1896150Y178600D03*
X1890650D03*
X1916513Y179468D03*
X1922013D03*
X1916513Y184468D03*
X1922013D03*
X1916513Y189468D03*
X1922013D03*
X1917100Y167400D03*
X1922600D03*
G54D117*
X1296679Y228017D03*
X1289679Y222899D03*
X1296679Y225458D03*
X1289679Y228017D03*
X1296679Y222899D03*
X1460354Y148569D03*
Y146010D03*
Y151128D03*
X1524200Y12218D03*
Y7100D03*
X1510200Y9641D03*
Y12200D03*
Y7082D03*
X1517200D03*
Y9641D03*
Y12200D03*
X1480354Y151039D03*
Y148479D03*
X1473354Y151039D03*
Y145919D03*
Y148479D03*
X1480354Y145919D03*
X1467354Y151128D03*
Y146010D03*
X1528065Y171552D03*
Y174112D03*
Y176672D03*
X1506000Y186570D03*
Y184010D03*
X1499000Y186570D03*
Y181450D03*
Y184010D03*
X1506000Y181450D03*
X1488962Y190185D03*
X1481962Y187626D03*
Y185067D03*
X1488962D03*
X1481962Y190185D03*
X1531200Y7100D03*
Y9659D03*
Y12218D03*
X1535065Y171552D03*
Y176672D03*
Y174112D03*
X1548628Y176772D03*
Y174212D03*
X1541628Y176772D03*
Y171652D03*
Y174212D03*
X1548628Y171652D03*
X1547650Y258590D03*
X1540650Y256031D03*
Y253472D03*
X1547650D03*
X1540650Y258590D03*
X1544300Y248318D03*
X1537300Y245759D03*
Y243200D03*
X1544300D03*
X1537300Y248318D03*
X1594600Y-14300D03*
X1601600Y-11741D03*
X1594600Y-9182D03*
X1601600Y-14300D03*
Y-9182D03*
X1613000Y-6218D03*
X1620000Y-3659D03*
X1613000Y-1100D03*
X1620000Y-6218D03*
Y-1100D03*
X1648296Y301559D03*
X1641296Y296441D03*
Y299000D03*
X1648296Y296441D03*
X1641296Y301559D03*
X1620717Y370711D03*
Y368151D03*
X1613717Y370711D03*
Y365591D03*
Y368151D03*
X1620717Y365591D03*
Y349711D03*
Y347151D03*
X1613717Y349711D03*
Y344591D03*
Y347151D03*
X1620717Y344591D03*
Y360211D03*
Y357651D03*
X1613717Y360211D03*
Y355091D03*
Y357651D03*
X1620717Y355091D03*
X1662526Y300586D03*
X1655526Y298027D03*
X1662526Y295468D03*
X1655526Y300586D03*
Y295468D03*
X1759900Y509359D03*
Y506800D03*
X1752900Y509359D03*
Y506800D03*
Y511918D03*
X1759900D03*
X1757792Y581471D03*
X1750792Y578912D03*
X1757792Y576353D03*
X1750792Y581471D03*
Y576353D03*
X1761300Y613600D03*
Y618718D03*
X1754300D03*
Y616159D03*
Y613600D03*
X1735000Y618700D03*
Y613582D03*
X1742000D03*
Y616141D03*
Y618700D03*
X1808400Y557982D03*
X1815400Y560541D03*
X1808400Y563100D03*
X1815400Y557982D03*
Y563100D03*
X1872115Y586119D03*
X1879115D03*
X1872115Y588679D03*
X1879115Y591239D03*
Y588679D03*
X1872115Y591239D03*
G54D207*
X1949650Y220787D03*
Y228661D03*
G54D108*
X1236921Y337307D03*
G54D171*
X1712642Y99814D03*
G54D153*
X1627642Y-14488D03*
X1647327Y-315D03*
G54D33*
X3937Y204370D03*
X-3937D03*
X-11811D03*
X35433D03*
X27559D03*
X19685D03*
X3937Y227992D03*
X-3937D03*
X-11811D03*
X35433D03*
X27559D03*
X19685D03*
X3937Y313504D03*
X-3937D03*
X-11811D03*
X3937Y337126D03*
X-3937D03*
X-11811D03*
X35433D03*
X27559D03*
X19685D03*
X35433Y313504D03*
X27559D03*
X19685D03*
G54D15*
X-15748Y101221D03*
Y116969D03*
Y132717D03*
Y148465D03*
Y357362D03*
Y373110D03*
Y388858D03*
Y404606D03*
X12205Y156339D03*
X-4331D03*
X17323Y101221D03*
Y116969D03*
Y132717D03*
Y148465D03*
X787Y101221D03*
Y116969D03*
Y132717D03*
Y148465D03*
X33858Y101221D03*
Y116969D03*
Y132717D03*
Y148465D03*
X28740Y109095D03*
Y124843D03*
Y140591D03*
Y156339D03*
X12205Y109095D03*
Y124843D03*
Y140591D03*
X-4331Y109095D03*
Y124843D03*
Y140591D03*
X17323Y357362D03*
Y373110D03*
Y388858D03*
Y404606D03*
X787Y357362D03*
Y373110D03*
Y388858D03*
Y404606D03*
X33858Y357362D03*
Y373110D03*
Y388858D03*
Y404606D03*
X28740Y365236D03*
Y380984D03*
Y396732D03*
X12205Y365236D03*
Y380984D03*
Y396732D03*
X-4331Y365236D03*
Y380984D03*
Y396732D03*
X12205Y412480D03*
X-4331D03*
X28740D03*
G54D24*
G01X1952004Y234249D02*
X1945061D01*
X16117Y-43892D03*
X8543Y636173D03*
X177070Y121250D03*
X237330Y408960D03*
X475000Y122500D03*
X539500Y478000D03*
X735000Y392500D03*
X872000Y111000D03*
X1215624Y133363D03*
X1225000Y487600D03*
X1712205Y536791D03*
X1707205D03*
X1702205D03*
X1697205D03*
X1692205D03*
X1687205D03*
X1712205D03*
X1707205D03*
X1702205D03*
X1697205D03*
X1692205D03*
X1687205D03*
X1717205D03*
D03*
X1925000Y62000D03*
X1926693Y646063D03*
G54D162*
X1616849Y98738D03*
G54D235*
G01X-10236Y101221D02*
X-8660D01*
X-7604Y100165D01*
Y98549D01*
X-6255Y97200D01*
X34700D01*
X39100Y92800D01*
X50799D01*
X51381Y92218D01*
Y90750D01*
G01X-4725Y101221D02*
X-5915D01*
X-6654Y100482D01*
Y98943D01*
X-5861Y98150D01*
X-112D01*
X338Y98600D01*
X1688D01*
X2138Y98150D01*
X16935D01*
X17385Y98600D01*
X18735D01*
X19185Y98150D01*
X31994D01*
X32444Y98600D01*
X33794D01*
X34244Y98150D01*
X35094D01*
X36948Y96296D01*
X37585D01*
X38539Y95341D01*
Y94705D01*
X39494Y93750D01*
X41585D01*
X42035Y94200D01*
X43385D01*
X43835Y93750D01*
X45185D01*
X45635Y94200D01*
X46985D01*
X47435Y93750D01*
X50821D01*
X51381Y94310D01*
Y95750D01*
G01X6299Y101221D02*
X8130D01*
X8580Y101671D01*
Y103874D01*
X10800Y106094D01*
X31390D01*
X44363Y100720D01*
X46445D01*
X46900Y101175D01*
Y102750D01*
G01X1181Y109095D02*
X3012D01*
X3751Y109834D01*
Y111945D01*
X5313Y113507D01*
X34406D01*
X42599Y121700D01*
X50528D01*
X51569Y122741D01*
Y123750D01*
G01X6299Y116969D02*
X7964D01*
X8565Y117570D01*
Y119409D01*
X10537Y121381D01*
X29381D01*
X43720Y135720D01*
X51011D01*
X51569Y136278D01*
Y137750D01*
G01X11811Y101221D02*
X9980D01*
X9530Y101671D01*
Y103480D01*
X11194Y105144D01*
X24001D01*
X24451Y104694D01*
X25801D01*
X26251Y105144D01*
X27601D01*
X28051Y104694D01*
X29401D01*
X29851Y105144D01*
X31201D01*
X35535Y103348D01*
X35779Y102760D01*
X37026Y102244D01*
X37614Y102487D01*
X38861Y101970D01*
X39105Y101382D01*
X40352Y100866D01*
X40940Y101109D01*
X44174Y99770D01*
X46455D01*
X46900Y99325D01*
Y97750D01*
G01X6693Y109095D02*
X5491D01*
X4701Y109885D01*
Y111551D01*
X5707Y112557D01*
X20400D01*
X20850Y112107D01*
X22200D01*
X22650Y112557D01*
X24000D01*
X24450Y112107D01*
X25800D01*
X26250Y112557D01*
X27600D01*
X28050Y112107D01*
X29400D01*
X29850Y112557D01*
X31200D01*
X31650Y112107D01*
X33000D01*
X33450Y112557D01*
X34800D01*
X37902Y115659D01*
X38538D01*
X39493Y116613D01*
Y117250D01*
X40447Y118204D01*
X41084D01*
X42038Y119159D01*
Y119795D01*
X42993Y120750D01*
X50850D01*
X51569Y120031D01*
Y118750D01*
G01X11811Y116969D02*
X10179D01*
X9515Y117633D01*
Y119015D01*
X10931Y120431D01*
X29775D01*
X33932Y124588D01*
X34568D01*
X35523Y125542D01*
Y126179D01*
X36477Y127133D01*
X37114D01*
X38068Y128088D01*
Y128724D01*
X39023Y129679D01*
X39659D01*
X40614Y130633D01*
Y131270D01*
X41568Y132224D01*
X42205D01*
X43159Y133179D01*
Y133815D01*
X44114Y134770D01*
X50929D01*
X51569Y134130D01*
Y132750D01*
G01X28346Y148465D02*
X27136D01*
X26066Y149535D01*
Y151022D01*
X27026Y151982D01*
X37418D01*
X38420Y150980D01*
X48424D01*
X49784Y152340D01*
Y153484D01*
X50656Y154356D01*
X51309D01*
G01X57069Y147990D02*
X55332D01*
X54517Y147175D01*
X42165D01*
X39031Y144041D01*
X-10972D01*
X-12123Y142890D01*
Y141041D01*
X-11673Y140591D01*
X-9843D01*
G01X22835Y148465D02*
X24666D01*
X25116Y148915D01*
Y151416D01*
X26632Y152932D01*
X37812D01*
X38814Y151930D01*
X48030D01*
X48834Y152734D01*
Y153906D01*
X48384Y154356D01*
X47309D01*
G01X-15354Y140591D02*
X-13523D01*
X-13073Y141041D01*
Y143284D01*
X-11366Y144991D01*
X38637D01*
X41771Y148125D01*
X54123D01*
X54938Y148940D01*
X62560D01*
G01X511500Y418187D02*
Y445385D01*
X507216Y449670D01*
X484513Y454211D01*
X457265Y448761D01*
X432541Y453706D01*
X414376Y450073D01*
X386987Y455551D01*
X356683Y449491D01*
X320971Y456634D01*
X274858Y447412D01*
Y447413D01*
X212410Y459902D01*
X141560Y466879D01*
X119661D01*
X91097Y456656D01*
X72128Y437743D01*
X48225Y427844D01*
X44953Y424573D01*
X35818Y402519D01*
X34043Y400744D01*
X28100D01*
X26290Y402554D01*
Y403690D01*
X27206Y404606D01*
X28346D01*
G01X510550Y418187D02*
Y444991D01*
X506747Y448794D01*
X484511Y453242D01*
Y453241D01*
X467855Y449909D01*
Y449910D01*
X467502Y449381D01*
X466178Y449116D01*
X465649Y449469D01*
X464325Y449204D01*
X463972Y448675D01*
X462648Y448410D01*
X462119Y448763D01*
X460795Y448498D01*
X460442Y447969D01*
X459118Y447704D01*
X458589Y448057D01*
X457265Y447792D01*
X449184Y449408D01*
X448654Y449055D01*
X447331Y449320D01*
X446978Y449850D01*
X445654Y450114D01*
X445124Y449761D01*
X443801Y450026D01*
X443448Y450556D01*
X442124Y450820D01*
X441594Y450467D01*
X440270Y450732D01*
X439917Y451262D01*
X438594Y451526D01*
X438064Y451173D01*
X436740Y451438D01*
X436387Y451968D01*
X432541Y452737D01*
X430192Y452267D01*
X429839Y451738D01*
X428515Y451473D01*
X427986Y451826D01*
X426662Y451561D01*
X426309Y451032D01*
X424985Y450767D01*
X424455Y451120D01*
X423132Y450855D01*
X422779Y450326D01*
X421455Y450061D01*
X420925Y450414D01*
X414376Y449104D01*
X412192Y449541D01*
X411663Y449188D01*
X410339Y449453D01*
X409986Y449982D01*
X386987Y454582D01*
X356683Y448522D01*
X320971Y455665D01*
X274858Y446443D01*
X212270Y458961D01*
X176891Y462445D01*
X141513Y465929D01*
X119826D01*
X91618Y455832D01*
X72666Y436936D01*
X48764Y427038D01*
X45759Y424034D01*
X36624Y401980D01*
X34437Y399794D01*
X27706D01*
X25340Y402160D01*
Y404173D01*
X24907Y404606D01*
X22835D01*
G01X1181Y365236D02*
X2329D01*
X3297Y364268D01*
Y362181D01*
X4634Y360844D01*
X29744D01*
X37128Y368228D01*
X46463Y390762D01*
X48996Y393295D01*
X50355D01*
X51630Y392020D01*
G01X6299Y373110D02*
X8110D01*
X8580Y373580D01*
Y375724D01*
X10398Y377542D01*
X29842D01*
X37934Y385634D01*
X43622Y399365D01*
X46401Y402145D01*
X47555D01*
X48830Y403420D01*
G01X-10236Y357362D02*
X-8541D01*
X-7510Y356331D01*
Y354580D01*
X-5600Y352670D01*
X34113D01*
X38985Y357541D01*
X46149Y374830D01*
X47582Y382038D01*
X49163Y383619D01*
X50351Y383612D01*
X50354D01*
X51610Y382340D01*
G01X6693Y365236D02*
X5437D01*
X4247Y364046D01*
Y362575D01*
X5028Y361794D01*
X29350D01*
X36322Y368767D01*
X40146Y377997D01*
X39902Y378585D01*
X40419Y379833D01*
X41007Y380076D01*
X41524Y381323D01*
X41280Y381911D01*
X41797Y383158D01*
X42385Y383402D01*
X42901Y384649D01*
X42658Y385237D01*
X43175Y386484D01*
X43763Y386728D01*
X44279Y387975D01*
X44036Y388563D01*
X44552Y389810D01*
X45140Y390054D01*
X45657Y391301D01*
X48602Y394245D01*
X50355D01*
X51630Y395520D01*
G01X11811Y373110D02*
X10000D01*
X9530Y373580D01*
Y375330D01*
X10792Y376592D01*
X30236D01*
X33599Y379955D01*
X34236D01*
X35190Y380909D01*
X35191Y381546D01*
X36145Y382500D01*
X36782D01*
X37736Y383455D01*
Y384091D01*
X38740Y385095D01*
X40295Y388848D01*
X40883Y389092D01*
X41399Y390339D01*
X41156Y390927D01*
X41672Y392174D01*
X42260Y392418D01*
X42777Y393665D01*
X42534Y394253D01*
X43050Y395500D01*
X43638Y395744D01*
X44155Y396991D01*
X43911Y397579D01*
X44428Y398826D01*
X46795Y401195D01*
X47555D01*
X48830Y399920D01*
G01X-4725Y357362D02*
X-5635D01*
X-6560Y356437D01*
Y354974D01*
X-5206Y353620D01*
X26504D01*
X26954Y354070D01*
X28304D01*
X28754Y353620D01*
X30104D01*
X30554Y354070D01*
X31904D01*
X32354Y353620D01*
X33719D01*
X38179Y358080D01*
X38705Y359348D01*
X38461Y359936D01*
X38978Y361183D01*
X39566Y361427D01*
X40083Y362674D01*
X39839Y363262D01*
X40356Y364509D01*
X40944Y364753D01*
X41461Y366000D01*
X41217Y366588D01*
X41734Y367835D01*
X42322Y368078D01*
X42839Y369325D01*
X42596Y369913D01*
X43112Y371161D01*
X43700Y371404D01*
X45235Y375107D01*
X45498Y376431D01*
X45145Y376960D01*
X45408Y378284D01*
X45937Y378638D01*
X46706Y382506D01*
X48772Y384572D01*
X50356Y384562D01*
X51630Y385820D01*
G01X518252Y420739D02*
Y448599D01*
X509375Y457475D01*
X508051Y457740D01*
X507522Y457387D01*
X506198Y457652D01*
X505845Y458181D01*
X504521Y458446D01*
X503992Y458093D01*
X502668Y458358D01*
X502315Y458887D01*
X500991Y459152D01*
X500462Y458799D01*
X499138Y459064D01*
X498785Y459593D01*
X481699Y463010D01*
X459350Y458542D01*
X428691Y464673D01*
X405354Y460006D01*
X384142Y464249D01*
X357500Y458921D01*
X323832Y465654D01*
X290178Y458923D01*
X257965Y465365D01*
X257436Y465012D01*
X257131Y463491D01*
X257484Y462962D01*
X273332Y459793D01*
X274121Y458610D01*
X273660Y456311D01*
X272477Y455522D01*
X252904Y459437D01*
X252115Y460620D01*
X253166Y465867D01*
X252813Y466396D01*
X251345Y466690D01*
X239150Y464251D01*
X135593Y474450D01*
X120762D01*
X87384Y462507D01*
X68282Y443402D01*
X39530Y431491D01*
X35168Y427129D01*
X31774Y418942D01*
X23904Y414923D01*
X22304D01*
X20948Y413567D01*
Y412930D01*
X21398Y412480D01*
X23228D01*
G01X531628Y418444D02*
Y453022D01*
X511779Y472871D01*
X483140Y478597D01*
X460699Y474110D01*
Y474111D01*
X429311Y480388D01*
X402144Y474955D01*
X382450Y478894D01*
X355771Y473558D01*
X323448Y480022D01*
X291471Y473627D01*
X254790Y480964D01*
X237262Y477458D01*
X139360Y487100D01*
X118533D01*
X80529Y473278D01*
X61091Y453841D01*
X32152Y441852D01*
X19710Y429410D01*
X15946D01*
X14050Y427514D01*
Y425300D01*
X13600Y424850D01*
X12025D01*
G01X515350Y420550D02*
Y447294D01*
X508775Y453869D01*
X484260Y458772D01*
X458459Y453612D01*
X432264Y458851D01*
X411590Y454716D01*
X385908Y459852D01*
X357861Y454243D01*
X322337Y461348D01*
X273474Y451574D01*
Y451575D01*
X210846Y464100D01*
X139289Y471150D01*
X120307D01*
X88807Y459877D01*
X69868Y440937D01*
X46031Y431065D01*
X41690Y426700D01*
X37117Y415661D01*
X30495Y409038D01*
X10694D01*
X8750Y407094D01*
Y405240D01*
X8116Y404606D01*
X6299D01*
G01X534623Y417251D02*
Y454076D01*
X512950Y475749D01*
X481995Y481943D01*
X461005Y477745D01*
X430046Y483936D01*
X401316Y478190D01*
X381741Y482105D01*
X355286Y476814D01*
X323151Y483241D01*
X291047Y476821D01*
X254937Y484042D01*
X246330Y482321D01*
X237722Y480599D01*
X142280Y490000D01*
X108382D01*
X82404Y479238D01*
X59576Y456410D01*
X30156Y444222D01*
X27313Y441379D01*
X24897D01*
X24447Y440929D01*
Y439354D01*
G01X541260Y429470D02*
Y454184D01*
X513951Y481493D01*
X483163Y487652D01*
X462767Y483571D01*
X431285Y489867D01*
X399508Y483512D01*
X381620Y487090D01*
X356033Y481973D01*
X323815Y488417D01*
X290838Y481821D01*
X254556Y489076D01*
X237681Y485702D01*
X145299Y494800D01*
X107543D01*
X77734Y482454D01*
X68853D01*
X64667Y480711D01*
X55050Y471094D01*
Y464544D01*
X46979Y456473D01*
X29448Y449210D01*
X20746D01*
X16946Y445410D01*
X14955D01*
X12811Y443266D01*
Y442235D01*
X12361Y441785D01*
X10786D01*
G01X523100Y421716D02*
Y450543D01*
X510993Y462651D01*
X480437Y468762D01*
X460088Y464692D01*
X429705Y470769D01*
X404414Y465710D01*
X383643Y469864D01*
X359256Y464987D01*
X326468Y471544D01*
X291169Y464484D01*
X252751Y472168D01*
X237794Y469176D01*
X135001Y479300D01*
X120141D01*
X84689Y466612D01*
X65514Y447437D01*
X36842Y435559D01*
X30940Y429656D01*
X27415Y422191D01*
X18670Y417723D01*
X-10658D01*
X-12570Y415811D01*
Y413181D01*
X-13271Y412480D01*
X-15354D01*
G01X526073Y423060D02*
Y451777D01*
X510523Y467326D01*
X496876Y470056D01*
X496347Y469703D01*
X495023Y469967D01*
X494670Y470497D01*
X493346Y470762D01*
X492817Y470409D01*
X491493Y470674D01*
X491140Y471203D01*
X489816Y471468D01*
X489287Y471115D01*
X487963Y471380D01*
X487610Y471909D01*
X486286Y472174D01*
X485757Y471821D01*
X484433Y472086D01*
X484080Y472615D01*
X482756Y472880D01*
X470348Y470398D01*
X469995Y469869D01*
X468671Y469604D01*
X468141Y469957D01*
X466818Y469692D01*
X466465Y469163D01*
X465141Y468898D01*
X464611Y469251D01*
X460740Y468477D01*
X430517Y474522D01*
X404316Y469282D01*
X383582Y473429D01*
X357761Y468265D01*
X324967Y474824D01*
X291308Y468092D01*
X253190Y475715D01*
X236897Y472456D01*
X137457Y482250D01*
X119724D01*
X83196Y469177D01*
X63861Y449841D01*
X35214Y437973D01*
X28407Y431166D01*
X25134Y424230D01*
X18225Y420700D01*
X5806D01*
X4050Y422456D01*
Y424400D01*
X3600Y424850D01*
X2025D01*
G01X17716Y412480D02*
X19548D01*
X19998Y412930D01*
Y413961D01*
X21910Y415873D01*
X23675D01*
X31030Y419629D01*
X34362Y427668D01*
X38991Y432297D01*
X67743Y444208D01*
X86863Y463330D01*
X120597Y475400D01*
X135640D01*
X239102Y465211D01*
X251345Y467659D01*
X253386Y467251D01*
X254175Y466067D01*
X253124Y460820D01*
X253477Y460292D01*
X272277Y456531D01*
X272805Y456884D01*
X273111Y458410D01*
X272759Y458938D01*
X256912Y462107D01*
X256121Y463291D01*
X256581Y465585D01*
X257765Y466374D01*
X290178Y459892D01*
X323832Y466623D01*
X357500Y459890D01*
X384142Y465218D01*
X405354Y460975D01*
X428691Y465642D01*
X459350Y459511D01*
X481699Y463979D01*
X509844Y458351D01*
X519202Y448993D01*
Y420739D01*
G01X530678Y418444D02*
Y452628D01*
X511310Y471995D01*
X483142Y477627D01*
Y477628D01*
X460699Y473141D01*
X429311Y479419D01*
X402144Y473986D01*
X382450Y477925D01*
X355771Y472589D01*
X323448Y479053D01*
X291471Y472658D01*
X254790Y479995D01*
X237310Y476498D01*
X139313Y486150D01*
X118701D01*
X81052Y472457D01*
X61630Y453035D01*
X32691Y441046D01*
X20104Y428460D01*
X16340D01*
X15000Y427120D01*
Y425300D01*
X15450Y424850D01*
X17025D01*
G01X514400Y420550D02*
Y446900D01*
X508306Y452994D01*
Y452993D01*
X506369Y453381D01*
X505839Y453028D01*
X504515Y453292D01*
X504162Y453822D01*
X502839Y454087D01*
X502309Y453734D01*
X500985Y453998D01*
X500632Y454528D01*
X499309Y454793D01*
X498779Y454440D01*
X497455Y454705D01*
X497102Y455234D01*
X484260Y457803D01*
X458459Y452643D01*
X432264Y457882D01*
X411590Y453747D01*
X385908Y458883D01*
X357861Y453274D01*
X322337Y460379D01*
X273474Y450605D01*
X210706Y463159D01*
X139242Y470200D01*
X120472D01*
X89328Y459054D01*
X70407Y440131D01*
X46571Y430259D01*
X42496Y426163D01*
X37923Y415122D01*
X30889Y408088D01*
X11088D01*
X9700Y406700D01*
Y405110D01*
X10204Y404606D01*
X11811D01*
G01X24447Y444354D02*
Y442779D01*
X24897Y442329D01*
X26919D01*
X29619Y445029D01*
X59037Y457216D01*
X81865Y480044D01*
X108193Y490950D01*
X142327D01*
X189999Y486255D01*
X190000D01*
X237674Y481559D01*
X254937Y485011D01*
X291047Y477790D01*
X323151Y484210D01*
X355286Y477783D01*
X381741Y483074D01*
X401316Y479159D01*
X430046Y484905D01*
X461005Y478714D01*
X481995Y482912D01*
X499299Y479450D01*
X499828Y479803D01*
X501152Y479538D01*
X501505Y479009D01*
X502829Y478744D01*
X503358Y479097D01*
X504682Y478832D01*
X505035Y478302D01*
X506359Y478038D01*
X506888Y478391D01*
X508212Y478126D01*
X508565Y477596D01*
X509889Y477331D01*
X510418Y477684D01*
X511742Y477419D01*
X512095Y476890D01*
X513419Y476625D01*
X535573Y454470D01*
Y417251D01*
G01X540310Y443259D02*
Y453790D01*
X513482Y480617D01*
X512158Y480882D01*
X511629Y480529D01*
X510305Y480794D01*
X509952Y481323D01*
X508628Y481588D01*
X508099Y481235D01*
X506775Y481500D01*
X506422Y482030D01*
Y482029D01*
X483166Y486682D01*
X483163Y486683D01*
X462767Y482602D01*
X462765D01*
X431285Y488898D01*
X399508Y482543D01*
X381620Y486121D01*
X356033Y481004D01*
X323815Y487448D01*
X290838Y480852D01*
X254556Y488107D01*
X237729Y484742D01*
X145252Y493850D01*
X107732D01*
X77923Y481504D01*
X69043D01*
X65206Y479906D01*
X56000Y470700D01*
Y464150D01*
X53779Y461928D01*
X47518Y455667D01*
X38578Y451964D01*
X29638Y448260D01*
X21140D01*
X17340Y444460D01*
X15349D01*
X13761Y442872D01*
Y442235D01*
X14211Y441785D01*
X15786D01*
G01X-9843Y412480D02*
X-10730D01*
X-11620Y413370D01*
Y415417D01*
X-10264Y416773D01*
X18899D01*
X28136Y421492D01*
X31729Y429101D01*
X37381Y434753D01*
X66053Y446631D01*
X85210Y465789D01*
X120306Y478350D01*
X134954D01*
X237842Y468216D01*
X245295Y469706D01*
Y469707D01*
X252751Y471199D01*
X291169Y463515D01*
X326468Y470575D01*
X359256Y464018D01*
X383643Y468895D01*
X404414Y464741D01*
X429705Y469800D01*
X460088Y463723D01*
X480437Y467793D01*
X510524Y461775D01*
X522150Y450149D01*
Y421716D01*
G01X527023Y423060D02*
Y452171D01*
X510992Y468202D01*
X482756Y473849D01*
X460740Y469446D01*
X430517Y475491D01*
X404316Y470251D01*
X383582Y474398D01*
X357761Y469234D01*
X324967Y475793D01*
X291308Y469061D01*
X253190Y476684D01*
X236849Y473416D01*
X137504Y483200D01*
X119559D01*
X82675Y470000D01*
X63322Y450647D01*
X34675Y438779D01*
X27618Y431721D01*
X24413Y424929D01*
X17996Y421650D01*
X6200D01*
X5000Y422850D01*
Y424400D01*
X5450Y424850D01*
X7025D01*
G01X68098Y151473D02*
X66523D01*
X66073Y151023D01*
Y149098D01*
X64965Y147990D01*
X57069D01*
G01X62560Y148940D02*
X64571D01*
X65123Y149492D01*
Y151023D01*
X64673Y151473D01*
X63098D01*
G01X100287Y426488D02*
X96702Y422904D01*
Y419981D01*
X90315Y413594D01*
X87822Y407578D01*
X80595Y400350D01*
X76250D01*
X75280Y399380D01*
X63480D01*
X62000Y397900D01*
Y395700D01*
X59773Y393473D01*
X56583D01*
X55130Y392020D01*
G01X52330Y403420D02*
X53915Y401835D01*
X56035D01*
X58845Y404646D01*
X60487Y408613D01*
X60917Y409472D01*
X62189Y410742D01*
X62999Y411080D01*
X64580D01*
X65030Y411530D01*
X66380D01*
X66830Y411080D01*
X68180D01*
X68630Y411530D01*
X69980D01*
X70430Y411080D01*
X71780D01*
X72230Y411530D01*
X73580D01*
X74030Y411080D01*
X75380D01*
X88009Y423709D01*
Y426554D01*
X97916Y436463D01*
G01X84522Y389977D02*
X81645Y387100D01*
X66367D01*
X58156Y383699D01*
X58084Y383627D01*
X56397D01*
X55110Y382340D01*
G01X466849Y410402D02*
X462421Y411261D01*
X461894Y410905D01*
X460569Y411163D01*
X460213Y411690D01*
X458887Y411947D01*
X458360Y411591D01*
X457035Y411849D01*
X456679Y412376D01*
X455353Y412633D01*
X454826Y412277D01*
X453500Y412535D01*
X453144Y413062D01*
X451819Y413319D01*
X451292Y412963D01*
X449966Y413221D01*
X449610Y413748D01*
X442590Y415111D01*
X439770Y414547D01*
X439417Y414018D01*
X438093Y413753D01*
X437563Y414106D01*
X436239Y413841D01*
X435886Y413312D01*
X434563Y413047D01*
X434033Y413400D01*
X428975Y412389D01*
X422916Y413601D01*
X422387Y413248D01*
X421063Y413513D01*
X420710Y414042D01*
X419386Y414307D01*
X418857Y413954D01*
X417533Y414219D01*
X417180Y414748D01*
X415856Y415013D01*
X409150Y413671D01*
X408797Y413142D01*
X407473Y412877D01*
X406944Y413230D01*
X405620Y412965D01*
X405267Y412436D01*
X403943Y412171D01*
X403414Y412524D01*
X402090Y412259D01*
X391023Y414472D01*
X390494Y414119D01*
X389170Y414384D01*
X388817Y414913D01*
X387493Y415178D01*
X386964Y414825D01*
X385640Y415089D01*
X385287Y415619D01*
X382713Y416134D01*
X356610Y410914D01*
X350504Y406844D01*
X330675Y402879D01*
X271836Y414639D01*
X213228Y426354D01*
X136613Y433901D01*
X130359D01*
X124896Y431637D01*
X121565Y428307D01*
X110768Y426068D01*
X104758Y420058D01*
Y417235D01*
X96917Y409394D01*
X91954Y397409D01*
X84522Y389977D01*
G01X73730Y392580D02*
X75075Y393925D01*
X82368D01*
X89079Y400636D01*
X93560Y411457D01*
X99193Y417090D01*
Y417091D01*
X100934Y418832D01*
Y421635D01*
X108858Y429557D01*
X119643Y431797D01*
X122891Y435045D01*
X129307Y437704D01*
X139776D01*
G01X103799Y431342D02*
X95752Y423298D01*
Y420375D01*
X89509Y414133D01*
X87016Y408117D01*
X80201Y401300D01*
X75856D01*
X74886Y400330D01*
X63086D01*
X61050Y398294D01*
Y396094D01*
X59379Y394423D01*
X56227D01*
X55130Y395520D01*
G01X52330Y399920D02*
X53295Y400885D01*
X56429D01*
X59651Y404107D01*
X61353Y408218D01*
X61698Y408909D01*
X62728Y409937D01*
X63190Y410130D01*
X75774D01*
X88959Y423315D01*
Y426160D01*
X91900Y429101D01*
G01X467030Y411335D02*
X442587Y416080D01*
X428975Y413358D01*
X415856Y415982D01*
X402090Y413228D01*
X382713Y417103D01*
X356239Y411809D01*
X350133Y407739D01*
X330675Y403848D01*
X213368Y427295D01*
X136660Y434851D01*
X130169D01*
X124357Y432443D01*
X121094Y429180D01*
X110297Y426941D01*
X103808Y420452D01*
Y417629D01*
X96111Y409933D01*
X91148Y397948D01*
X81251Y388050D01*
X69500D01*
G01X55130Y385820D02*
X56373Y384577D01*
X57791D01*
X66178Y388050D01*
X69500D01*
G01X73730Y396080D02*
X74935Y394875D01*
X81974D01*
X88272Y401173D01*
X88273Y401175D01*
X92754Y411996D01*
X98521Y417762D01*
Y417763D01*
X99984Y419226D01*
Y422029D01*
X108387Y430430D01*
X119171Y432670D01*
X122352Y435851D01*
X129117Y438654D01*
X132100D01*
G01X70230Y392580D02*
X69088Y393722D01*
X66522D01*
X64725Y391925D01*
Y391645D01*
G01X70230Y396080D02*
X68822Y394672D01*
X66698D01*
X64725Y396645D01*
G01X58000Y351000D02*
X59537D01*
X60274Y351737D01*
X61041D01*
G01X58000Y351000D02*
Y355000D01*
X56600Y356400D01*
G01X61041Y351737D02*
X61792D01*
X62029Y351500D01*
X65000D01*
G01X69730Y424980D02*
X70850Y426100D01*
X71650D01*
X73022Y427472D01*
Y431068D01*
X91330Y449375D01*
X120236Y461350D01*
X134000D01*
G01X503745Y412776D02*
X481561Y434960D01*
X447277Y441778D01*
X429064Y438116D01*
X414027Y441123D01*
X403422Y439003D01*
X382812Y443125D01*
X355873Y437736D01*
X355344Y438089D01*
X354020Y437825D01*
X353667Y437295D01*
X352343Y437030D01*
X351814Y437383D01*
X350490Y437119D01*
X350137Y436589D01*
X344138Y435389D01*
X335058Y429335D01*
X328513Y428026D01*
X209771Y451756D01*
X142310Y458400D01*
X120596D01*
X92955Y446951D01*
X90811Y444806D01*
G01X57990Y423170D02*
X59340Y421820D01*
X69883D01*
X73494Y423317D01*
X77000Y426823D01*
Y430994D01*
X90811Y444806D01*
G01X100287Y426488D02*
X106974Y433172D01*
X117318Y435319D01*
X121100Y438534D01*
X121108Y438537D01*
X121156Y438558D01*
X121161Y438560D01*
X121165Y438562D01*
X121176Y438566D01*
X128291Y441514D01*
X143127D01*
X209631Y434963D01*
X330238Y410858D01*
X345429Y413903D01*
X351177Y417736D01*
X384980Y424495D01*
X395921Y422307D01*
X396274Y421778D01*
X397598Y421513D01*
X398127Y421866D01*
X399451Y421601D01*
X399804Y421072D01*
X401128Y420807D01*
X401657Y421160D01*
X403977Y420696D01*
X416314Y423164D01*
X429627Y420500D01*
X445240Y423622D01*
X446564Y423359D01*
X446918Y422830D01*
X448242Y422566D01*
X448771Y422920D01*
X450095Y422656D01*
X450448Y422127D01*
X451773Y421864D01*
X452302Y422217D01*
X453626Y421954D01*
X453979Y421425D01*
X455303Y421162D01*
X455833Y421515D01*
X457157Y421252D01*
X457510Y420723D01*
X458834Y420459D01*
X459363Y420813D01*
X464215Y419848D01*
X464568Y419319D01*
X465892Y419056D01*
X466421Y419409D01*
X467745Y419146D01*
X468099Y418617D01*
X469423Y418353D01*
X469952Y418707D01*
X473305Y418040D01*
G01X73730Y414180D02*
X75177Y415627D01*
X75865D01*
X85055Y424817D01*
Y427676D01*
X102572Y445193D01*
X122505Y453450D01*
X139300D01*
G01X485881Y419554D02*
X479170Y426265D01*
X445285Y433006D01*
X428705Y429689D01*
X416241Y432182D01*
X404459Y429826D01*
X382960Y434126D01*
X348214Y427177D01*
X340872Y422282D01*
X329084Y419924D01*
X208471Y444036D01*
X142863Y450499D01*
X127262D01*
X116753Y446146D01*
X112285Y443150D01*
X102750Y441298D01*
X99831Y438379D01*
Y438378D01*
X97916Y436463D01*
G01X82464Y407622D02*
X84501Y409662D01*
X87047Y415805D01*
X92839Y421597D01*
Y424442D01*
X105125Y436723D01*
X114379Y438644D01*
X119703Y442202D01*
X128025Y445650D01*
X140341D01*
X210055Y438784D01*
X329926Y414824D01*
X342917Y417424D01*
X349935Y422105D01*
X359955Y424109D01*
X360485Y423756D01*
X361808Y424021D01*
X362161Y424550D01*
X363485Y424815D01*
X364015Y424462D01*
X365338Y424727D01*
X365691Y425256D01*
X383158Y428749D01*
X403850Y424611D01*
X416211Y427083D01*
X428122Y424704D01*
X429446Y424969D01*
X429975Y424616D01*
X431299Y424880D01*
X431652Y425410D01*
X432976Y425675D01*
X433505Y425321D01*
X434829Y425586D01*
X435182Y426116D01*
X436506Y426380D01*
X437036Y426027D01*
X438359Y426292D01*
X438712Y426822D01*
X440036Y427086D01*
X440566Y426733D01*
X441889Y426998D01*
X442243Y427527D01*
X445326Y428144D01*
X450489Y427117D01*
X450843Y426588D01*
X452167Y426324D01*
X452696Y426678D01*
X454020Y426415D01*
X454374Y425885D01*
X455698Y425622D01*
X456227Y425976D01*
X462449Y424738D01*
X462802Y424209D01*
X464126Y423946D01*
X464655Y424299D01*
X465980Y424036D01*
X466333Y423507D01*
X467657Y423243D01*
X468186Y423597D01*
X469510Y423334D01*
X469864Y422805D01*
X471188Y422541D01*
X471717Y422895D01*
X473041Y422631D01*
X473395Y422102D01*
X474719Y421839D01*
X475248Y422192D01*
X476572Y421929D01*
X478640Y419861D01*
G01X73730Y403380D02*
X74872Y404522D01*
X79367D01*
X82048Y407205D01*
X82464Y407622D01*
G01X69730Y428480D02*
Y428070D01*
X70750Y427050D01*
X71256D01*
X72072Y427866D01*
Y431462D01*
X90791Y450181D01*
X120047Y462300D01*
X121800D01*
G01X81387Y434036D02*
X93494Y446145D01*
X120785Y457450D01*
X142263D01*
X209631Y450815D01*
X328513Y427057D01*
X335429Y428440D01*
X344509Y434494D01*
X382812Y442156D01*
X403422Y438034D01*
X414027Y440154D01*
X429065Y437146D01*
X447278Y440809D01*
X481093Y434084D01*
X503073Y412104D01*
G01X57990Y419670D02*
X59190Y420870D01*
X70073D01*
X74033Y422511D01*
X77950Y426429D01*
Y430599D01*
X81387Y434036D01*
G01X103799Y431342D02*
X106503Y434045D01*
X116887Y436200D01*
X120484Y439258D01*
X120483D01*
X120597Y439355D01*
X120788Y439435D01*
X120791Y439436D01*
X120799Y439439D01*
X120812Y439444D01*
X128102Y442464D01*
X143174D01*
X209771Y435904D01*
X330238Y411827D01*
X345058Y414798D01*
X350806Y418631D01*
X384980Y425464D01*
X403977Y421665D01*
X416314Y424133D01*
X429627Y421469D01*
X445240Y424591D01*
X473490Y418972D01*
G01X73730Y417680D02*
X74833Y416577D01*
X75471D01*
X84105Y425211D01*
Y428070D01*
X102033Y445999D01*
X122316Y454400D01*
X126700D01*
G01X91900Y429101D02*
X103220Y440421D01*
X112655Y442254D01*
X117204Y445304D01*
X127451Y449549D01*
X142815D01*
X142816Y449548D01*
Y449549D01*
X208331Y443095D01*
X329084Y418955D01*
X341243Y421387D01*
X348585Y426282D01*
X382960Y433157D01*
X404459Y428857D01*
X416241Y431213D01*
X428705Y428720D01*
X445286Y432037D01*
X478702Y425389D01*
X485209Y418882D01*
G01X73730Y406880D02*
X75138Y405472D01*
X78973D01*
X83695Y410200D01*
X86241Y416344D01*
X91889Y421991D01*
Y424836D01*
X104654Y437596D01*
X114005Y439537D01*
X119253Y443044D01*
X127835Y446600D01*
X130000D01*
G01X66230Y428480D02*
X65030Y427280D01*
X61920D01*
X61005Y428195D01*
Y429305D01*
G01X49265Y423995D02*
Y422735D01*
X50030Y421970D01*
X53290D01*
X54490Y423170D01*
G01X66809Y416405D02*
X58465D01*
X52810Y410750D01*
Y408410D01*
X54244Y406976D01*
Y405624D01*
G01X70230Y417680D02*
X68955Y416405D01*
X66809D01*
G01X63024Y405636D02*
X64693D01*
X65415Y406358D01*
X68143D01*
X68420Y406081D01*
X69431D01*
X70230Y406880D01*
G01X66230Y424980D02*
X64880Y426330D01*
X61930D01*
X61005Y425405D01*
Y424305D01*
G01X49265Y418995D02*
Y420165D01*
X50120Y421020D01*
X53140D01*
X54490Y419670D01*
G01X60279Y415455D02*
X58859D01*
X58152Y414748D01*
Y414055D01*
X57444Y413347D01*
X56751D01*
X56044Y412640D01*
Y411947D01*
X55336Y411239D01*
X54643D01*
X53760Y410356D01*
Y408804D01*
X54924Y407640D01*
X55860D01*
X56383Y408163D01*
G01X70230Y414180D02*
Y414990D01*
X69765Y415455D01*
X66900D01*
X66410Y414965D01*
X65410D01*
X64920Y415455D01*
X63920D01*
X63430Y414965D01*
X62430D01*
X61940Y415455D01*
X60279D01*
G01X65384Y403258D02*
Y404983D01*
X65809Y405408D01*
X67749D01*
X68026Y405131D01*
X69083D01*
X70230Y403984D01*
Y403380D01*
G01X206696Y651654D02*
X205190Y650086D01*
X203176D01*
X198827Y650423D01*
X193498Y649531D01*
X191355Y646895D01*
X191018Y644986D01*
X190498Y644623D01*
X189079Y644873D01*
X188714Y645393D01*
X190240Y654048D01*
X189423Y655214D01*
X187229Y655599D01*
X186061Y654782D01*
X184352Y645081D01*
X183832Y644717D01*
X182414Y644967D01*
X182050Y645488D01*
X183560Y654059D01*
X182745Y655228D01*
X180551Y655613D01*
X179383Y654796D01*
X177671Y645079D01*
X177151Y644715D01*
X175732Y644965D01*
X175367Y645484D01*
X176864Y653978D01*
X176049Y655145D01*
X173853Y655529D01*
X172685Y654714D01*
X170987Y645067D01*
X170467Y644702D01*
X169049Y644952D01*
X168685Y645473D01*
X170179Y653956D01*
X169364Y655125D01*
X167170Y655510D01*
X166002Y654693D01*
X164308Y645073D01*
X163788Y644709D01*
X162368Y644957D01*
X162004Y645477D01*
X163501Y653972D01*
X162684Y655138D01*
X160492Y655523D01*
X159323Y654708D01*
X157614Y645006D01*
X157095Y644643D01*
X155675Y644891D01*
X155311Y645411D01*
X156816Y653952D01*
X155999Y655118D01*
X153806Y655503D01*
X152638Y654686D01*
X150934Y645014D01*
X150401Y644641D01*
X149005Y644887D01*
X148629Y645422D01*
X150136Y653974D01*
X149320Y655141D01*
X147128Y655526D01*
X145959Y654709D01*
X144251Y645000D01*
X143731Y644636D01*
X142310Y644886D01*
X141947Y645406D01*
X143455Y653973D01*
X142638Y655139D01*
X140447Y655523D01*
X139278Y654706D01*
X137574Y645033D01*
X137054Y644669D01*
X135634Y644918D01*
X135269Y645440D01*
X136771Y653957D01*
X135956Y655126D01*
X133763Y655511D01*
X132595Y654694D01*
X130906Y645126D01*
X130383Y644760D01*
X128967Y645009D01*
X128602Y645532D01*
X130104Y654050D01*
X129287Y655217D01*
X127092Y655602D01*
X125927Y654787D01*
X124223Y645114D01*
X123699Y644748D01*
X122283Y644996D01*
X121918Y645517D01*
X123426Y654083D01*
X122613Y655249D01*
X120415Y655635D01*
X119250Y654820D01*
X117542Y645111D01*
X117019Y644745D01*
X115602Y644994D01*
X115237Y645515D01*
X116745Y654069D01*
X115916Y655248D01*
X113745Y655631D01*
X112567Y654806D01*
X110863Y645134D01*
X110340Y644768D01*
X108922Y645017D01*
X108557Y645538D01*
X110062Y654079D01*
X109246Y655244D01*
X107052Y655629D01*
X105887Y654814D01*
X104178Y645113D01*
X103655Y644748D01*
X102237Y644997D01*
X101872Y645518D01*
X103369Y654013D01*
X102553Y655178D01*
X100359Y655563D01*
X99193Y654747D01*
X97499Y645127D01*
X96976Y644761D01*
X95559Y645010D01*
X95194Y645533D01*
X96689Y654017D01*
X95873Y655183D01*
X93679Y655569D01*
X92514Y654753D01*
X90816Y645107D01*
X90293Y644742D01*
X88873Y644990D01*
X88509Y645511D01*
X90006Y654006D01*
X89190Y655170D01*
X86996Y655557D01*
X85830Y654741D01*
X84118Y645024D01*
X83595Y644658D01*
X82178Y644907D01*
X81813Y645430D01*
X83324Y654002D01*
X82508Y655168D01*
X80314Y655555D01*
X79149Y654739D01*
X77440Y645038D01*
X76917Y644672D01*
X75498Y644921D01*
X75133Y645442D01*
X76659Y654097D01*
X75843Y655262D01*
X73649Y655648D01*
X72483Y654835D01*
X72121Y652780D01*
X70360Y650614D01*
X65500Y649801D01*
X61230Y650131D01*
X59179D01*
X57684Y651626D01*
G01X206696Y647714D02*
X205190Y649136D01*
X203139D01*
X198869Y649466D01*
X194009Y648653D01*
X192248Y646487D01*
X191886Y644432D01*
X190720Y643619D01*
X188526Y644005D01*
X187710Y645170D01*
X189236Y653825D01*
X188871Y654346D01*
X187452Y654595D01*
X186929Y654229D01*
X185220Y644528D01*
X184055Y643712D01*
X181861Y644099D01*
X181045Y645265D01*
X182556Y653837D01*
X182191Y654360D01*
X180774Y654609D01*
X180251Y654243D01*
X178539Y644526D01*
X177373Y643710D01*
X175179Y644097D01*
X174363Y645261D01*
X175860Y653756D01*
X175496Y654277D01*
X174076Y654525D01*
X173553Y654160D01*
X171855Y644514D01*
X170690Y643698D01*
X168496Y644084D01*
X167680Y645250D01*
X169175Y653734D01*
X168810Y654257D01*
X167393Y654506D01*
X166870Y654140D01*
X165176Y644520D01*
X164010Y643704D01*
X161816Y644089D01*
X161000Y645254D01*
X162497Y653749D01*
X162132Y654270D01*
X160714Y654519D01*
X160191Y654154D01*
X158482Y644453D01*
X157317Y643638D01*
X155123Y644023D01*
X154307Y645188D01*
X155812Y653729D01*
X155447Y654250D01*
X154029Y654499D01*
X153506Y654133D01*
X151802Y644461D01*
X150624Y643636D01*
X148453Y644019D01*
X147624Y645198D01*
X149132Y653752D01*
X148767Y654273D01*
X147350Y654522D01*
X146827Y654156D01*
X145119Y644447D01*
X143954Y643632D01*
X141756Y644018D01*
X140943Y645184D01*
X142451Y653750D01*
X142086Y654271D01*
X140670Y654519D01*
X140146Y654153D01*
X138442Y644480D01*
X137277Y643665D01*
X135082Y644050D01*
X134265Y645217D01*
X135767Y653735D01*
X135402Y654258D01*
X133986Y654507D01*
X133463Y654141D01*
X131774Y644573D01*
X130606Y643756D01*
X128413Y644141D01*
X127598Y645310D01*
X129100Y653827D01*
X128735Y654349D01*
X127315Y654598D01*
X126795Y654234D01*
X125091Y644561D01*
X123922Y643744D01*
X121731Y644128D01*
X120914Y645294D01*
X122422Y653861D01*
X122059Y654381D01*
X120638Y654631D01*
X120118Y654267D01*
X118410Y644558D01*
X117241Y643741D01*
X115049Y644126D01*
X114233Y645293D01*
X115740Y653845D01*
X115364Y654380D01*
X113968Y654626D01*
X113435Y654253D01*
X111731Y644581D01*
X110563Y643764D01*
X108370Y644149D01*
X107553Y645315D01*
X109058Y653856D01*
X108694Y654376D01*
X107274Y654624D01*
X106755Y654261D01*
X105046Y644559D01*
X103877Y643744D01*
X101685Y644129D01*
X100868Y645295D01*
X102365Y653790D01*
X102001Y654310D01*
X100581Y654558D01*
X100061Y654194D01*
X98367Y644574D01*
X97199Y643757D01*
X95005Y644142D01*
X94190Y645311D01*
X95684Y653794D01*
X95320Y654315D01*
X93902Y654565D01*
X93382Y654200D01*
X91684Y644553D01*
X90516Y643738D01*
X88320Y644122D01*
X87505Y645289D01*
X89002Y653783D01*
X88637Y654302D01*
X87218Y654552D01*
X86698Y654188D01*
X84986Y644471D01*
X83818Y643654D01*
X81624Y644039D01*
X80809Y645208D01*
X82319Y653779D01*
X81955Y654300D01*
X80537Y654550D01*
X80017Y654186D01*
X78308Y644485D01*
X77140Y643668D01*
X74946Y644053D01*
X74129Y645219D01*
X75655Y653874D01*
X75290Y654394D01*
X73871Y654644D01*
X73351Y654281D01*
X73014Y652372D01*
X70871Y649736D01*
X65542Y648844D01*
X61193Y649181D01*
X59179D01*
X57684Y647686D01*
G01X509092Y411096D02*
Y412197D01*
X483881Y437409D01*
X446057Y444931D01*
X427979Y441316D01*
X413936Y444124D01*
X404647Y442266D01*
X403863Y442422D01*
X379383Y447319D01*
X359911Y443425D01*
X324149Y450578D01*
X277964Y441339D01*
X210182Y454746D01*
X143133Y461350D01*
X134000D01*
G01X139300Y453450D02*
X143311D01*
X209035Y446977D01*
X329286Y422942D01*
X338713Y424826D01*
X346621Y430098D01*
X383411Y437455D01*
X404311Y433275D01*
X415036Y435421D01*
X427643Y432901D01*
X431537Y433680D01*
X432066Y433327D01*
X433390Y433591D01*
X433743Y434121D01*
X435067Y434386D01*
X435596Y434033D01*
X436920Y434298D01*
X437273Y434827D01*
X438597Y435092D01*
X439126Y434739D01*
X440450Y435004D01*
X440803Y435533D01*
X442127Y435798D01*
X442656Y435445D01*
X443980Y435710D01*
X444333Y436239D01*
X445657Y436504D01*
X454052Y434834D01*
X454406Y434305D01*
X455730Y434041D01*
X456259Y434395D01*
X479965Y429679D01*
X491638Y418006D01*
G01X139776Y437704D02*
X141246D01*
X210388Y430894D01*
X330268Y406929D01*
X348477Y410569D01*
X354362Y414493D01*
X382999Y420219D01*
X402407Y416338D01*
X416658Y419188D01*
X429746Y416572D01*
X444266Y419476D01*
X445590Y419211D01*
X445943Y418682D01*
X447267Y418417D01*
X447796Y418770D01*
X449120Y418505D01*
X449473Y417976D01*
X450797Y417711D01*
X451326Y418064D01*
X457032Y416923D01*
X457386Y416394D01*
X458709Y416129D01*
X459239Y416482D01*
X460563Y416218D01*
X460916Y415688D01*
X462239Y415423D01*
X462769Y415776D01*
X464093Y415512D01*
X464446Y414982D01*
X465770Y414717D01*
X466299Y415071D01*
X467623Y414806D01*
X467976Y414276D01*
X469300Y414012D01*
X469829Y414365D01*
X471153Y414100D01*
X471213Y414040D01*
X471214D01*
X474829Y410425D01*
G01X510042Y411096D02*
Y412591D01*
X484349Y438285D01*
X476868Y439773D01*
X476514Y440302D01*
X475190Y440565D01*
X474661Y440212D01*
X473337Y440475D01*
X472983Y441004D01*
X471659Y441267D01*
X471130Y440914D01*
X469806Y441177D01*
X469453Y441706D01*
X468128Y441969D01*
X467599Y441616D01*
X446056Y445900D01*
X444187Y445526D01*
X443657Y445879D01*
X442334Y445615D01*
X441981Y445085D01*
X440657Y444820D01*
X440127Y445173D01*
X438804Y444909D01*
X438451Y444379D01*
X438450D01*
X427979Y442285D01*
X413936Y445093D01*
X404646Y443235D01*
X379383Y448288D01*
X359911Y444394D01*
X324149Y451547D01*
X277963Y442308D01*
X210321Y455687D01*
X143180Y462300D01*
X121800D01*
G01X126700Y454400D02*
X143358D01*
X209175Y447918D01*
X329286Y423911D01*
X338342Y425721D01*
X346250Y430993D01*
X383411Y438424D01*
X404311Y434244D01*
X415036Y436390D01*
X427643Y433870D01*
X445656Y437473D01*
X480433Y430555D01*
X492310Y418678D01*
G01X130000Y446600D02*
X140388D01*
X210195Y439725D01*
X329926Y415793D01*
X342546Y418319D01*
X349564Y423000D01*
X383158Y429718D01*
X403850Y425580D01*
X416211Y428052D01*
X428122Y425673D01*
X445326Y429113D01*
X477040Y422805D01*
X479312Y420533D01*
G01X132100Y438654D02*
X141293D01*
X210528Y431835D01*
X270397Y419868D01*
Y419867D01*
X330268Y407898D01*
X348106Y411464D01*
X353991Y415388D01*
X382999Y421188D01*
X402407Y417307D01*
X416658Y420157D01*
X429746Y417541D01*
X444266Y420445D01*
X471622Y414976D01*
X475501Y411097D01*
G01X246406Y647786D02*
X247829Y649209D01*
X258700D01*
X261125Y646784D01*
G01X246406Y651726D02*
X247773Y650359D01*
X258700D01*
X261125Y652784D01*
G01X394280Y647594D02*
X392941Y648933D01*
X381986D01*
X379561Y646508D01*
G01X394280Y651534D02*
X392829Y650083D01*
X381986D01*
X379561Y652508D01*
G01X469200Y199793D02*
Y176564D01*
X470125Y171803D01*
X470595Y171487D01*
X470852Y170161D01*
X470536Y169692D01*
X472977Y157125D01*
X480538Y145919D01*
X480539D01*
X504162Y129981D01*
X564666Y118220D01*
X574177Y113566D01*
X642815Y99571D01*
X655337Y97391D01*
X671823Y100597D01*
X686323Y97852D01*
X695086Y95534D01*
X707617Y93828D01*
X709260Y93517D01*
X714098Y93381D01*
X734851Y99081D01*
X746561Y99664D01*
X753784Y106513D01*
X773726Y106915D01*
X776162Y107185D01*
X819944Y113035D01*
X822543Y113978D01*
X825191Y115032D01*
X833745Y114293D01*
X835917Y114667D01*
X875578Y122906D01*
X887969Y125480D01*
X932614Y116553D01*
X940705Y118172D01*
X964071Y113499D01*
X982802Y109753D01*
X1001336Y106411D01*
X1036777Y113499D01*
X1103254Y126794D01*
X1150542Y117339D01*
X1175868Y122402D01*
X1209817Y148675D01*
X1211400Y156596D01*
X1213718Y168196D01*
X1213405Y168667D01*
X1213669Y169992D01*
X1214141Y170306D01*
X1214405Y171629D01*
X1214092Y172100D01*
X1214356Y173425D01*
X1214828Y173739D01*
X1215092Y175062D01*
X1214778Y175533D01*
X1215043Y176858D01*
X1215515Y177172D01*
X1215779Y178495D01*
X1215465Y178966D01*
X1215730Y180291D01*
X1216202Y180605D01*
X1216466Y181928D01*
X1216152Y182399D01*
X1216417Y183724D01*
X1216889Y184038D01*
X1217153Y185361D01*
X1216839Y185832D01*
X1217104Y187157D01*
X1217576Y187471D01*
X1217840Y188794D01*
X1217424Y196092D01*
X1217001Y196469D01*
X1216924Y197817D01*
X1217301Y198240D01*
X1217225Y199587D01*
X1216802Y199964D01*
X1216725Y201313D01*
X1217101Y201735D01*
X1216961Y204203D01*
X1216368Y207170D01*
X1215897Y207484D01*
X1215632Y208809D01*
X1215946Y209280D01*
X1215682Y210603D01*
X1215211Y210917D01*
X1214946Y212242D01*
X1215260Y212713D01*
X1214996Y214036D01*
X1214524Y214350D01*
X1214259Y215675D01*
X1214573Y216146D01*
X1214309Y217469D01*
X1213135Y218663D01*
X1210070Y220592D01*
X1208871Y221791D01*
G01X472790Y197933D02*
Y181415D01*
X477634Y156494D01*
X482761Y148892D01*
X502857Y135337D01*
X502858D01*
X505938Y133260D01*
X591523Y116622D01*
X599605Y113909D01*
X609968Y114864D01*
X610026Y114832D01*
X610025D01*
X615240Y111960D01*
X615241D01*
X620583Y109019D01*
X657038Y101495D01*
X673051Y104696D01*
X695325Y98651D01*
X714283Y96463D01*
X734566Y102171D01*
X752613Y109184D01*
X771156Y108934D01*
X776073Y109542D01*
X821052Y116229D01*
X824000Y117309D01*
X825322Y117794D01*
X834259Y117439D01*
X875578Y126121D01*
X886836Y128487D01*
X887376Y128632D01*
X932583Y119591D01*
X940558Y121186D01*
X978991Y113499D01*
X987216Y111854D01*
X994716Y111536D01*
X1002067Y109555D01*
X1021783Y113499D01*
X1103233Y129792D01*
X1137941Y122850D01*
X1149470Y120276D01*
X1174891Y125931D01*
X1206774Y151494D01*
X1214154Y191446D01*
X1214074Y193510D01*
X1211400Y203571D01*
X1211180Y204399D01*
X1209331Y208627D01*
G01X468250Y199807D02*
Y176472D01*
X472081Y156754D01*
X479853Y145235D01*
X503791Y129085D01*
X564361Y117311D01*
X573868Y112659D01*
X642639Y98637D01*
X655347Y96424D01*
X671825Y99629D01*
X686081Y96933D01*
X694900Y94600D01*
X707465Y92889D01*
X709158Y92569D01*
X714213Y92427D01*
X735002Y98137D01*
X746960Y98732D01*
X754171Y105570D01*
X763978Y105768D01*
X763979D01*
X773788Y105966D01*
X776277Y106241D01*
X820172Y112107D01*
X822881Y113090D01*
X824000Y113535D01*
X825333Y114066D01*
X833786Y113335D01*
X836095Y113733D01*
X875578Y121935D01*
X887973Y124510D01*
X932614Y115584D01*
X940705Y117203D01*
X959225Y113499D01*
X982624Y108819D01*
X1001345Y105443D01*
X1103254Y125825D01*
X1150542Y116370D01*
X1176273Y121514D01*
X1210680Y148140D01*
X1211400Y151741D01*
X1218796Y188727D01*
X1217906Y204324D01*
X1215186Y217933D01*
X1213735Y219408D01*
X1211400Y220878D01*
X1210667Y221340D01*
X1209544Y222463D01*
G01X503389Y136125D02*
X502196Y136929D01*
X483446Y149577D01*
X478530Y156865D01*
X473741Y181507D01*
X473740Y181508D01*
Y183933D01*
X474140Y184333D01*
Y185683D01*
X473740Y186083D01*
Y187433D01*
X474140Y187833D01*
Y189183D01*
X473740Y189583D01*
Y190933D01*
X474140Y191333D01*
Y192683D01*
X473740Y193083D01*
Y194433D01*
X474140Y194833D01*
Y196183D01*
X473740Y196583D01*
Y197933D01*
G01X481767Y203406D02*
Y201609D01*
X477657Y180451D01*
X481927Y158479D01*
X486469Y151744D01*
X507833Y137333D01*
X592799Y120815D01*
X604919Y121451D01*
X613950Y120797D01*
X616751Y120238D01*
X633043Y110870D01*
X659150Y105920D01*
X672174Y108525D01*
X672180Y108526D01*
X677681Y108695D01*
X696707Y108258D01*
X707072Y106669D01*
X722000Y102800D01*
X729121Y104600D01*
X730023Y104905D01*
X752856Y112605D01*
X771997Y112080D01*
X776995Y112762D01*
X820473Y119751D01*
X824000Y121079D01*
X824822Y121389D01*
X832690Y121472D01*
X837979Y122211D01*
X875578Y130215D01*
X886419Y132523D01*
X887082Y132701D01*
X932732Y123571D01*
X940167Y125059D01*
X987077Y115676D01*
X995097Y115753D01*
X1003520Y113745D01*
X1103436Y133730D01*
X1149478Y124521D01*
X1173227Y130157D01*
X1201319Y152937D01*
X1207829Y188388D01*
X1207232Y197165D01*
X1204785Y204614D01*
X1204023Y205646D01*
X1203599Y207176D01*
G01X433874Y647516D02*
X435297Y648939D01*
X436256D01*
X438681Y646514D01*
G01X433874Y651456D02*
X435241Y650089D01*
X436256D01*
X438681Y652514D01*
G01X500618Y205407D02*
Y192201D01*
X515284Y177535D01*
X524077Y164500D01*
X544829Y150503D01*
X594323Y141154D01*
X603491Y139207D01*
X610637Y140604D01*
X619970Y139523D01*
X627944Y135930D01*
X630191Y135769D01*
X644136Y132982D01*
X653936Y134942D01*
X654504Y134829D01*
X665689Y132898D01*
X672983Y131848D01*
X680582Y131605D01*
X722991Y120523D01*
X739543Y125670D01*
X746273Y127988D01*
X774035Y126152D01*
X818421Y135028D01*
X825445Y137902D01*
X831493Y138951D01*
X887232Y150097D01*
X936858Y140172D01*
X939012Y138735D01*
X977511Y131035D01*
X994605Y133129D01*
X1009015Y131902D01*
X1102116Y150524D01*
X1146715Y141602D01*
X1163482Y146540D01*
X1177570Y159214D01*
X1177600Y159779D01*
X1178605Y160682D01*
X1179170Y160653D01*
X1180173Y161555D01*
X1180203Y162120D01*
X1181208Y163024D01*
X1181773Y162994D01*
X1182776Y163896D01*
X1183193Y166133D01*
X1182873Y166600D01*
X1183121Y167928D01*
X1183589Y168247D01*
X1183836Y169574D01*
X1183516Y170041D01*
X1183764Y171369D01*
X1184232Y171688D01*
X1184479Y173015D01*
X1184159Y173482D01*
X1184407Y174810D01*
X1184875Y175129D01*
X1185122Y176456D01*
X1184802Y176923D01*
X1185050Y178251D01*
X1185518Y178570D01*
X1185765Y179897D01*
X1185445Y180364D01*
X1185693Y181692D01*
X1186161Y182011D01*
X1186408Y183338D01*
X1186088Y183805D01*
X1186336Y185133D01*
X1186804Y185452D01*
X1187694Y190220D01*
X1187128Y197092D01*
G01X594741Y135085D02*
X541445Y145711D01*
X521000Y159502D01*
X520479Y159853D01*
X510347Y174873D01*
X510353D01*
X510362Y174882D01*
Y174884D01*
X495005Y190241D01*
Y205055D01*
G01X490645Y203000D02*
Y188538D01*
X491331Y184444D01*
X507686Y171040D01*
X517544Y156424D01*
X539469Y141636D01*
X540555Y141427D01*
X596710Y129107D01*
X610019Y131632D01*
X615863Y130570D01*
X622421Y126576D01*
Y126575D01*
G01X487206Y202262D02*
Y200610D01*
X486974Y199281D01*
X487299Y198818D01*
X487066Y197487D01*
X486602Y197162D01*
X486370Y195833D01*
X486695Y195370D01*
X486462Y194039D01*
X485998Y193714D01*
X485764Y192377D01*
X486089Y191914D01*
X485856Y190583D01*
X485392Y190258D01*
X485160Y188929D01*
X485485Y188466D01*
X485252Y187135D01*
X484788Y186810D01*
X484556Y185481D01*
X484881Y185018D01*
X484648Y183687D01*
X484184Y183362D01*
X483640Y180247D01*
X483897Y178922D01*
X484367Y178606D01*
X484625Y177280D01*
X484308Y176811D01*
X484565Y175486D01*
X485035Y175170D01*
X485293Y173844D01*
X484976Y173375D01*
X485233Y172050D01*
X485703Y171734D01*
X485961Y170408D01*
X485644Y169939D01*
X485901Y168614D01*
X486371Y168298D01*
X486629Y166972D01*
X486312Y166503D01*
X486569Y165178D01*
X487039Y164862D01*
X487296Y163536D01*
X486980Y163067D01*
X487516Y160306D01*
X488270Y159187D01*
X488826Y159079D01*
X489582Y157959D01*
X489474Y157404D01*
X490853Y155360D01*
X510098Y142377D01*
X595344Y125806D01*
X609019Y128440D01*
X615013Y127372D01*
X634315Y115737D01*
X658679Y110863D01*
X671684Y113465D01*
X695092Y113451D01*
X708513Y111273D01*
X723993Y108363D01*
X730111Y110144D01*
X749592Y117022D01*
X772245Y116217D01*
X775821Y116744D01*
X820120Y124306D01*
X826230Y126405D01*
X834213Y126607D01*
X836494Y126951D01*
X875578Y135386D01*
X886312Y137702D01*
X887273Y137970D01*
X932288Y128523D01*
X938437Y129452D01*
X983982Y120337D01*
X995143Y120599D01*
X1005397Y119006D01*
X1103421Y138611D01*
X1148910Y129514D01*
X1159950Y132335D01*
X1159951D01*
X1170990Y135155D01*
X1196468Y156130D01*
X1202131Y190171D01*
X1202066Y194650D01*
X1200671Y201732D01*
X1200138Y202903D01*
G01X543984Y131273D02*
Y131274D01*
X508204Y138229D01*
X487154Y152429D01*
X482823Y158850D01*
X481965Y163271D01*
X482281Y163740D01*
X482024Y165066D01*
X481554Y165382D01*
X481297Y166707D01*
X481613Y167176D01*
X481356Y168502D01*
X480886Y168818D01*
X480629Y170143D01*
X480945Y170612D01*
X480688Y171938D01*
X480218Y172254D01*
X479961Y173579D01*
X480278Y174048D01*
X480020Y175374D01*
X479550Y175690D01*
X479293Y177015D01*
X479610Y177484D01*
X479352Y178810D01*
X478882Y179126D01*
X478625Y180451D01*
X479086Y182829D01*
X479556Y183145D01*
X479813Y184471D01*
X479497Y184940D01*
X479754Y186265D01*
X480224Y186581D01*
X480481Y187907D01*
X480165Y188376D01*
X480422Y189701D01*
X480892Y190017D01*
X481149Y191343D01*
X480833Y191812D01*
X482717Y201517D01*
Y203406D01*
G01X503389Y136125D02*
X506309Y134156D01*
X591766Y117543D01*
X599717Y114874D01*
X610171Y115837D01*
X620916Y109921D01*
X657041Y102465D01*
X673084Y105672D01*
X695505Y99587D01*
X714206Y97429D01*
X734264Y103074D01*
X752441Y110137D01*
X771104Y109885D01*
X775945Y110484D01*
X820816Y117155D01*
X824000Y118322D01*
X825172Y118751D01*
X834179Y118393D01*
X875578Y127093D01*
X886601Y129409D01*
X887345Y129608D01*
X932583Y120560D01*
X940558Y122155D01*
X987330Y112801D01*
X994861Y112481D01*
X1002099Y110531D01*
X1016937Y113499D01*
X1103233Y130761D01*
X1138138Y123780D01*
X1149470Y121250D01*
X1174469Y126811D01*
X1205903Y152015D01*
X1210061Y174531D01*
X1209740Y174997D01*
X1209985Y176325D01*
X1210452Y176646D01*
X1210697Y177973D01*
X1210376Y178439D01*
X1210621Y179767D01*
X1211088Y180088D01*
X1211333Y181415D01*
X1211012Y181881D01*
X1211257Y183209D01*
X1211400Y183307D01*
X1211724Y183530D01*
X1211969Y184857D01*
X1211648Y185323D01*
X1211893Y186651D01*
X1212360Y186972D01*
X1212605Y188299D01*
X1212284Y188765D01*
X1212529Y190093D01*
X1212996Y190414D01*
X1213200Y191515D01*
X1213128Y193368D01*
X1211735Y198612D01*
X1211122Y198967D01*
X1210891Y199838D01*
X1211246Y200450D01*
X1211015Y201319D01*
X1210403Y201674D01*
X1210172Y202545D01*
X1210526Y203157D01*
X1210280Y204085D01*
X1208460Y208247D01*
G01X499668Y205407D02*
Y191807D01*
X514547Y176927D01*
X523392Y163815D01*
X544460Y149605D01*
X594136Y140222D01*
X603483Y138237D01*
X610674Y139643D01*
X619714Y138596D01*
X627707Y134994D01*
X630064Y134825D01*
X644136Y132013D01*
X653936Y133973D01*
X654330Y133894D01*
X665540Y131959D01*
X672900Y130900D01*
X680445Y130658D01*
X723014Y119535D01*
X739839Y124767D01*
X746401Y127027D01*
X774098Y125195D01*
X818697Y134114D01*
X822201Y135548D01*
X822203D01*
X825709Y136983D01*
X831668Y138016D01*
X875578Y146797D01*
X887232Y149128D01*
X936487Y139277D01*
X936902Y139000D01*
X938641Y137840D01*
X977475Y130073D01*
X994623Y132174D01*
X1009069Y130943D01*
X1102116Y149555D01*
X1146759Y140624D01*
X1163958Y145689D01*
X1183651Y163405D01*
X1188652Y190171D01*
X1188075Y197169D01*
G01X1190463Y200001D02*
X1190661Y198901D01*
X1190668Y198866D01*
X1192795Y190633D01*
X1192556Y189305D01*
X1192091Y188982D01*
X1191851Y187653D01*
X1192174Y187188D01*
X1191935Y185860D01*
X1191470Y185537D01*
X1191230Y184208D01*
X1191553Y183743D01*
X1191314Y182415D01*
X1190849Y182092D01*
X1190609Y180763D01*
X1190932Y180298D01*
X1190693Y178970D01*
X1190228Y178647D01*
X1189988Y177318D01*
X1190311Y176853D01*
X1190072Y175525D01*
X1189607Y175202D01*
X1189367Y173872D01*
X1189690Y173408D01*
X1189451Y172080D01*
X1188986Y171757D01*
X1188747Y170427D01*
X1189069Y169963D01*
X1188830Y168635D01*
X1188365Y168312D01*
X1188126Y166982D01*
X1188449Y166518D01*
X1187631Y161972D01*
X1166781Y143702D01*
X1146439Y138025D01*
X1140906Y138884D01*
X1102114Y146644D01*
X1009075Y128034D01*
X993936Y129044D01*
X977755Y127827D01*
X939266Y135494D01*
X934850Y136651D01*
X932623Y136402D01*
X886971Y146047D01*
X885877Y145786D01*
X832093Y134589D01*
X825060Y134077D01*
X820545Y132254D01*
X818445Y131461D01*
X776441Y123451D01*
X772577Y122801D01*
X746290Y123846D01*
X724580Y116902D01*
X723082Y116564D01*
X659461Y129800D01*
X652202Y130685D01*
X643111Y128867D01*
X633553Y131130D01*
X628320Y131441D01*
X619152Y135716D01*
X611085Y136722D01*
X601006Y134805D01*
X541818Y146606D01*
X521164Y160538D01*
X521000Y160781D01*
X511035Y175555D01*
X495955Y190635D01*
Y198055D01*
X496355Y198455D01*
Y199805D01*
X495955Y200205D01*
Y201555D01*
X496355Y201955D01*
Y203305D01*
X495955Y203705D01*
Y205055D01*
G01X491595Y203000D02*
Y188618D01*
X492209Y184953D01*
X493253Y184098D01*
X493816Y184154D01*
X494861Y183297D01*
X494917Y182734D01*
X495961Y181879D01*
X496524Y181935D01*
X497569Y181078D01*
X497625Y180515D01*
X498669Y179660D01*
X499232Y179716D01*
X500277Y178859D01*
X500332Y178296D01*
X501376Y177441D01*
X501939Y177497D01*
X502984Y176640D01*
X503040Y176077D01*
X508396Y171687D01*
X518229Y157109D01*
X539840Y142533D01*
X540746Y142358D01*
X596724Y130077D01*
X610015Y132599D01*
X616207Y131474D01*
X628968Y123700D01*
X629240Y123646D01*
X629828Y124039D01*
X630712Y123862D01*
X631104Y123273D01*
X654840Y118524D01*
X674362Y122429D01*
X679536Y121647D01*
X685062Y118631D01*
X695986Y117446D01*
X723542Y112476D01*
X727006Y113255D01*
X746940Y120176D01*
X773148Y119778D01*
X777505Y120469D01*
X777507D01*
X777519Y120472D01*
X777527Y120473D01*
X818588Y127730D01*
X825688Y130285D01*
X833366Y130659D01*
X875578Y139605D01*
X886803Y141984D01*
X932475Y132484D01*
X936522Y132938D01*
X981543Y123933D01*
X996373Y124598D01*
X1006531Y123174D01*
X1103281Y142525D01*
X1147632Y133654D01*
X1167348Y139000D01*
X1167400Y139014D01*
X1168372Y139278D01*
X1192285Y159331D01*
X1194630Y172639D01*
X1195148Y175579D01*
X1194743Y176158D01*
X1194899Y177046D01*
X1195479Y177451D01*
X1195722Y178831D01*
X1195316Y179410D01*
X1195473Y180297D01*
X1196053Y180703D01*
X1196365Y182476D01*
X1195960Y183055D01*
X1196116Y183943D01*
X1196696Y184348D01*
X1196956Y185825D01*
X1196550Y186404D01*
X1196707Y187291D01*
X1197287Y187697D01*
X1197756Y190360D01*
X1194630Y200552D01*
X1194606Y200630D01*
Y201247D01*
G01X486256Y202262D02*
Y200693D01*
X482673Y180238D01*
X486620Y159935D01*
X490168Y154675D01*
X499943Y148081D01*
X499944D01*
X509727Y141481D01*
X595343Y124838D01*
X609026Y127473D01*
X614673Y126467D01*
X633966Y114837D01*
X634129Y114804D01*
Y114805D01*
X658679Y109894D01*
X671778Y112514D01*
X695015Y112501D01*
X708349Y110337D01*
X724041Y107387D01*
X730402Y109239D01*
X749738Y116066D01*
X772298Y115264D01*
X775970Y115805D01*
X820356Y123382D01*
X826400Y125458D01*
X834296Y125658D01*
X836665Y126016D01*
X875578Y134413D01*
X886540Y136779D01*
X887305Y136992D01*
X932261Y127557D01*
X938414Y128487D01*
X983899Y119384D01*
X995081Y119647D01*
X1005418Y118041D01*
X1103421Y137642D01*
X1148936Y128539D01*
X1171431Y134286D01*
X1197347Y155623D01*
X1203083Y190099D01*
X1203015Y194750D01*
X1201583Y202022D01*
X1201003Y203297D01*
G01X513200Y202400D02*
Y197615D01*
X524566Y186248D01*
X532663Y174245D01*
X548905Y163289D01*
X608136Y150895D01*
X625175Y154208D01*
X636570Y149680D01*
X647081Y151782D01*
X657149Y149423D01*
X674110Y152771D01*
X728472Y134512D01*
X739772Y137118D01*
X750303Y136091D01*
X775224Y134754D01*
X811313Y141973D01*
X823565Y148308D01*
X824000Y148380D01*
X830785Y149510D01*
X875578Y158469D01*
X889159Y161185D01*
X939185Y151182D01*
X947977Y145319D01*
X976372Y139641D01*
X990440Y142452D01*
X997136Y144549D01*
X1010371Y143895D01*
X1021013Y145116D01*
X1102478Y161411D01*
X1149821Y151942D01*
X1154425Y152862D01*
X1157608Y154983D01*
X1161550Y160963D01*
X1166753Y170070D01*
X1167400Y172093D01*
X1173925Y192490D01*
X1175920Y197400D01*
G01X632584Y147965D02*
X623823Y151002D01*
X605875Y147513D01*
X548647Y159288D01*
X548212Y159360D01*
X548211Y159361D01*
X529744Y171815D01*
X522283Y182876D01*
X509650Y196434D01*
Y201132D01*
X510050Y201532D01*
Y202882D01*
X509650Y203282D01*
Y204632D01*
G01X1183898Y197401D02*
Y197208D01*
X1183882Y189465D01*
X1177849Y166337D01*
X1161209Y148432D01*
X1147658Y144352D01*
X1129506Y147983D01*
X1129500Y147984D01*
X1129491Y147986D01*
X1129485Y147987D01*
X1102181Y153448D01*
X1009427Y134895D01*
X996629Y136257D01*
X977229Y133213D01*
X940899Y140479D01*
X935988Y143752D01*
X888441Y153263D01*
X875578Y150690D01*
X830773Y141728D01*
X830630Y141706D01*
X825813Y141338D01*
X814680Y136452D01*
X774723Y128461D01*
X744233Y130337D01*
X723075Y123706D01*
X683931Y134418D01*
X661477Y136712D01*
X654578Y138096D01*
X644220Y136023D01*
X628711Y139060D01*
X616802Y143885D01*
X613815Y144175D01*
X604882Y142442D01*
X545972Y154125D01*
X526355Y167356D01*
X518179Y179476D01*
X504199Y193455D01*
Y206468D01*
G01X671037Y176163D02*
X655920Y181451D01*
X612810Y172761D01*
X559248Y186062D01*
X556710Y187772D01*
X556602Y188328D01*
X555481Y189083D01*
X554926Y188975D01*
X553807Y189729D01*
X553699Y190284D01*
X552578Y191039D01*
X552023Y190931D01*
X550904Y191685D01*
X550055Y192950D01*
X550164Y193505D01*
X549411Y194626D01*
X548856Y194736D01*
X548104Y195856D01*
X548213Y196411D01*
X547460Y197532D01*
X546905Y197642D01*
X546153Y198762D01*
X546262Y199317D01*
X545508Y200439D01*
X544953Y200548D01*
X544950Y200552D01*
X544201Y201668D01*
X543975Y202058D01*
G01X537969Y198003D02*
X540708Y195263D01*
X545119Y188722D01*
X555901Y181449D01*
X601514Y169953D01*
X601876Y169862D01*
X611245Y167502D01*
X627395Y170642D01*
X637208Y166506D01*
X645472Y168157D01*
X648549Y168773D01*
X649420Y168607D01*
X652227Y167918D01*
X658055Y166099D01*
X673378Y170113D01*
X714116Y161977D01*
X732061Y157100D01*
X745683Y154222D01*
X750294Y151246D01*
X756936Y148304D01*
X775583Y147167D01*
X804538Y152958D01*
X819899Y163124D01*
X875578Y174259D01*
X891222Y177388D01*
X945624Y166507D01*
X963572Y154543D01*
X976392Y151981D01*
X981141Y152930D01*
X994845Y161217D01*
X1018997Y161624D01*
X1019026D01*
X1028872Y162389D01*
X1099663Y176547D01*
X1102476Y177217D01*
X1130246Y175901D01*
X1141604Y183120D01*
X1143830Y183696D01*
X1148574Y187527D01*
X1152351Y192365D01*
X1159041Y200555D01*
X1159361Y200875D01*
G01X532826Y198073D02*
X537081Y193818D01*
X542445Y185866D01*
X543441Y185195D01*
X543996Y185302D01*
X545116Y184546D01*
X545224Y183991D01*
X546343Y183237D01*
X546898Y183344D01*
X548018Y182589D01*
X548126Y182033D01*
X549245Y181279D01*
X549800Y181387D01*
X550920Y180631D01*
X551028Y180075D01*
X554500Y177734D01*
X556645Y177307D01*
X610285Y164375D01*
X626865Y167597D01*
X636750Y163472D01*
X647622Y165645D01*
X648051Y165633D01*
X658918Y162766D01*
X676176Y166636D01*
X712329Y153142D01*
X728790Y148706D01*
X734258Y149706D01*
X751026Y146353D01*
X775124Y144981D01*
X806252Y151206D01*
X820571Y160344D01*
X875578Y171238D01*
X890530Y174199D01*
X944037Y163502D01*
X959514Y153183D01*
X976410Y149804D01*
X983501Y151223D01*
X983504Y151224D01*
X994441Y157367D01*
X1009419Y157101D01*
X1027423Y159228D01*
X1027940Y159268D01*
X1100359Y173754D01*
X1100373Y173758D01*
X1102552Y174257D01*
X1130220Y172902D01*
X1141669Y180422D01*
X1146490Y181594D01*
X1152925Y186993D01*
X1157536Y193913D01*
X1157425Y194468D01*
X1158175Y195592D01*
X1158730Y195703D01*
X1159478Y196826D01*
X1159368Y197380D01*
X1160117Y198505D01*
X1160672Y198615D01*
X1162182Y200881D01*
G01X523322Y204254D02*
Y201209D01*
X524276Y200255D01*
X524842D01*
X525797Y199299D01*
Y198734D01*
X526751Y197780D01*
X527317D01*
X528272Y196824D01*
Y196259D01*
X532657Y191874D01*
X539309Y182011D01*
X540428Y181257D01*
X540983Y181364D01*
X542103Y180608D01*
X542211Y180053D01*
X543330Y179299D01*
X543885Y179406D01*
X545005Y178651D01*
X545113Y178095D01*
X546232Y177341D01*
X546787Y177449D01*
X546800Y177440D01*
X547907Y176693D01*
X548015Y176138D01*
X551853Y173549D01*
X609140Y160276D01*
X625569Y163468D01*
X626792Y163021D01*
Y163022D01*
X636398Y159507D01*
X647165Y161660D01*
X658844Y158803D01*
X675116Y161965D01*
X717275Y147399D01*
X729296Y144555D01*
X734041Y145697D01*
X751271Y143234D01*
X774986Y141853D01*
X808159Y148487D01*
X822641Y157126D01*
X830361Y158285D01*
X830384Y158289D01*
X875578Y167328D01*
X890354Y170283D01*
X941904Y159982D01*
X955494Y150924D01*
X976402Y146740D01*
X985225Y148505D01*
X991218Y151271D01*
X996412Y153412D01*
X1010176Y152872D01*
X1026057Y154949D01*
X1103269Y170390D01*
X1130325Y169013D01*
X1130400Y169059D01*
X1131134Y169511D01*
X1143072Y177455D01*
X1149188Y179027D01*
X1158493Y185381D01*
X1160593Y188556D01*
X1160481Y189111D01*
X1161226Y190238D01*
X1161781Y190351D01*
X1162525Y191476D01*
X1163328Y193359D01*
X1163118Y193883D01*
X1163648Y195126D01*
X1164173Y195337D01*
X1164703Y196578D01*
X1164492Y197103D01*
X1165022Y198345D01*
X1165548Y198556D01*
X1166078Y199797D01*
X1166381Y200418D01*
X1166380D01*
G01X601995Y156616D02*
X564556Y164821D01*
X558287Y166195D01*
X551143Y167584D01*
X535445Y178173D01*
X528424Y188581D01*
X517750Y199256D01*
Y201055D01*
G01X514150Y202350D02*
Y198009D01*
X525303Y186856D01*
X533348Y174930D01*
X549282Y164181D01*
X608143Y151865D01*
X625267Y155194D01*
X636659Y150667D01*
X647097Y152755D01*
X657166Y150395D01*
X665444Y152029D01*
X665446Y152030D01*
X674173Y153752D01*
X728520Y135499D01*
X734325Y136837D01*
X734326D01*
X739710Y138079D01*
X750375Y137039D01*
X775155Y135710D01*
X810995Y142879D01*
X823261Y149221D01*
X830614Y150445D01*
X875578Y159438D01*
X889159Y162154D01*
X939556Y152077D01*
X948348Y146214D01*
X976372Y140610D01*
X990204Y143374D01*
X997014Y145507D01*
X1010340Y144848D01*
X1020865Y146056D01*
X1102478Y162380D01*
X1149821Y152911D01*
X1154054Y153758D01*
X1156921Y155667D01*
X1160740Y161461D01*
X1162682Y164861D01*
X1162496Y165543D01*
X1162942Y166326D01*
X1163625Y166512D01*
X1164071Y167293D01*
X1163885Y167975D01*
X1164332Y168758D01*
X1165015Y168944D01*
X1165878Y170455D01*
X1167400Y175214D01*
X1167415Y175261D01*
X1167400Y175290D01*
X1167179Y175720D01*
X1167400Y176413D01*
X1167535Y176836D01*
X1167994Y177072D01*
X1169451Y181629D01*
X1169128Y182257D01*
X1169402Y183115D01*
X1170031Y183439D01*
X1170305Y184296D01*
X1169981Y184925D01*
X1170256Y185783D01*
X1170885Y186107D01*
X1171356Y187580D01*
X1171032Y188208D01*
X1171307Y189067D01*
X1171936Y189391D01*
X1173031Y192814D01*
X1175040Y197758D01*
G01X1180004Y197400D02*
Y194243D01*
X1179857Y193992D01*
X1173071Y168825D01*
X1160479Y153236D01*
X1155635Y150008D01*
X1147242Y148329D01*
X1129327Y151913D01*
X1129297Y151920D01*
X1102219Y157336D01*
X1019588Y140810D01*
X1009995Y139210D01*
X997978Y140486D01*
X977200Y136403D01*
X974441Y136866D01*
X943812Y142992D01*
X935720Y147872D01*
X888865Y157242D01*
X875578Y154584D01*
X830703Y145608D01*
X824451Y144679D01*
X824000Y144469D01*
X812599Y139148D01*
X774874Y131605D01*
X742196Y133554D01*
X737203Y132225D01*
X723534Y128573D01*
X689396Y137906D01*
X670133Y140179D01*
X665572Y144531D01*
X662352Y145271D01*
X660640Y145019D01*
X659803Y144852D01*
X646849Y147779D01*
X636301Y145670D01*
X623753Y150020D01*
X605870Y146544D01*
X548473Y158353D01*
X547850Y158458D01*
X529059Y171130D01*
X521537Y182283D01*
X521000Y182859D01*
X508700Y196060D01*
Y204632D01*
G01X649591Y138067D02*
X644218Y136992D01*
X629412Y139903D01*
X628974Y139979D01*
X617031Y144818D01*
X613770Y145134D01*
X609328Y144273D01*
X609327D01*
X604884Y143411D01*
X546345Y155020D01*
X527040Y168041D01*
X518916Y180084D01*
X505149Y193849D01*
Y206468D01*
G01X545812Y204337D02*
X546410Y203739D01*
X548862D01*
X549392Y203209D01*
X551934Y199444D01*
X551560Y197514D01*
X553441Y194731D01*
X554908Y194446D01*
X558843Y197101D01*
X559152Y197041D01*
X559160Y197039D01*
X559467Y196980D01*
X560554Y195368D01*
X560418Y194673D01*
X559770Y194236D01*
Y194235D01*
X559123Y193799D01*
X558671Y191476D01*
X559803Y189798D01*
X562044Y189358D01*
X564036Y190701D01*
X565597Y190392D01*
X567458Y187637D01*
X570902Y186700D01*
X572836Y187807D01*
X574227Y187429D01*
X575210Y185714D01*
X579873Y184445D01*
X581619Y185445D01*
X584160Y184754D01*
X584873Y183507D01*
X612929Y175876D01*
X655647Y184688D01*
X679511Y176812D01*
X725692Y167573D01*
X743669Y167778D01*
X743800Y167650D01*
X744122Y167334D01*
X744144Y165450D01*
X745162Y164455D01*
X747195Y164478D01*
X747501Y164482D01*
X748495Y165499D01*
X748473Y167384D01*
X748916Y167837D01*
X751587Y167867D01*
X763362Y158691D01*
X765700Y157159D01*
X777621Y153786D01*
X798694Y158002D01*
X818813Y170635D01*
X831499Y173447D01*
X875578Y182267D01*
X892669Y185687D01*
X948613Y174499D01*
X976592Y180095D01*
X1025973Y170220D01*
X1102552Y185531D01*
X1129883Y183603D01*
X1130400Y183930D01*
X1139267Y189535D01*
X1142737Y194781D01*
X1148189Y201250D01*
X1152416Y203947D01*
X1153204Y205181D01*
G01X543151Y201581D02*
X543378Y201191D01*
Y201190D01*
X550218Y191000D01*
X550219Y191001D01*
X558856Y185180D01*
X612788Y171787D01*
X655852Y180468D01*
X675010Y173767D01*
X722353Y164299D01*
X735830Y161094D01*
X741201Y161452D01*
X748885Y156361D01*
X751479Y154708D01*
X757993Y152013D01*
X775296Y150222D01*
X801559Y155475D01*
X818595Y166833D01*
X891872Y181490D01*
X948529Y170158D01*
X976893Y175832D01*
X989601Y173289D01*
X989954Y172761D01*
X989182Y168900D01*
X989971Y167716D01*
X993049Y167100D01*
X994233Y167890D01*
X995005Y171750D01*
X995533Y172102D01*
X997843Y171639D01*
X998196Y171111D01*
X997424Y167250D01*
X998213Y166066D01*
X1001291Y165450D01*
X1002475Y166240D01*
X1003247Y170100D01*
X1003775Y170453D01*
X1025576Y166094D01*
X1102427Y181463D01*
X1130060Y179753D01*
X1143036Y187552D01*
X1143798Y188776D01*
X1151654Y198782D01*
G01X538641Y198675D02*
X541445Y195871D01*
X542199Y194752D01*
X542755Y194644D01*
X543510Y193524D01*
X543402Y192969D01*
X545804Y189407D01*
X546923Y188652D01*
X547478Y188760D01*
X548598Y188004D01*
X548706Y187449D01*
X549825Y186695D01*
X550380Y186802D01*
X551500Y186046D01*
X551608Y185491D01*
X552727Y184737D01*
X553282Y184844D01*
X554402Y184089D01*
X554510Y183533D01*
X556294Y182330D01*
X601747Y170876D01*
G01X532076Y197479D02*
X536344Y193210D01*
X541760Y185181D01*
X554127Y176839D01*
X556441Y176378D01*
X610263Y163402D01*
X626546Y166567D01*
X626764Y166609D01*
X636652Y162483D01*
X647703Y164692D01*
X647913Y164686D01*
X658900Y161788D01*
X676108Y165647D01*
X712039Y152236D01*
X728750Y147732D01*
X734210Y148728D01*
X734211Y148727D01*
X734257Y148736D01*
X734260D01*
X750905Y145408D01*
X775191Y144025D01*
X806613Y150309D01*
X820932Y159446D01*
X875578Y170269D01*
X890530Y173230D01*
X943666Y162607D01*
X959143Y152288D01*
X976410Y148835D01*
X983835Y150320D01*
X994682Y156412D01*
X1009467Y156149D01*
X1027516Y158282D01*
X1028070Y158325D01*
X1100572Y172827D01*
X1100599Y172834D01*
X1102636Y173301D01*
X1130483Y171937D01*
X1142054Y179537D01*
X1144303Y180083D01*
X1144304Y180085D01*
X1146930Y180723D01*
X1153641Y186352D01*
X1156021Y189926D01*
Y189925D01*
X1162973Y200354D01*
G01X522372Y204254D02*
Y200814D01*
X531920Y191266D01*
X538624Y181326D01*
X551467Y172663D01*
X609123Y159304D01*
X625491Y162485D01*
X636322Y158522D01*
X641967Y159650D01*
Y159651D01*
X647144Y160686D01*
X658821Y157830D01*
X675047Y160983D01*
X696028Y153734D01*
Y153735D01*
X717010Y146485D01*
X729298Y143578D01*
X734087Y144730D01*
X751176Y142287D01*
X775053Y140897D01*
X808505Y147587D01*
X822967Y156214D01*
X830515Y157347D01*
X830560Y157355D01*
X875578Y166359D01*
X890354Y169314D01*
X941533Y159086D01*
X955123Y150029D01*
X976402Y145771D01*
X985521Y147595D01*
X991598Y150400D01*
X996582Y152454D01*
X1010219Y151919D01*
X1026212Y154011D01*
X1103339Y169435D01*
X1130572Y168049D01*
X1131647Y168710D01*
X1143465Y176574D01*
X1149586Y178148D01*
X1159183Y184701D01*
X1163366Y191023D01*
X1166943Y199402D01*
X1167235Y200001D01*
G01X1171068Y200773D02*
X1170554Y198965D01*
X1170553Y198961D01*
X1170552Y198958D01*
X1170033Y197712D01*
X1169509Y197497D01*
X1168990Y196250D01*
X1169205Y195727D01*
X1168686Y194481D01*
X1168162Y194266D01*
X1167643Y193019D01*
X1167858Y192496D01*
X1167400Y191397D01*
X1165925Y187857D01*
X1165401Y187642D01*
X1164882Y186395D01*
X1165097Y185872D01*
X1163919Y183043D01*
X1162796Y182295D01*
X1162242Y182405D01*
X1161117Y181655D01*
X1161007Y181101D01*
X1159884Y180353D01*
X1159330Y180463D01*
X1158205Y179714D01*
X1158094Y179159D01*
X1156971Y178411D01*
X1156417Y178521D01*
X1155292Y177771D01*
X1155182Y177217D01*
X1154054Y176465D01*
X1152731Y176201D01*
X1152260Y176514D01*
X1150935Y176250D01*
X1150621Y175778D01*
X1144246Y174503D01*
X1131587Y165136D01*
X1103053Y166438D01*
X1024820Y150791D01*
X1011021Y148959D01*
X1001895Y149264D01*
X1000945D01*
X996336Y149353D01*
X986557Y145709D01*
X976403Y143678D01*
X952526Y148455D01*
X941210Y156000D01*
X890018Y166238D01*
X875578Y163350D01*
X830515Y154337D01*
X822891Y153108D01*
X810002Y145768D01*
X775023Y138772D01*
X750585Y140081D01*
X738765Y141764D01*
X731055Y140111D01*
X720384Y142306D01*
X679128Y156439D01*
X673995Y157807D01*
X657253Y154347D01*
X647267Y156840D01*
X637311Y154848D01*
X625195Y159406D01*
X608509Y156162D01*
X602198Y157544D01*
X564759Y165749D01*
X558480Y167126D01*
X551514Y168480D01*
X536130Y178858D01*
X529161Y189189D01*
X518700Y199650D01*
Y201055D01*
G01X634044Y184570D02*
X612155Y180034D01*
X588199Y187127D01*
Y187126D01*
X588198Y187127D01*
X582398Y191115D01*
X581776Y190999D01*
X580965Y189820D01*
X579301Y189511D01*
X576868Y191183D01*
X576611Y192585D01*
X577162Y193383D01*
X577067Y193900D01*
X575041Y195292D01*
X574449Y195183D01*
X572445Y192264D01*
X571044Y192005D01*
X568456Y193783D01*
X568196Y195182D01*
X570644Y198740D01*
X570528Y199363D01*
X568586Y200699D01*
X567963Y200583D01*
X566678Y198716D01*
X565279Y198457D01*
X560508Y201734D01*
X558074Y201283D01*
X554914Y203454D01*
X554081Y207927D01*
X554082D01*
X554009Y208319D01*
X554020Y208333D01*
X553918Y208866D01*
X553512Y209203D01*
X553427D01*
G01X652282Y184964D02*
X612959Y176853D01*
X585503Y184321D01*
X584790Y185568D01*
X581488Y186466D01*
X579742Y185466D01*
X575839Y186528D01*
X574856Y188243D01*
X572705Y188828D01*
X570772Y187721D01*
X568048Y188462D01*
X566166Y191249D01*
X563833Y191710D01*
X561840Y190367D01*
X560371Y190655D01*
X559679Y191681D01*
X559981Y193231D01*
X561277Y194105D01*
X561562Y195573D01*
X560035Y197839D01*
X559494Y197943D01*
Y197944D01*
X559337Y197974D01*
X559334D01*
X558638Y198109D01*
X554703Y195454D01*
X554008Y195589D01*
X552568Y197720D01*
X552942Y199650D01*
X550129Y203817D01*
X549256Y204689D01*
X546804D01*
X546484Y205009D01*
G01X558744Y213171D02*
X559584D01*
X562587Y210168D01*
X574682Y202014D01*
X576127Y199834D01*
X579994Y197226D01*
X582555Y196705D01*
X592760Y189826D01*
X599176Y188208D01*
X614800Y184937D01*
X657145Y193402D01*
X680930Y184509D01*
X726848Y175325D01*
X752614Y175417D01*
X768696Y165041D01*
X768834Y164966D01*
X778906Y160404D01*
X794478Y163515D01*
X816544Y178226D01*
X875578Y190035D01*
X893480Y193616D01*
X950168Y182279D01*
X979678Y188182D01*
X984827Y187151D01*
X998577Y190122D01*
X1001619Y190016D01*
X1002052Y189551D01*
X1001935Y186225D01*
X1002907Y185186D01*
X1006045Y185074D01*
X1007084Y186046D01*
X1007200Y189372D01*
X1007665Y189805D01*
X1011867Y189658D01*
X1012300Y189195D01*
X1012148Y184876D01*
X1013119Y183836D01*
X1016257Y183724D01*
X1017296Y184696D01*
X1017519Y191012D01*
X1017982Y191445D01*
X1020337Y191362D01*
X1020770Y190898D01*
X1020548Y184581D01*
X1021519Y183540D01*
X1024657Y183428D01*
X1025696Y184400D01*
X1025885Y189734D01*
X1026348Y190167D01*
X1032778Y189940D01*
X1034648Y189138D01*
X1035380Y187304D01*
X1033722Y183436D01*
X1034250Y182114D01*
X1037136Y180877D01*
X1038458Y181405D01*
X1040116Y185273D01*
X1040704Y185509D01*
X1047277Y182692D01*
X1108512Y194940D01*
X1117013Y194690D01*
X1123196Y193076D01*
X1128230Y192738D01*
X1132251Y194230D01*
X1143257Y205237D01*
G01X553146Y210153D02*
X553854D01*
X554788Y209381D01*
X555029Y208115D01*
X555017Y208098D01*
X555777Y204015D01*
X558288Y202289D01*
X560722Y202741D01*
X565493Y199463D01*
X566118Y199579D01*
X567403Y201446D01*
X568800Y201706D01*
X571391Y199924D01*
X571651Y198526D01*
X569203Y194968D01*
X569319Y194344D01*
X571258Y193011D01*
X571884Y193127D01*
X573889Y196046D01*
X575255Y196298D01*
X577931Y194460D01*
X578168Y193167D01*
X577617Y192369D01*
X577732Y191743D01*
X579515Y190517D01*
X580405Y190683D01*
X581215Y191862D01*
X582612Y192122D01*
X588612Y187996D01*
X588614Y187995D01*
X600403Y184505D01*
X600404D01*
X612196Y181013D01*
X655314Y189948D01*
X679726Y181762D01*
X726585Y172390D01*
X752789Y172665D01*
X766946Y162498D01*
X777880Y158028D01*
X796410Y161729D01*
X816893Y175384D01*
X875578Y187123D01*
X893134Y190635D01*
X948158Y179631D01*
X978452Y185689D01*
X979950Y185452D01*
Y185453D01*
X1009829Y178949D01*
X1010362Y179291D01*
X1010594Y180355D01*
X1011790Y181126D01*
X1014858Y180456D01*
X1015628Y179260D01*
X1015396Y178197D01*
X1015740Y177662D01*
X1018043Y177161D01*
X1018576Y177503D01*
X1019124Y180015D01*
X1020320Y180786D01*
X1023388Y180116D01*
X1024158Y178920D01*
X1023610Y176408D01*
X1023954Y175873D01*
X1026320Y175358D01*
X1028340Y175736D01*
X1028698Y176259D01*
X1028433Y177673D01*
X1029239Y178846D01*
X1032323Y179425D01*
X1033497Y178621D01*
X1033750Y177268D01*
X1034276Y176913D01*
X1102084Y190401D01*
X1108005Y189993D01*
X1108483Y190411D01*
X1108530Y191081D01*
X1109600Y192017D01*
X1112733Y191801D01*
X1113669Y190727D01*
X1113623Y190058D01*
X1114040Y189580D01*
X1116391Y189418D01*
X1117904Y190738D01*
X1120433Y190564D01*
X1121785Y189017D01*
X1125239Y188781D01*
X1125772Y189246D01*
X1126671Y189184D01*
X1127136Y188650D01*
X1128696Y188544D01*
X1130400Y189392D01*
X1130731Y189557D01*
X1130956Y190229D01*
X1131763Y190629D01*
X1132434Y190404D01*
X1133610Y190989D01*
X1139295Y197995D01*
X1146940Y206001D01*
X1146948Y206009D01*
X1146956Y206016D01*
X1148399Y207459D01*
G01X541260Y429470D02*
Y409972D01*
G01X540310Y443259D02*
Y409972D01*
G01X594741Y135085D02*
X601002Y133837D01*
X611116Y135760D01*
X618886Y134791D01*
X628083Y130503D01*
X633414Y130186D01*
X643094Y127894D01*
X652239Y129723D01*
X659306Y128861D01*
X723090Y115591D01*
X724830Y115984D01*
X746420Y122890D01*
X772638Y121847D01*
X776609Y122515D01*
X818704Y130543D01*
X820891Y131369D01*
X825278Y133140D01*
X832225Y133646D01*
X875578Y142671D01*
X886085Y144858D01*
X886984Y145073D01*
X932577Y135440D01*
X934780Y135687D01*
X939052Y134567D01*
X977697Y126869D01*
X993940Y128091D01*
X1009138Y127077D01*
X1102114Y145675D01*
X1140740Y137948D01*
X1146496Y137054D01*
X1167245Y142845D01*
X1167764Y143300D01*
X1188508Y161476D01*
X1193767Y190669D01*
X1191597Y199069D01*
X1191399Y200169D01*
G01X543984Y131273D02*
X592866Y121770D01*
X604928Y122403D01*
X614078Y121741D01*
X617090Y121140D01*
X633378Y111774D01*
X659145Y106888D01*
X672065Y109473D01*
X672085Y109474D01*
X672087D01*
X677677Y109646D01*
X696790Y109207D01*
X707264Y107601D01*
X722003Y103781D01*
X728888Y105521D01*
X729719Y105805D01*
X752713Y113560D01*
X771945Y113032D01*
X776855Y113702D01*
X820228Y120674D01*
X824644Y122338D01*
X832619Y122422D01*
X837814Y123148D01*
X886197Y133448D01*
X887050Y133677D01*
X932732Y124540D01*
X940167Y126028D01*
X987167Y116628D01*
X995204Y116705D01*
X1003538Y114718D01*
X1103436Y134699D01*
X1149461Y125494D01*
X1172796Y131032D01*
X1200448Y153454D01*
X1206873Y188442D01*
X1206292Y196982D01*
X1203930Y204172D01*
X1203154Y205223D01*
X1202683Y206922D01*
G01X634264Y197080D02*
X614555Y193177D01*
X598252Y196436D01*
X589785Y202549D01*
X589559Y203954D01*
X592240Y207665D01*
X592141Y208275D01*
X592139Y208291D01*
X590226Y209672D01*
X589601Y209572D01*
X587737Y206990D01*
X586137Y206729D01*
X583927Y208324D01*
X583689Y209800D01*
X586622Y213864D01*
X586623D01*
X586474Y214785D01*
X584733Y216042D01*
X584108Y215941D01*
X580817Y211386D01*
X579215Y211127D01*
X575325Y213936D01*
X575098Y215339D01*
X575635Y216081D01*
X575534Y216706D01*
X573622Y218087D01*
X572996Y217985D01*
X572012Y216623D01*
X570607Y216397D01*
X569564Y217150D01*
X569565D01*
X569450Y217248D01*
X568955Y217743D01*
G01X1136029Y203810D02*
X1130997Y198778D01*
X1127641Y196800D01*
X1125093Y196424D01*
X1122858Y197133D01*
X1116241Y202093D01*
X1109595Y203420D01*
X1107505Y203002D01*
X1100688Y198460D01*
X1098881Y198095D01*
X1097341Y199124D01*
X1094827Y198621D01*
X1093405Y196488D01*
X1090645Y195937D01*
X1089674Y196587D01*
X1086980Y196048D01*
X1086373Y195138D01*
X1081850Y194233D01*
X1080668Y195022D01*
X1079794Y199394D01*
X1079265Y199747D01*
X1076960Y199286D01*
X1076607Y198757D01*
X1077480Y194385D01*
X1076691Y193202D01*
X1076690Y193201D01*
X1070576Y191983D01*
X1069392Y192773D01*
X1068553Y196970D01*
X1068026Y197322D01*
X1065715Y196859D01*
X1065362Y196331D01*
X1066200Y192134D01*
X1065410Y190950D01*
X1062332Y190335D01*
X1061148Y191125D01*
X1060311Y195311D01*
X1060022Y196755D01*
X1059496Y197107D01*
X1057185Y196644D01*
X1056832Y196116D01*
X1057545Y192545D01*
X1057956Y190486D01*
X1057166Y189302D01*
X1054088Y188687D01*
X1053847Y188847D01*
X1052904Y189477D01*
X1051660Y195702D01*
X1051133Y196054D01*
X1048822Y195591D01*
X1048469Y195063D01*
X1049712Y188838D01*
X1048922Y187654D01*
X1047168Y187304D01*
X1046437Y187286D01*
X1043318Y188754D01*
X1038752Y192419D01*
X1038597Y193834D01*
X1039143Y194511D01*
X1039009Y195737D01*
X1037835Y196680D01*
X1036608Y196546D01*
X1036063Y195867D01*
X1033765Y195615D01*
X1031417Y197500D01*
X1029048Y198352D01*
X1011086Y194813D01*
X1007642Y196161D01*
X1004137Y196128D01*
X986634Y190721D01*
X977227Y191685D01*
Y191684D01*
X949622Y186285D01*
X928557Y190497D01*
X928533Y190503D01*
X895806Y197964D01*
X875578Y193919D01*
X815772Y181958D01*
X791976Y166094D01*
X780837Y163866D01*
X771475Y167899D01*
X754306Y179378D01*
X727212Y179171D01*
X682049Y188202D01*
X657893Y197455D01*
X615445Y189039D01*
X596816Y192764D01*
X585398Y200506D01*
X584015Y202606D01*
X575314Y208506D01*
X575237Y208491D01*
X575233Y208490D01*
X575080Y208461D01*
X574846Y208416D01*
X569307Y212171D01*
X568319Y213159D01*
G01X558744Y214121D02*
X559979D01*
X563195Y210905D01*
X575370Y202696D01*
X576815Y200516D01*
X580369Y198120D01*
X582930Y197599D01*
X593153Y190707D01*
X599390Y189134D01*
X614804Y185907D01*
X657224Y194387D01*
X681191Y185426D01*
X726940Y176276D01*
X752893Y176369D01*
X769212Y165839D01*
X769226Y165833D01*
X779020Y161396D01*
X794107Y164410D01*
X816173Y179121D01*
X875578Y191004D01*
X893480Y194585D01*
X950168Y183248D01*
X979678Y189151D01*
X984820Y188122D01*
X998492Y191076D01*
X1002045Y190952D01*
X1003016Y189912D01*
X1002899Y186586D01*
X1003333Y186122D01*
X1005684Y186038D01*
X1006148Y186472D01*
X1006264Y189798D01*
X1007304Y190769D01*
X1012294Y190595D01*
X1013264Y189555D01*
X1013112Y185237D01*
X1013546Y184772D01*
X1015896Y184688D01*
X1016360Y185122D01*
X1016582Y191439D01*
X1017622Y192409D01*
X1020764Y192298D01*
X1021734Y191258D01*
X1021512Y184941D01*
X1021946Y184476D01*
X1024296Y184392D01*
X1024760Y184826D01*
X1024949Y190160D01*
X1025987Y191131D01*
X1032989Y190884D01*
X1035385Y189857D01*
X1036409Y187291D01*
X1034751Y183423D01*
X1034987Y182833D01*
X1037149Y181906D01*
X1037739Y182142D01*
X1039397Y186010D01*
X1040717Y186538D01*
X1047380Y183682D01*
X1098337Y193875D01*
X1098590Y194256D01*
X1099474Y194434D01*
X1099855Y194179D01*
X1108432Y195893D01*
X1117149Y195637D01*
X1118363Y195322D01*
X1118831Y195597D01*
X1119704Y195368D01*
X1119977Y194901D01*
X1120940Y194648D01*
X1121391Y194913D01*
X1122264Y194684D01*
X1122527Y194234D01*
X1123349Y194018D01*
X1128090Y193700D01*
X1131725Y195049D01*
X1141285Y204609D01*
Y204610D01*
X1142584Y205909D01*
G01X569627Y218415D02*
X570095Y217947D01*
X570152Y217898D01*
X570845Y217398D01*
X571472Y217499D01*
X572455Y218861D01*
X573859Y219088D01*
X576409Y217246D01*
X576637Y215845D01*
X576100Y215101D01*
X576201Y214476D01*
X579452Y212128D01*
X580277Y212261D01*
X583568Y216817D01*
X584970Y217043D01*
X587349Y215325D01*
X587624Y213627D01*
X584690Y209563D01*
X584803Y208865D01*
X586374Y207731D01*
X587196Y207865D01*
X589061Y210448D01*
X590464Y210673D01*
X593014Y208831D01*
X593241Y207428D01*
X590560Y203716D01*
X590661Y203089D01*
X598641Y197328D01*
X614556Y194146D01*
X633350Y197867D01*
X659447Y203035D01*
X683694Y192797D01*
X726923Y184260D01*
X726927Y184259D01*
X726930Y184258D01*
X727933Y184060D01*
X756364Y184486D01*
X773250Y171623D01*
X781423Y168039D01*
X789955Y169748D01*
X815570Y186767D01*
X897303Y203125D01*
X897897Y203118D01*
X930994Y195584D01*
X939042Y193975D01*
X939060Y193971D01*
X948705Y191640D01*
X948913Y191638D01*
X953243Y192559D01*
X957742Y195232D01*
X957823Y195299D01*
X957830Y195305D01*
X957840Y195313D01*
X957844Y195316D01*
X957847Y195318D01*
X966811Y205081D01*
X966954Y205208D01*
X969971Y207398D01*
X973357Y207467D01*
X980167Y205795D01*
X985721Y202129D01*
X987086Y200764D01*
X988092Y199500D01*
X993376D01*
X1003297Y201978D01*
X1012700Y200096D01*
X1026996Y202956D01*
X1028672Y204072D01*
X1032339Y204806D01*
X1034487Y204376D01*
X1038891Y201440D01*
X1043122Y200593D01*
X1043305D01*
X1045791Y201091D01*
X1048588Y200532D01*
X1050319Y200878D01*
X1052536Y202356D01*
X1055970Y203042D01*
X1063566Y201524D01*
X1066526Y202116D01*
X1067785Y202852D01*
X1068397Y203558D01*
X1068357Y204122D01*
X1069241Y205144D01*
X1069806Y205184D01*
X1070689Y206204D01*
X1072991Y209906D01*
X1074768Y211049D01*
X1079051Y210029D01*
X1079796Y208819D01*
X1078963Y205322D01*
X1079296Y204781D01*
X1081584Y204235D01*
X1082125Y204568D01*
X1082958Y208065D01*
X1084169Y208810D01*
X1086448Y208266D01*
X1088242Y207069D01*
X1088989Y203335D01*
X1089519Y202983D01*
X1091823Y203445D01*
X1092175Y203975D01*
X1091374Y207982D01*
X1092927Y210310D01*
X1095452Y210816D01*
X1099073Y210092D01*
X1099864Y208909D01*
X1099274Y205970D01*
X1099627Y205442D01*
X1101797Y205008D01*
X1102488Y205468D01*
X1103050Y208271D01*
X1104234Y209060D01*
X1108491Y209911D01*
X1108805Y210383D01*
X1110130Y210648D01*
X1110601Y210334D01*
X1111924Y210598D01*
X1116289Y210113D01*
X1116731Y210467D01*
X1118073Y210317D01*
X1118427Y209875D01*
X1119768Y209726D01*
X1120656Y208616D01*
X1120363Y205991D01*
X1120761Y205495D01*
X1123098Y205233D01*
X1123594Y205631D01*
X1123887Y208256D01*
X1124997Y209144D01*
X1127171Y208900D01*
X1128694D01*
G01X671371Y193310D02*
Y193311D01*
X657977Y198441D01*
X615446Y190008D01*
X597191Y193659D01*
X586088Y201187D01*
X584705Y203287D01*
X575521Y209514D01*
X575053Y209424D01*
X569915Y212907D01*
X569022Y213800D01*
G01X586929Y223900D02*
X618557Y255528D01*
X635581Y340665D01*
X668655Y378460D01*
X676334Y390107D01*
X681622Y394374D01*
X708144Y400893D01*
X713923Y404368D01*
X730327Y411156D01*
X760343Y416515D01*
X774187Y431927D01*
X783948Y434703D01*
X788864Y434046D01*
X794592Y430219D01*
X847100Y419671D01*
X887248Y411606D01*
X897560Y412124D01*
X898031Y411697D01*
X898117Y409993D01*
X899171Y409039D01*
X902710Y409217D01*
X903664Y410271D01*
X903578Y411975D01*
X904005Y412446D01*
X907907Y412641D01*
X938467Y406432D01*
X946865Y402953D01*
X949259Y400559D01*
X954655Y398511D01*
X967305Y398915D01*
X974125Y396365D01*
X982211Y396060D01*
X993757Y399498D01*
X1002862Y398546D01*
X1009847Y399632D01*
X1012616Y401173D01*
X1013007Y402542D01*
X1012380Y403667D01*
X1012553Y404276D01*
X1014962Y405617D01*
X1015571Y405443D01*
X1016198Y404320D01*
X1017565Y403928D01*
X1020852Y405759D01*
X1023045Y406981D01*
X1097297Y414511D01*
X1108236Y412325D01*
X1108590Y411794D01*
X1109570Y411598D01*
X1110100Y411952D01*
X1115422Y410889D01*
X1118177Y411434D01*
X1123116Y410447D01*
X1123477Y409905D01*
X1124579Y409685D01*
X1125120Y410046D01*
X1146163Y405841D01*
X1150159Y405042D01*
X1174364Y409882D01*
X1174941Y409498D01*
X1175824Y409674D01*
X1176209Y410252D01*
X1180557Y411121D01*
X1181133Y410736D01*
X1182017Y410913D01*
X1182401Y411490D01*
X1189284Y412866D01*
X1197664Y410726D01*
X1198831Y410012D01*
X1198832D01*
X1209945Y397353D01*
X1210632Y395104D01*
X1213133Y371449D01*
X1212688Y370899D01*
X1212783Y370003D01*
X1213333Y369558D01*
X1213371Y369200D01*
X1214396Y359519D01*
X1214708Y349708D01*
X1214866Y344750D01*
X1211837Y338187D01*
X1211400Y337715D01*
X1209376Y335531D01*
X1208359Y333360D01*
X1207610Y327860D01*
X1207366Y326072D01*
X1205770Y322500D01*
X1203460Y317332D01*
Y315668D01*
G01X574606Y264625D02*
X581931D01*
X590545Y273239D01*
X609165Y366352D01*
X624078Y383393D01*
X625260Y389158D01*
X625851Y389548D01*
X626032Y390430D01*
X625643Y391021D01*
X625823Y391902D01*
X626415Y392292D01*
X626418Y392307D01*
X626546Y392934D01*
X626595Y393174D01*
X626546Y393248D01*
X626418Y393442D01*
X626206Y393764D01*
X626386Y394645D01*
X626418Y394666D01*
X626546Y394751D01*
X626977Y395035D01*
X627158Y395917D01*
X626769Y396507D01*
X626949Y397388D01*
X627540Y397778D01*
X627721Y398660D01*
X627331Y399251D01*
X627762Y401355D01*
X634285Y409411D01*
X664157Y431118D01*
X670961Y439225D01*
X683155Y446252D01*
X689352Y448119D01*
X706967Y449224D01*
X730129Y450676D01*
X737145Y455898D01*
X765822Y465541D01*
X779856Y466154D01*
X801055Y463352D01*
X817824Y464445D01*
X847100Y458566D01*
X890239Y449904D01*
X980412Y454425D01*
X1035032Y447960D01*
X1114865Y456065D01*
X1126111Y453817D01*
X1146163Y457827D01*
X1148887Y458372D01*
X1200651Y448024D01*
X1217062Y442137D01*
X1230949Y434703D01*
X1271638Y396371D01*
X1272167Y379831D01*
X1270865Y376588D01*
X1259233Y347620D01*
X1258581Y322500D01*
X1258402Y315626D01*
X1239456Y281631D01*
X1229398Y277957D01*
X1228756Y278255D01*
X1227910Y277946D01*
X1227612Y277304D01*
X1226767Y276996D01*
X1226126Y277295D01*
X1225280Y276986D01*
X1224982Y276344D01*
X1223887Y275944D01*
X1223245Y276242D01*
X1222399Y275933D01*
X1222101Y275291D01*
X1219511Y274345D01*
X1215230Y273630D01*
X1212510Y270910D01*
Y268903D01*
X1210979Y267372D01*
X1209657D01*
G01X601049Y345981D02*
X587280Y277105D01*
X579950Y269775D01*
X575056D01*
G01X1223676Y265805D02*
X1223680Y265807D01*
X1226248Y267186D01*
X1229091Y268454D01*
X1231681Y269400D01*
X1245565Y274470D01*
X1267166Y313227D01*
X1267194Y314300D01*
X1267407Y322500D01*
X1268012Y345819D01*
X1269089Y348511D01*
X1281037Y378384D01*
X1280338Y400298D01*
X1249151Y429685D01*
X1247376Y430569D01*
X1237424Y439945D01*
X1216031Y451392D01*
X1149417Y464710D01*
X1146163Y464059D01*
X1130400Y460906D01*
X1130353Y460897D01*
X1115760Y463816D01*
X1035615Y455680D01*
X980980Y462083D01*
X890805Y457563D01*
X847100Y466339D01*
X818331Y472116D01*
X793369Y470486D01*
X780053Y472232D01*
X761891Y471448D01*
X760700Y471047D01*
X721196Y457762D01*
X687883Y455673D01*
X680146Y453336D01*
X665988Y445154D01*
X665500Y444572D01*
X659436Y437346D01*
X630180Y416087D01*
X629465Y415567D01*
X628189Y413992D01*
X626546Y411963D01*
X626418Y411805D01*
X626156Y411481D01*
X618894Y405933D01*
X618511Y404062D01*
X618900Y403472D01*
X618720Y402590D01*
X618128Y402200D01*
X617948Y401319D01*
X618338Y400729D01*
X618157Y399847D01*
X617566Y399457D01*
X617363Y398467D01*
X617752Y397877D01*
X617572Y396994D01*
X616980Y396605D01*
X616800Y395724D01*
X617190Y395134D01*
X617009Y394251D01*
X616671Y394029D01*
X616417Y393862D01*
X616237Y392981D01*
X616626Y392391D01*
X616445Y391508D01*
X615854Y391119D01*
X615634Y390043D01*
X616023Y389453D01*
X615842Y388570D01*
X615251Y388181D01*
X614366Y383867D01*
X603999Y372020D01*
X601499Y359521D01*
X585296Y278495D01*
X580126Y273325D01*
X575776D01*
G01X594800Y366894D02*
X596724Y357274D01*
X581758Y282459D01*
X578074Y278775D01*
X574776D01*
G01X574800Y282325D02*
X576769D01*
X580353Y285908D01*
X590280Y335543D01*
X594091Y354595D01*
X592393Y363090D01*
X592786Y363678D01*
X592609Y364562D01*
X592020Y364954D01*
X591844Y365836D01*
X592237Y366424D01*
X592060Y367308D01*
X591471Y367700D01*
X591295Y368582D01*
X591688Y369170D01*
X591511Y370054D01*
X590922Y370446D01*
X590746Y371328D01*
X591138Y371916D01*
X590961Y372800D01*
X590372Y373192D01*
X590196Y374074D01*
X590588Y374662D01*
X590411Y375546D01*
X589822Y375938D01*
X589646Y376820D01*
X590038Y377408D01*
X589862Y378292D01*
X589272Y378684D01*
X589080Y379647D01*
X589472Y380235D01*
X589296Y381119D01*
X588707Y381511D01*
X587342Y388334D01*
X588149Y392364D01*
Y392365D01*
X588955Y396394D01*
X613672Y426379D01*
X623769Y432176D01*
X641145Y434002D01*
X655350Y444329D01*
X661014Y451082D01*
X677761Y460751D01*
X685796Y463176D01*
X719722Y465304D01*
X760484Y479014D01*
X780803Y479881D01*
X793760Y478143D01*
X818860Y479781D01*
X891387Y465221D01*
X981242Y469726D01*
X1035679Y463345D01*
X1118118Y471720D01*
X1134819Y468380D01*
X1135722Y468199D01*
X1146163Y470287D01*
X1151267Y471308D01*
X1177225Y466115D01*
X1180174Y466695D01*
X1217843Y459161D01*
X1242566Y445929D01*
X1251371Y437632D01*
X1254105Y436889D01*
X1289045Y403964D01*
X1289911Y376823D01*
X1285093Y364775D01*
X1276810Y344066D01*
X1276250Y322500D01*
X1276009Y313197D01*
X1275946Y310767D01*
X1252153Y268081D01*
X1232242Y254988D01*
X1226299Y252531D01*
X1223200D01*
G01X586109Y367405D02*
X589226Y351819D01*
X576994Y290639D01*
X575492Y289137D01*
G01X584181Y360208D02*
X584192Y360152D01*
X586495Y348631D01*
X576481Y298543D01*
X573037Y290286D01*
Y290184D01*
X571841Y288989D01*
G01X584720Y227459D02*
X614872Y257612D01*
X632040Y343464D01*
X662345Y378097D01*
X671832Y392492D01*
X677187Y397620D01*
X679034Y398635D01*
X706325Y405349D01*
X712916Y409311D01*
X717141Y411032D01*
X717221Y411074D01*
X720040Y412916D01*
X728284Y415663D01*
X733961Y415865D01*
X753169Y419286D01*
X755254Y419649D01*
X758575Y420690D01*
X771728Y437169D01*
X771781Y437231D01*
X773260Y438789D01*
X775462Y439789D01*
X778132Y439905D01*
X791304Y438140D01*
X796437Y434712D01*
X887676Y416395D01*
X908956Y417462D01*
X949199Y409451D01*
X958200Y405971D01*
X958514Y405850D01*
X993703Y404542D01*
X1013934Y410566D01*
X1023166Y412388D01*
X1056097Y415707D01*
X1056100D01*
X1098672Y419998D01*
X1102593Y419299D01*
X1102733Y419270D01*
X1102736Y419269D01*
X1102743Y419268D01*
X1102753Y419266D01*
X1102759Y419265D01*
Y419264D01*
X1104802Y420609D01*
X1107002Y420155D01*
X1108049Y418563D01*
X1108635Y418441D01*
X1111009Y418017D01*
X1111728Y418518D01*
X1111734Y418557D01*
X1111938Y419673D01*
X1113287Y420606D01*
X1116472Y420036D01*
X1117404Y418684D01*
X1117280Y418008D01*
Y418007D01*
X1117195Y417541D01*
X1117559Y417019D01*
X1118587Y416835D01*
X1118588D01*
X1121067Y416393D01*
X1123161Y414487D01*
X1146163Y409888D01*
X1150009Y409119D01*
X1190632Y417248D01*
X1197734Y415356D01*
X1204083Y411446D01*
X1214279Y399997D01*
X1215239Y396926D01*
X1217900Y371882D01*
X1220868Y367748D01*
X1220215Y342570D01*
X1212506Y313867D01*
X1211400Y312315D01*
X1210853Y311547D01*
X1208948Y309642D01*
G01X584278Y230285D02*
X612986Y258993D01*
X630166Y344865D01*
X657648Y376274D01*
X669601Y394399D01*
X675290Y399847D01*
X677989Y401334D01*
X702409Y407338D01*
X711662Y412901D01*
X714127Y413819D01*
X714241Y413872D01*
X719900Y416883D01*
X727298Y417954D01*
X734464Y418400D01*
X735935D01*
X752769Y421416D01*
X757800Y423300D01*
X769576Y437986D01*
X770548Y439010D01*
X770555Y439017D01*
X772461Y441025D01*
X774092Y441788D01*
X778292Y441970D01*
X793833Y439890D01*
X797547Y437409D01*
X887894Y419269D01*
X906378Y420194D01*
Y420195D01*
X916164Y420685D01*
X916678Y420220D01*
X917578Y420265D01*
X918043Y420780D01*
X924865Y421122D01*
X935927Y416850D01*
X936208Y416216D01*
X937048Y415892D01*
X937682Y416172D01*
X938521Y415848D01*
X938802Y415214D01*
X939642Y414889D01*
X940276Y415170D01*
X959000Y407939D01*
X991071Y406749D01*
X1021518Y415815D01*
X1093043Y423019D01*
X1093044D01*
X1099540Y423673D01*
X1099541D01*
X1100221Y423742D01*
X1100758Y423303D01*
X1101115Y423339D01*
X1101116D01*
X1101655Y423394D01*
X1102093Y423931D01*
X1102988Y424021D01*
X1103525Y423582D01*
X1104422Y423673D01*
X1104860Y424210D01*
X1105755Y424300D01*
X1106291Y423861D01*
X1107188Y423952D01*
X1107626Y424489D01*
X1108700Y424597D01*
X1111090Y424151D01*
X1111482Y423579D01*
X1112368Y423413D01*
X1112939Y423805D01*
X1113457Y423708D01*
X1118261Y422812D01*
X1125530Y416487D01*
X1137836Y413739D01*
X1146163Y412075D01*
X1150174Y411273D01*
X1191141Y419469D01*
X1197690Y417842D01*
X1207406Y412020D01*
X1217299Y401066D01*
X1218460Y397486D01*
X1220767Y373820D01*
X1224084Y369200D01*
X1224474Y368657D01*
X1224391Y365477D01*
G01X577832Y233729D02*
X578731Y232830D01*
X581211D01*
X609318Y260938D01*
X626418Y346414D01*
X626573Y347189D01*
X651716Y375922D01*
X665903Y397450D01*
X672655Y403917D01*
X676215Y405878D01*
X693208Y410058D01*
X694517Y411260D01*
Y411261D01*
X706195Y421997D01*
X707720Y422607D01*
X713909Y423838D01*
X719100Y423900D01*
X733367Y423607D01*
X737617D01*
X747460Y424490D01*
X750394Y425407D01*
X755946Y427743D01*
X766436Y440434D01*
X770081Y444274D01*
X772554Y445683D01*
X778465Y445939D01*
X797060Y443458D01*
X799407Y441890D01*
X888251Y424053D01*
X925630Y425929D01*
X962051Y411858D01*
X988245Y410874D01*
X1020730Y420546D01*
X1109417Y429478D01*
X1120743Y427163D01*
X1128846Y419931D01*
X1150144Y415320D01*
X1192227Y423735D01*
X1198829Y421901D01*
X1211400Y414225D01*
X1212480Y413565D01*
X1217245Y408403D01*
Y408402D01*
X1222080Y403163D01*
X1223739Y396884D01*
X1226128Y375545D01*
X1229858Y370351D01*
X1229712Y364712D01*
X1229665Y362938D01*
X1229071Y340046D01*
G01X568400Y237300D02*
X576150D01*
X576825Y237975D01*
X580705D01*
X606837Y264107D01*
X624036Y350076D01*
X648415Y377935D01*
X662798Y399750D01*
X671492Y408077D01*
X682414Y413552D01*
X696704Y418446D01*
X706222Y427193D01*
X726093Y428441D01*
X745989Y427400D01*
X750918Y429136D01*
X757131Y435005D01*
X768693Y447185D01*
X771624Y448655D01*
X778765Y448961D01*
X799915Y446130D01*
X800896Y445478D01*
X888528Y427882D01*
X926248Y429773D01*
X964917Y414826D01*
X985605Y414057D01*
X1020152Y424347D01*
X1109678Y433430D01*
X1122569Y430852D01*
X1132553Y422317D01*
X1146163Y419596D01*
X1150907Y418648D01*
X1193572Y427184D01*
X1200349Y425315D01*
X1215003Y416606D01*
X1225664Y405551D01*
X1227410Y398710D01*
X1229250Y388350D01*
X1229330Y387900D01*
X1230603Y376874D01*
X1234332Y371680D01*
X1234270Y369270D01*
X1234268Y369200D01*
X1234189Y366187D01*
X1233876Y354126D01*
X1233372Y334727D01*
X1230520Y322500D01*
X1228722Y314789D01*
X1228449Y314300D01*
X1223321Y305098D01*
X1214362Y298821D01*
X1213467Y298819D01*
X1212528D01*
G01X574900Y241956D02*
X580126D01*
X603660Y265491D01*
X621055Y352454D01*
X645377Y380248D01*
X659853Y402206D01*
X672278Y414107D01*
X694705Y421785D01*
X704633Y430912D01*
X734087Y432758D01*
X739463Y435920D01*
X746974Y436585D01*
X750494Y435967D01*
X755494Y438142D01*
X765862Y450480D01*
X770173Y451597D01*
X778963Y451985D01*
X805636Y448412D01*
X888809Y431711D01*
X926865Y433619D01*
X967944Y417734D01*
X982724Y417183D01*
X1019378Y428097D01*
X1110712Y437366D01*
X1124209Y434669D01*
X1135962Y424723D01*
X1146163Y422685D01*
X1150202Y421878D01*
X1194630Y430764D01*
X1194678Y430774D01*
X1201725Y428858D01*
Y428859D01*
X1201849Y428825D01*
X1217428Y419628D01*
X1229397Y407274D01*
X1230883Y401082D01*
X1233230Y388354D01*
X1234341Y379230D01*
X1238473Y373473D01*
X1238799Y373019D01*
X1238475Y360530D01*
G01X561294Y245800D02*
X579886D01*
X579887Y245799D01*
X580673D01*
X601743Y266869D01*
X619330Y354825D01*
X642545Y381354D01*
X644460Y388968D01*
X645055Y389323D01*
X645299Y390294D01*
X644944Y390889D01*
X645187Y391858D01*
X652086Y399951D01*
X661441Y409645D01*
X670645Y416569D01*
X693206Y424289D01*
X703441Y433701D01*
X733950Y435614D01*
X744067Y441249D01*
X748550Y446853D01*
X768572Y453587D01*
X779211Y454052D01*
X815994Y449117D01*
X816861Y449094D01*
X889107Y434589D01*
X927328Y436505D01*
X969895Y420065D01*
X981013Y419651D01*
X1018864Y430923D01*
X1112850Y440544D01*
X1124446Y438224D01*
X1139159Y426426D01*
X1150437Y424091D01*
X1196267Y433556D01*
X1202596Y431792D01*
X1219323Y421892D01*
X1232286Y408624D01*
X1235897Y391007D01*
X1237279Y381069D01*
X1242270Y374119D01*
X1241099Y329033D01*
X1240821Y327690D01*
X1240241Y327309D01*
X1240039Y326329D01*
X1240419Y325750D01*
X1240217Y324771D01*
X1239637Y324390D01*
X1239435Y323410D01*
X1239815Y322831D01*
X1239613Y321852D01*
X1239032Y321471D01*
X1238830Y320491D01*
X1239210Y319912D01*
X1239008Y318933D01*
X1238428Y318553D01*
X1238225Y317573D01*
X1238606Y316993D01*
X1238354Y315779D01*
X1227435Y296194D01*
X1216096Y292050D01*
X1213013D01*
X1211164Y290240D01*
G01X568990Y250793D02*
X581389D01*
X598973Y268376D01*
X616671Y356967D01*
X616828Y357753D01*
X638319Y382312D01*
X639029Y385136D01*
X640730Y391893D01*
X641325Y392249D01*
X641569Y393220D01*
X641214Y393814D01*
X641806Y396169D01*
X643961Y398393D01*
X644654Y398404D01*
X645350Y399123D01*
X645339Y399816D01*
X646034Y400534D01*
X646728Y400545D01*
X647424Y401264D01*
X647413Y401957D01*
X648108Y402675D01*
X648802Y402686D01*
X649498Y403405D01*
X649487Y404098D01*
X650182Y404816D01*
X650876Y404827D01*
X651572Y405546D01*
X651561Y406239D01*
X654214Y408976D01*
X668835Y419976D01*
X691215Y427634D01*
X701856Y437418D01*
Y437419D01*
X732574Y439371D01*
X742525Y444914D01*
X745942Y449197D01*
X767847Y456564D01*
X779438Y457067D01*
X812475Y452642D01*
X817056Y452942D01*
X889389Y438418D01*
X927954Y440351D01*
X972120Y423283D01*
X978908Y423029D01*
X1018340Y434776D01*
X1113253Y444409D01*
X1126220Y441817D01*
X1143216Y428915D01*
X1146163Y428243D01*
X1150171Y427329D01*
X1195368Y437540D01*
X1205936Y434230D01*
X1205937D01*
X1221665Y425266D01*
X1236066Y410290D01*
X1239906Y390486D01*
X1240980Y383477D01*
X1244113Y379113D01*
X1246669Y375554D01*
X1246438Y366646D01*
G01X567251Y255850D02*
X580771D01*
X595319Y270399D01*
X613474Y361148D01*
X632989Y383449D01*
X636673Y400776D01*
X637221Y402342D01*
X639002Y404538D01*
X668618Y426057D01*
X674953Y433603D01*
X686015Y439991D01*
X691081Y441522D01*
X729669Y443965D01*
X739413Y451224D01*
X767072Y460525D01*
X779721Y461046D01*
X808676Y457165D01*
X817378Y457734D01*
X889743Y443203D01*
X928724Y445157D01*
X974739Y427376D01*
X976478Y427311D01*
X1017233Y439449D01*
X1113640Y449235D01*
X1123060Y447353D01*
X1146163Y452058D01*
X1150295Y452899D01*
X1190989Y444498D01*
X1207876Y438472D01*
X1224905Y429570D01*
X1263843Y392898D01*
X1264214Y381266D01*
X1252750Y352602D01*
X1251400Y349226D01*
X1250584Y317793D01*
X1234144Y288297D01*
X1227821Y285861D01*
Y285860D01*
X1221789Y283536D01*
G01X634137Y404629D02*
X632591Y402719D01*
X628678Y384307D01*
X610838Y363921D01*
X592436Y271876D01*
X581550Y260989D01*
X576411D01*
X575600Y261800D01*
G01X586300Y224616D02*
X617681Y255997D01*
X634699Y341100D01*
X667897Y379037D01*
X675622Y390754D01*
X681189Y395247D01*
X707777Y401782D01*
X713494Y405219D01*
X730059Y412074D01*
X759854Y417394D01*
X773663Y432766D01*
X783878Y435671D01*
X789209Y434959D01*
X794964Y431114D01*
X847100Y420641D01*
X887319Y412561D01*
X897906Y413093D01*
X898961Y412138D01*
X899046Y410434D01*
X899517Y410008D01*
X902269Y410147D01*
X902694Y410617D01*
X902609Y412321D01*
X903565Y413376D01*
X907979Y413596D01*
X938746Y407345D01*
X947404Y403759D01*
X949787Y401375D01*
X954815Y399467D01*
X967462Y399871D01*
X974314Y397309D01*
X982090Y397016D01*
X993667Y400463D01*
X1002835Y399504D01*
X1009533Y400545D01*
X1011810Y401813D01*
X1011985Y402424D01*
X1011358Y403548D01*
X1011747Y404915D01*
X1013263Y405759D01*
X1014843Y406639D01*
X1016210Y406250D01*
X1016484Y405759D01*
X1016837Y405126D01*
X1017447Y404951D01*
X1018898Y405759D01*
X1022754Y407907D01*
X1097343Y415471D01*
X1115423Y411858D01*
X1118178Y412403D01*
X1146163Y406810D01*
X1150159Y406011D01*
X1189310Y413841D01*
X1198039Y411612D01*
X1199451Y410747D01*
X1210794Y397826D01*
X1211400Y395844D01*
X1211568Y395294D01*
X1215345Y359585D01*
X1215630Y350630D01*
X1215823Y344556D01*
X1212637Y337651D01*
X1210174Y334993D01*
X1209281Y333088D01*
X1208720Y328970D01*
X1208290Y325810D01*
X1206811Y322500D01*
X1204410Y317129D01*
Y315668D01*
G01X576115Y265575D02*
X574606D01*
G01X576115D02*
X581537D01*
X589669Y273708D01*
X608283Y366787D01*
X623197Y383830D01*
X626877Y401773D01*
X633625Y410106D01*
X663504Y431818D01*
X670233Y439836D01*
X670232D01*
X670341Y439965D01*
X682775Y447131D01*
X689183Y449061D01*
X706967Y450176D01*
X729788Y451607D01*
X736699Y456751D01*
X737004Y456854D01*
X765646Y466485D01*
X779898Y467107D01*
X801087Y464307D01*
X817888Y465402D01*
X847100Y459536D01*
X890310Y450859D01*
X980444Y455378D01*
X1035040Y448916D01*
X1114911Y457025D01*
X1126111Y454786D01*
X1146163Y458796D01*
X1148887Y459341D01*
X1200906Y448942D01*
X1217449Y443008D01*
X1231509Y435481D01*
X1272576Y396794D01*
X1273123Y379662D01*
X1266582Y363372D01*
X1266583D01*
X1263043Y354557D01*
X1260179Y347424D01*
X1259531Y322500D01*
X1259346Y315368D01*
X1258751Y314300D01*
X1240114Y280859D01*
X1219754Y273422D01*
X1215687Y272743D01*
X1213460Y270516D01*
Y268509D01*
X1211373Y266422D01*
X1209657D01*
G01X575056Y268825D02*
X580344D01*
X588156Y276636D01*
X601980Y345794D01*
X606678Y369295D01*
X619150Y383550D01*
X619660Y386038D01*
X620251Y386427D01*
X620432Y387310D01*
X620042Y387900D01*
X620222Y388781D01*
X620813Y389171D01*
X620994Y390053D01*
X620605Y390643D01*
X620785Y391524D01*
X621376Y391914D01*
X621557Y392796D01*
X621168Y393386D01*
X621348Y394267D01*
X621939Y394657D01*
X622120Y395539D01*
X621730Y396130D01*
X621913Y397027D01*
X622505Y397416D01*
X622685Y398299D01*
X622296Y398889D01*
X623320Y403891D01*
X628265Y408031D01*
X629230Y409221D01*
X629231Y409223D01*
X632007Y412652D01*
X661929Y434390D01*
X668470Y442188D01*
X681650Y449798D01*
X688579Y451890D01*
X730226Y454501D01*
X731174Y455206D01*
X735843Y458680D01*
X765117Y468524D01*
X780157Y469181D01*
Y469182D01*
X797073Y466909D01*
X818075Y468281D01*
X847100Y462455D01*
X890548Y453735D01*
X980858Y458263D01*
X1035040Y451790D01*
X1115182Y459929D01*
X1128053Y457355D01*
X1146163Y460969D01*
X1148981Y461531D01*
X1206590Y450016D01*
X1218355Y445796D01*
X1235152Y436809D01*
X1275988Y398336D01*
X1276600Y379163D01*
X1263623Y346721D01*
X1262993Y322500D01*
X1262787Y314559D01*
X1242421Y278019D01*
X1225018Y271663D01*
X1222379Y269023D01*
X1222001Y268645D01*
G01X600568Y359708D02*
X584420Y278964D01*
X579732Y274275D01*
X575776D01*
G01X1221990Y256931D02*
X1225188D01*
X1230000Y258791D01*
X1231919Y260053D01*
X1232062Y260746D01*
X1232815Y261241D01*
X1233508Y261098D01*
X1234260Y261592D01*
X1234403Y262285D01*
X1235156Y262780D01*
X1235848Y262637D01*
X1236600Y263131D01*
X1236743Y263824D01*
X1237496Y264319D01*
X1238188Y264176D01*
X1248746Y271117D01*
X1270865Y310802D01*
X1271548Y312027D01*
X1271820Y322500D01*
X1272407Y345122D01*
X1284900Y376349D01*
X1285469Y377771D01*
X1284900Y395591D01*
X1284687Y402262D01*
X1252245Y432830D01*
X1248559Y434700D01*
X1239617Y443125D01*
X1216521Y455485D01*
X1181719Y462445D01*
X1178913Y461892D01*
X1149330Y467807D01*
X1146163Y467174D01*
X1132420Y464427D01*
X1116128Y467685D01*
X1035650Y459512D01*
X981110Y465904D01*
X891087Y461393D01*
X847100Y470225D01*
X818587Y475950D01*
X793615Y474321D01*
X780514Y476073D01*
X761184Y475230D01*
X760700Y475067D01*
X720466Y461534D01*
X686821Y459423D01*
X678979Y457056D01*
X663498Y448115D01*
X657142Y440540D01*
X642163Y429652D01*
X623894Y427734D01*
X616177Y423420D01*
X605011Y409874D01*
X605078Y409170D01*
X604506Y408475D01*
X603801Y408407D01*
X603229Y407713D01*
X603296Y407009D01*
X602724Y406314D01*
X602019Y406246D01*
X601447Y405552D01*
X601514Y404848D01*
X600942Y404152D01*
X600237Y404085D01*
X599474Y403159D01*
X599541Y402455D01*
X598969Y401760D01*
X598264Y401692D01*
X595454Y398284D01*
X595455D01*
X592644Y394875D01*
X591409Y388696D01*
X595499Y368244D01*
X595731Y367080D01*
X597693Y357274D01*
X582634Y281990D01*
X578468Y277825D01*
X574884D01*
G01X589349Y335730D02*
X579477Y286377D01*
X576375Y283275D01*
X574800D01*
G01X576165Y288465D02*
X576916Y289216D01*
X576915D01*
X577870Y290170D01*
X590195Y351819D01*
X587041Y367591D01*
X586992Y367841D01*
X587385Y368429D01*
X587208Y369313D01*
X586619Y369705D01*
X586443Y370587D01*
X586836Y371175D01*
X586659Y372059D01*
X586070Y372451D01*
X585894Y373333D01*
X586286Y373921D01*
X586109Y374805D01*
X585520Y375197D01*
X585344Y376079D01*
X585736Y376668D01*
X585560Y377551D01*
X584971Y377944D01*
X584794Y378829D01*
Y378830D01*
X582994Y387830D01*
X584883Y397273D01*
X585656Y398668D01*
X610598Y428924D01*
X619238Y434571D01*
X625410Y436865D01*
X626053Y436571D01*
X626418Y436706D01*
X626546Y436754D01*
X626898Y436885D01*
X627192Y437529D01*
X628789Y438122D01*
X629432Y437828D01*
X630277Y438141D01*
X630571Y438785D01*
X633313Y439804D01*
X635567Y440105D01*
X636129Y439675D01*
X637022Y439794D01*
X637451Y440357D01*
X638888Y440548D01*
X639450Y440119D01*
X640343Y440238D01*
X640772Y440801D01*
X644654Y441319D01*
X650056Y445607D01*
X652653Y448702D01*
X653359Y448763D01*
X653937Y449453D01*
X653876Y450158D01*
X655002Y451500D01*
X655831Y452487D01*
X676291Y464299D01*
X685069Y466949D01*
X718986Y469076D01*
X759781Y482796D01*
X780870Y483715D01*
X793877Y481976D01*
X819518Y483636D01*
X892055Y469069D01*
X981373Y473547D01*
X1035709Y467178D01*
X1118685Y475606D01*
X1138052Y471733D01*
X1146163Y473358D01*
X1151416Y474410D01*
X1176448Y469400D01*
X1181378Y470386D01*
X1219203Y462822D01*
X1244894Y449075D01*
X1252750Y441673D01*
X1252926Y441507D01*
X1256304Y440642D01*
X1293402Y405697D01*
X1294348Y376037D01*
X1288486Y361382D01*
X1287775Y359605D01*
X1287772Y359598D01*
X1287768Y359588D01*
X1287765Y359580D01*
X1287759Y359562D01*
X1281188Y343137D01*
X1280651Y322500D01*
X1280316Y309638D01*
X1280048Y309158D01*
X1255404Y264939D01*
X1233856Y250770D01*
X1227508Y248135D01*
X1224995D01*
G01X1224340Y242787D02*
X1228608D01*
X1236333Y245983D01*
X1259341Y261110D01*
X1263961Y269400D01*
X1283946Y305260D01*
X1285639Y308299D01*
X1285795Y314300D01*
X1286515Y342000D01*
X1286516Y342022D01*
X1292610Y357258D01*
X1293060Y358384D01*
Y358386D01*
X1297385Y369200D01*
X1299742Y375092D01*
X1298699Y407830D01*
X1254778Y449205D01*
X1220684Y467452D01*
X1177772Y476037D01*
X1173039Y475089D01*
X1153796Y478940D01*
X1146163Y477414D01*
X1140378Y476257D01*
X1119354Y480462D01*
X1035715Y471965D01*
X981878Y478340D01*
X892441Y473856D01*
X856248Y481119D01*
Y481121D01*
X819818Y488430D01*
X794051Y486755D01*
X781092Y488488D01*
X758897Y487522D01*
X718063Y473788D01*
X684162Y471661D01*
X674435Y468724D01*
X651430Y455442D01*
X645355Y448201D01*
X644477Y447391D01*
X644476D01*
X643602Y446583D01*
X643156Y446287D01*
X642470Y445831D01*
X631526Y444366D01*
X616900Y438790D01*
X616671Y438703D01*
X616397Y438598D01*
X607031Y432253D01*
X581999Y401887D01*
X579596Y397553D01*
X577668Y387912D01*
X585526Y348631D01*
X575567Y298822D01*
X572160Y290652D01*
X571170Y289662D01*
G01X599199Y240594D02*
X585392Y226787D01*
G01X599199Y240594D02*
X615748Y257143D01*
X632922Y343029D01*
X663103Y377520D01*
X672567Y391879D01*
X677755Y396847D01*
X679382Y397742D01*
X706692Y404460D01*
X713343Y408458D01*
X717543Y410169D01*
X717704Y410254D01*
X720457Y412053D01*
X728454Y414718D01*
X734059Y414917D01*
X755537Y418742D01*
X759137Y419869D01*
X772471Y436577D01*
X773822Y438000D01*
X775687Y438847D01*
X778089Y438952D01*
X790959Y437227D01*
X796065Y433817D01*
X887605Y415440D01*
X908886Y416507D01*
X948933Y408535D01*
X956114Y405759D01*
X958200Y404952D01*
X958320Y404906D01*
X993824Y403586D01*
X1014162Y409642D01*
X1023306Y411447D01*
X1098636Y419039D01*
X1102416Y418365D01*
X1102535Y418340D01*
X1102551Y418336D01*
X1102557Y418335D01*
X1102951Y418252D01*
X1104996Y419599D01*
X1106424Y419304D01*
X1107470Y417712D01*
X1108082Y417585D01*
X1108089Y417574D01*
X1111230Y417012D01*
X1112593Y417963D01*
X1112802Y419115D01*
X1113505Y419601D01*
X1115914Y419170D01*
X1116398Y418468D01*
X1116189Y417323D01*
X1117004Y416153D01*
X1120629Y415506D01*
X1120630Y415505D01*
X1122716Y413607D01*
X1146163Y408919D01*
X1150009Y408150D01*
X1190601Y416272D01*
X1197354Y414473D01*
X1203466Y410710D01*
X1213433Y399518D01*
X1214304Y396732D01*
X1216981Y371532D01*
X1219910Y367453D01*
X1219767Y361939D01*
X1219264Y361462D01*
X1219241Y360561D01*
X1219718Y360059D01*
X1219693Y359060D01*
X1219189Y358583D01*
X1219163Y357582D01*
X1219640Y357080D01*
X1219268Y342708D01*
X1216905Y333914D01*
X1216314Y333573D01*
X1216078Y332702D01*
X1216421Y332111D01*
X1216187Y331244D01*
X1216186Y331240D01*
X1215594Y330900D01*
X1215358Y330028D01*
X1215701Y329437D01*
X1215466Y328566D01*
X1214874Y328226D01*
X1214638Y327354D01*
X1214981Y326763D01*
X1214747Y325896D01*
X1214746Y325892D01*
X1214154Y325552D01*
X1213918Y324680D01*
X1214261Y324089D01*
X1214027Y323222D01*
X1214026Y323218D01*
X1213434Y322878D01*
X1213198Y322006D01*
X1213541Y321415D01*
X1211632Y314279D01*
X1211400Y313953D01*
X1210125Y312163D01*
X1208276Y310314D01*
G01X583606Y230957D02*
X612110Y259462D01*
X629284Y345300D01*
X656890Y376851D01*
X668866Y395012D01*
X674722Y400620D01*
X677640Y402227D01*
X702042Y408227D01*
X711247Y413761D01*
X713795Y414711D01*
X719600Y417800D01*
X727200Y418900D01*
X734352Y419345D01*
X734464Y419350D01*
X735850D01*
X752516Y422337D01*
X757222Y424098D01*
X768859Y438612D01*
X769858Y439665D01*
X769865Y439672D01*
X771895Y441810D01*
X773861Y442729D01*
X778335Y442923D01*
X794178Y440803D01*
X797919Y438304D01*
X887965Y420224D01*
X925019Y422081D01*
X959194Y408883D01*
X990950Y407705D01*
X1021333Y416752D01*
X1108740Y425556D01*
X1118690Y423699D01*
X1125972Y417362D01*
X1138033Y414669D01*
X1146163Y413044D01*
X1150174Y412242D01*
X1191163Y420443D01*
X1198057Y418730D01*
X1208016Y412762D01*
X1218141Y401553D01*
X1219396Y397681D01*
X1221688Y374167D01*
X1225254Y369200D01*
X1225432Y368952D01*
X1225341Y365453D01*
X1225340Y365452D01*
X1225205Y360205D01*
X1224813Y345063D01*
X1224730Y341840D01*
X1223997Y338670D01*
X1223453Y336318D01*
G01X577849Y231119D02*
X578610Y231880D01*
X581605D01*
X610194Y260469D01*
X627455Y346754D01*
X652474Y375345D01*
X666638Y396837D01*
X673223Y403144D01*
X676564Y404985D01*
X693672Y409193D01*
X695161Y410561D01*
X695812Y410532D01*
X696476Y411143D01*
X696503Y411795D01*
X697167Y412405D01*
X697818Y412376D01*
X698482Y412987D01*
X698509Y413639D01*
X699173Y414249D01*
X699824Y414220D01*
X699934Y414321D01*
X700488Y414831D01*
X700515Y415483D01*
Y415484D01*
X706710Y421179D01*
X707991Y421692D01*
X714008Y422889D01*
X719096Y422949D01*
X733347Y422657D01*
X737660D01*
X747646Y423552D01*
X750721Y424513D01*
X756530Y426958D01*
X767148Y439803D01*
X770674Y443517D01*
X772825Y444743D01*
X778422Y444986D01*
X796715Y442545D01*
X799035Y440995D01*
X888180Y423098D01*
X925476Y424970D01*
X961856Y410914D01*
X988366Y409918D01*
X1020915Y419609D01*
X1109368Y428518D01*
X1120301Y426283D01*
X1128400Y419055D01*
X1150136Y414349D01*
X1192191Y422758D01*
X1198447Y421021D01*
X1211400Y413111D01*
X1211872Y412823D01*
X1221221Y402692D01*
X1222802Y396709D01*
X1225211Y375192D01*
X1228899Y370056D01*
X1228735Y363735D01*
X1228715Y362963D01*
G01X568377Y236350D02*
X576544D01*
X577219Y237025D01*
X581099D01*
X607713Y263638D01*
X624918Y349641D01*
X649173Y377358D01*
X663533Y399137D01*
X672046Y407292D01*
X682783Y412673D01*
X697201Y417611D01*
X706618Y426265D01*
X726098Y427489D01*
X746127Y426441D01*
X751424Y428306D01*
X757803Y434331D01*
X769268Y446410D01*
X771868Y447714D01*
X778722Y448008D01*
X799572Y445217D01*
X800526Y444583D01*
X888457Y426927D01*
X926094Y428814D01*
X964723Y413882D01*
X985726Y413101D01*
X1020337Y423410D01*
X1109632Y432470D01*
X1122139Y429968D01*
X1132124Y421433D01*
X1146163Y418627D01*
X1150907Y417679D01*
X1193537Y426208D01*
X1194630Y425907D01*
X1199973Y424433D01*
X1214407Y415854D01*
X1224805Y405072D01*
X1226480Y398509D01*
X1228389Y387762D01*
X1229687Y376520D01*
X1233374Y371385D01*
X1233317Y369200D01*
X1233293Y368293D01*
X1233239Y366212D01*
G01X574900Y241006D02*
X580520D01*
X604536Y265022D01*
X621937Y352019D01*
X646135Y379671D01*
X660588Y401593D01*
X670632Y411214D01*
X671324Y411199D01*
X672047Y411891D01*
X672062Y412585D01*
X672784Y413276D01*
X674626Y413906D01*
X675248Y413601D01*
X676196Y413925D01*
X676500Y414549D01*
X695202Y420950D01*
X705029Y429984D01*
X734373Y431824D01*
X739760Y434992D01*
X746933Y435627D01*
X750611Y434981D01*
X756078Y437360D01*
X766395Y449636D01*
X770315Y450652D01*
X778921Y451032D01*
X805480Y447474D01*
X888738Y430756D01*
X926711Y432659D01*
X967749Y416790D01*
X982845Y416227D01*
X1019563Y427160D01*
X1110666Y436406D01*
X1123782Y433785D01*
X1135535Y423839D01*
X1150202Y420909D01*
X1194645Y429798D01*
X1201476Y427941D01*
X1216834Y418874D01*
X1228533Y406799D01*
X1229953Y400885D01*
X1232290Y388210D01*
X1233427Y378874D01*
X1237841Y372724D01*
X1236921Y337307D01*
G01X561294Y246750D02*
X580280D01*
X600867Y267338D01*
X618448Y355260D01*
X641679Y381808D01*
X644319Y392306D01*
X651382Y400590D01*
X660809Y410360D01*
X670194Y417420D01*
X692709Y425124D01*
X703045Y434629D01*
X733676Y436549D01*
X743441Y441989D01*
X747982Y447665D01*
X768396Y454531D01*
X779254Y455005D01*
X816070Y450066D01*
X816967Y450042D01*
X889178Y435544D01*
X927482Y437464D01*
X970089Y421009D01*
X980892Y420607D01*
X1018678Y431859D01*
X1112896Y441504D01*
X1124860Y439110D01*
X1132397Y433067D01*
Y433068D01*
X1139576Y427311D01*
X1150437Y425062D01*
X1196300Y434534D01*
X1202972Y432674D01*
X1219915Y422646D01*
X1233161Y409088D01*
X1236834Y391168D01*
X1238188Y381432D01*
X1243228Y374414D01*
X1242459Y344788D01*
G01X638108Y385368D02*
X637453Y382766D01*
X615946Y358188D01*
X598097Y268845D01*
X580995Y251743D01*
X568990D01*
G01X567240Y254900D02*
X581165D01*
X596195Y269930D01*
X614356Y360713D01*
X633868Y383009D01*
X636740Y396520D01*
X637334Y396905D01*
X637521Y397786D01*
X637136Y398379D01*
X637590Y400519D01*
X638064Y401872D01*
X639662Y403842D01*
X640390Y404371D01*
X641088Y404260D01*
X641817Y404789D01*
X641928Y405488D01*
X642656Y406017D01*
X643156Y405937D01*
X643354Y405906D01*
X644083Y406435D01*
X644194Y407134D01*
X644922Y407663D01*
X645620Y407552D01*
X646349Y408081D01*
X646460Y408781D01*
X647188Y409310D01*
X647886Y409199D01*
X648615Y409728D01*
X648726Y410427D01*
X651637Y412542D01*
X669271Y425357D01*
X675573Y432864D01*
X686395Y439113D01*
X691251Y440580D01*
X730011Y443034D01*
X739860Y450371D01*
X767246Y459581D01*
X779677Y460092D01*
Y460093D01*
X808644Y456210D01*
X817312Y456777D01*
X817315D01*
X889672Y442248D01*
X928570Y444198D01*
X974545Y426432D01*
X976599Y426355D01*
X1017418Y438512D01*
X1113594Y448275D01*
X1123062Y446383D01*
X1146163Y451088D01*
X1150294Y451929D01*
X1190732Y443581D01*
X1207494Y437599D01*
X1224348Y428788D01*
X1262906Y392475D01*
X1263258Y381434D01*
X1256558Y364683D01*
X1255921Y364410D01*
X1255549Y363480D01*
X1255822Y362843D01*
X1250454Y349421D01*
X1250110Y336170D01*
G01X575600Y259300D02*
X576339Y260039D01*
X581944D01*
X593312Y271407D01*
X611720Y363486D01*
X629557Y383867D01*
X630612Y388833D01*
X631206Y389218D01*
X631393Y390099D01*
X631007Y390692D01*
X631194Y391572D01*
X631788Y391957D01*
X631975Y392839D01*
X631590Y393432D01*
X631776Y394312D01*
X632370Y394697D01*
X632557Y395578D01*
X632172Y396171D01*
X632358Y397051D01*
X632952Y397436D01*
X633139Y398317D01*
X632754Y398910D01*
X633473Y402298D01*
X634875Y404030D01*
X636961Y406607D01*
X666654Y428166D01*
X673433Y436243D01*
X684331Y442534D01*
X690407Y444367D01*
X706967Y445406D01*
X730029Y446852D01*
X738442Y453114D01*
X766525Y462557D01*
X779690Y463134D01*
X804708Y459771D01*
X817561Y460613D01*
X847100Y454682D01*
X889961Y446077D01*
X979940Y450587D01*
X987217Y449734D01*
X987656Y449179D01*
X988551Y449074D01*
X989105Y449512D01*
X993258Y449026D01*
X993696Y448470D01*
X994591Y448365D01*
X995146Y448804D01*
X996408Y448657D01*
X996847Y448101D01*
X997741Y447996D01*
X998296Y448434D01*
X1035027Y444130D01*
X1114546Y452200D01*
X1125341Y450041D01*
X1146163Y454265D01*
X1150106Y455065D01*
X1194482Y445981D01*
X1194630Y445929D01*
X1212408Y439716D01*
X1226879Y431964D01*
X1267287Y394410D01*
X1267500Y387750D01*
X1267600Y384631D01*
X1267725Y380726D01*
X1254844Y348524D01*
X1254169Y322500D01*
X1254024Y316929D01*
X1236331Y285187D01*
X1218990Y278850D01*
X1217849D01*
G01X580659Y334764D02*
X582677Y344856D01*
X579376Y361375D01*
X579761Y361952D01*
X579565Y362933D01*
X578987Y363318D01*
X578792Y364298D01*
X579176Y364875D01*
X578980Y365856D01*
X578402Y366241D01*
X578207Y367221D01*
X578591Y367798D01*
X578395Y368779D01*
X577818Y369164D01*
X577622Y370144D01*
X578006Y370721D01*
X577810Y371702D01*
X577233Y372087D01*
X577037Y373067D01*
X577421Y373644D01*
X577225Y374625D01*
X576648Y375010D01*
X576452Y375990D01*
X576836Y376567D01*
X576640Y377549D01*
X576063Y377933D01*
X575867Y378913D01*
X576251Y379490D01*
X576055Y380471D01*
X575478Y380856D01*
X574192Y387286D01*
X576198Y397319D01*
X579726Y403685D01*
X604828Y434135D01*
X608533Y437243D01*
X614198Y440771D01*
X629701Y447612D01*
X630695Y447744D01*
X631246Y447323D01*
X632238Y447456D01*
X632659Y448007D01*
X633650Y448139D01*
X634200Y447718D01*
X635192Y447850D01*
X635613Y448402D01*
X640267Y449023D01*
X642405Y449828D01*
X649583Y457680D01*
X673589Y471539D01*
X683307Y474471D01*
X717504Y476617D01*
X757800Y490169D01*
X758375Y490362D01*
X780830Y491342D01*
X793957Y489614D01*
X820046Y491321D01*
X892690Y476731D01*
X981976Y481208D01*
X1035732Y474842D01*
X1119535Y483355D01*
X1141972Y478868D01*
X1146163Y479704D01*
X1154167Y481302D01*
X1171661Y477803D01*
X1179456Y479366D01*
X1219232Y471390D01*
X1255494Y453014D01*
X1302118Y409090D01*
X1303220Y374559D01*
X1295244Y354624D01*
X1289947Y341382D01*
X1289059Y307204D01*
X1286534Y302672D01*
X1262062Y258761D01*
X1238198Y243069D01*
X1228968Y239250D01*
X1223200D01*
G01X580659Y334764D02*
X574496Y303937D01*
X570083Y294388D01*
X569812Y293801D01*
G01X560884Y290296D02*
Y289116D01*
X561325Y288675D01*
X562355D01*
X563254Y289575D01*
X564232Y291077D01*
X571001Y308704D01*
X575930Y333345D01*
Y349382D01*
X568618Y385947D01*
X570972Y397716D01*
X575922Y406644D01*
X601195Y437301D01*
X605785Y441152D01*
X625201Y453757D01*
X637524Y460730D01*
X651304Y465226D01*
X655055Y466337D01*
X671688Y475939D01*
X682452Y479187D01*
X716584Y481329D01*
X757490Y495088D01*
X757800Y495102D01*
X781482Y496133D01*
X794375Y494413D01*
X820376Y496110D01*
X893057Y481515D01*
X982483Y485998D01*
X1035748Y479627D01*
X1119966Y488186D01*
X1143981Y483383D01*
X1146163Y483815D01*
X1154002Y485369D01*
X1167858Y482598D01*
X1178255Y484684D01*
X1220400Y476199D01*
X1257780Y457457D01*
X1307432Y410662D01*
X1308616Y373528D01*
X1306885Y369200D01*
X1301896Y356728D01*
X1301892Y356716D01*
X1295865Y341647D01*
Y341646D01*
X1295295Y340221D01*
X1295000Y328859D01*
X1294622Y314300D01*
X1294400Y305773D01*
X1274129Y269400D01*
X1266107Y255005D01*
X1240588Y238225D01*
X1230145Y233900D01*
X1223260D01*
G01X555831Y294196D02*
Y292921D01*
X556228Y292524D01*
X557480D01*
X559451Y294497D01*
X567019Y311198D01*
X570188Y327051D01*
X569996Y339582D01*
X566122Y375830D01*
X564549Y383688D01*
X567801Y399954D01*
X572681Y408760D01*
X598318Y439861D01*
X603409Y444134D01*
X616252Y453253D01*
X616671Y453502D01*
X632324Y462815D01*
X636081Y464294D01*
X642655Y466884D01*
X652594Y470043D01*
X657937Y472399D01*
X670085Y479412D01*
X677991Y482435D01*
X683178Y483522D01*
X711870Y490357D01*
X755925Y498835D01*
X781610Y499951D01*
X794411Y498233D01*
X820635Y499944D01*
X888308Y486355D01*
X899644Y485658D01*
X982568Y489818D01*
X1036340Y483517D01*
X1120574Y492080D01*
X1145516Y487089D01*
X1146163Y487218D01*
X1153609Y488708D01*
X1168278Y485773D01*
X1180191Y488155D01*
X1188511Y486649D01*
X1221365Y480079D01*
X1259470Y461260D01*
X1311803Y411947D01*
X1312768Y381682D01*
X1313053Y372743D01*
X1308621Y361664D01*
X1300792Y338321D01*
X1298796Y304598D01*
X1269436Y251915D01*
X1242771Y234384D01*
X1231699Y229801D01*
X1231217Y229602D01*
Y229601D01*
X1231043Y229530D01*
X1223200D01*
G01X589349Y335730D02*
X593122Y354595D01*
X586373Y388334D01*
X588070Y396814D01*
X613049Y427117D01*
X623470Y433100D01*
X640792Y434921D01*
X654697Y445029D01*
X660393Y451822D01*
X677381Y461629D01*
X685627Y464118D01*
X719538Y466245D01*
X760309Y479958D01*
X760700Y479975D01*
X780846Y480834D01*
X793793Y479098D01*
X818924Y480738D01*
X891458Y466176D01*
X981274Y470679D01*
X1035686Y464301D01*
X1118164Y472680D01*
X1134819Y469349D01*
X1135722Y469168D01*
X1146163Y471256D01*
X1151267Y472277D01*
X1177227Y467084D01*
X1180176Y467664D01*
X1218168Y460066D01*
X1243126Y446707D01*
X1251850Y438487D01*
X1252750Y438242D01*
X1254584Y437744D01*
X1289983Y404387D01*
X1290867Y376655D01*
X1290600Y375987D01*
X1277756Y343871D01*
X1277201Y322500D01*
X1276936Y312270D01*
X1276890Y310509D01*
X1252870Y267414D01*
X1232689Y254144D01*
X1226488Y251581D01*
X1223200D01*
G01X568949Y294199D02*
X569220Y294786D01*
X573586Y304233D01*
X581708Y344856D01*
X573223Y387286D01*
X575295Y397650D01*
X578937Y404222D01*
X604150Y434807D01*
X607973Y438015D01*
X613752Y441614D01*
X629441Y448536D01*
X640034Y449951D01*
X641857Y450637D01*
X648980Y458430D01*
X673209Y472417D01*
X683138Y475413D01*
X717320Y477558D01*
X758199Y491306D01*
X780872Y492295D01*
X793988Y490569D01*
X820110Y492278D01*
X892761Y477686D01*
X982008Y482161D01*
X1035740Y475798D01*
X1119581Y484315D01*
X1141972Y479837D01*
X1154167Y482271D01*
X1171661Y478772D01*
X1179456Y480335D01*
X1219546Y472296D01*
X1256046Y453800D01*
X1303056Y409513D01*
X1304176Y374391D01*
X1290893Y341187D01*
X1290003Y306946D01*
X1262779Y258094D01*
X1238645Y242225D01*
X1229157Y238300D01*
X1223200D01*
G01X560884Y286396D02*
Y287284D01*
X561325Y287725D01*
X562749D01*
X563997Y288973D01*
X565083Y290643D01*
X571917Y308439D01*
X576880Y333250D01*
Y349477D01*
X569587Y385947D01*
X571875Y397385D01*
X576711Y406107D01*
X601873Y436629D01*
X606352Y440386D01*
X614463Y445652D01*
X615154Y445505D01*
X615910Y445995D01*
X616057Y446687D01*
X616811Y447177D01*
X617503Y447030D01*
X618259Y447520D01*
X618406Y448212D01*
X619160Y448702D01*
X619852Y448555D01*
X620608Y449045D01*
X620755Y449737D01*
X621509Y450227D01*
X622201Y450080D01*
X622957Y450570D01*
X623104Y451262D01*
X623470Y451500D01*
X625694Y452944D01*
X626418Y453354D01*
X628772Y454686D01*
X629454Y454497D01*
X630180Y454907D01*
X630238Y454940D01*
X630427Y455622D01*
X637909Y459856D01*
X641160Y460916D01*
X641790Y460596D01*
X642647Y460875D01*
X642967Y461506D01*
X643156Y461568D01*
X643822Y461785D01*
X644453Y461464D01*
X645309Y461743D01*
X645629Y462375D01*
X646484Y462654D01*
X647115Y462333D01*
X647971Y462612D01*
X648292Y463244D01*
X651587Y464318D01*
X655433Y465458D01*
X672068Y475061D01*
X682621Y478245D01*
X716768Y480388D01*
X757666Y494144D01*
X781440Y495180D01*
X794343Y493458D01*
X820312Y495153D01*
X892986Y480560D01*
X982450Y485045D01*
X1035740Y478671D01*
X1119920Y487226D01*
X1143980Y482414D01*
X1146163Y482847D01*
X1154001Y484400D01*
X1167858Y481629D01*
X1178255Y483714D01*
X1220088Y475292D01*
X1257229Y456669D01*
X1305000Y411647D01*
X1306000Y410705D01*
X1306494Y410239D01*
X1307660Y373696D01*
X1305861Y369200D01*
X1305000Y367048D01*
X1301003Y357055D01*
X1300999Y357043D01*
X1298664Y351204D01*
X1295000Y342044D01*
X1294349Y340416D01*
X1293671Y314300D01*
X1293456Y306031D01*
X1273041Y269400D01*
X1265390Y255672D01*
X1240141Y239069D01*
X1229956Y234850D01*
X1223200D01*
G01X552151Y292245D02*
X552706Y292800D01*
X554608D01*
X555834Y291574D01*
X557874D01*
X560246Y293947D01*
X567930Y310905D01*
X571140Y326964D01*
X570946Y339640D01*
X567063Y375974D01*
X565518Y383688D01*
X568704Y399623D01*
X573470Y408223D01*
X598996Y439189D01*
X603991Y443381D01*
X616771Y452456D01*
X632744Y461959D01*
X642973Y465988D01*
X652931Y469152D01*
X658368Y471550D01*
X670495Y478551D01*
X678260Y481520D01*
X683386Y482594D01*
X712070Y489428D01*
X756036Y497888D01*
X781567Y498998D01*
X794378Y497278D01*
X820571Y498987D01*
X888185Y485410D01*
X899639Y484706D01*
X982536Y488865D01*
X1036333Y482561D01*
X1120528Y491119D01*
Y491120D01*
X1145516Y486120D01*
X1146163Y486249D01*
X1153609Y487739D01*
X1168278Y484804D01*
X1180200Y487187D01*
X1188333Y485715D01*
X1221056Y479171D01*
X1258922Y460471D01*
X1310865Y411524D01*
X1312097Y372911D01*
X1307729Y361992D01*
X1299851Y338503D01*
X1297860Y304871D01*
X1268719Y252582D01*
X1242324Y235228D01*
X1230971Y230529D01*
X1230854Y230480D01*
X1223200D01*
G01X1222673Y267973D02*
X1225542Y270842D01*
X1243079Y277247D01*
X1263731Y314300D01*
X1263944Y322500D01*
X1264569Y346526D01*
X1277556Y378995D01*
X1276926Y398759D01*
X1235712Y437587D01*
X1218742Y446667D01*
X1206845Y450934D01*
X1148981Y462500D01*
X1146163Y461938D01*
X1128053Y458324D01*
X1115228Y460889D01*
X1035048Y452746D01*
X980891Y459216D01*
X890619Y454690D01*
X847100Y463425D01*
X818139Y469238D01*
X797106Y467864D01*
X780837Y470049D01*
X780200Y470135D01*
X764941Y469468D01*
X735397Y459533D01*
X729885Y455432D01*
X688410Y452832D01*
X681270Y450676D01*
X667849Y442928D01*
X661275Y435090D01*
X631347Y413347D01*
X627585Y408701D01*
X622456Y404407D01*
X618269Y383987D01*
X605796Y369730D01*
X601049Y345981D01*
G01X1221990Y255981D02*
X1225366D01*
X1230437Y257941D01*
X1238711Y263381D01*
X1238710Y263382D01*
X1249463Y270450D01*
X1272492Y311769D01*
X1272771Y322500D01*
X1273353Y344927D01*
X1286425Y377603D01*
X1285625Y402685D01*
X1252797Y433616D01*
X1252750Y433640D01*
X1249111Y435486D01*
X1240177Y443903D01*
X1216846Y456390D01*
X1181720Y463414D01*
X1178915Y462861D01*
X1149330Y468776D01*
X1146163Y468143D01*
X1132420Y465396D01*
X1116174Y468645D01*
X1035657Y460468D01*
X981142Y466857D01*
X891158Y462348D01*
X847100Y471195D01*
X818651Y476907D01*
X793647Y475276D01*
X780557Y477026D01*
X761008Y476174D01*
X760700Y476070D01*
X720281Y462475D01*
X686652Y460365D01*
X678599Y457934D01*
X662877Y448855D01*
X656489Y441240D01*
X641810Y430571D01*
X623600Y428659D01*
X615557Y424163D01*
X604278Y410479D01*
X604276D01*
X591759Y395295D01*
X590440Y388696D01*
X594567Y368058D01*
X594800Y366894D01*
G01X586109Y367405D02*
X582025Y387830D01*
X583980Y397605D01*
X584867Y399205D01*
X609957Y429640D01*
X618807Y435425D01*
X633082Y440732D01*
X643156Y442077D01*
X644268Y442226D01*
X649389Y446292D01*
X655210Y453227D01*
X675911Y465177D01*
X684900Y467891D01*
X718802Y470017D01*
X759605Y483740D01*
X780913Y484668D01*
X793910Y482931D01*
X819582Y484593D01*
X892126Y470024D01*
X981405Y474500D01*
X1035716Y468134D01*
X1118731Y476566D01*
X1138052Y472702D01*
X1146163Y474327D01*
X1151416Y475379D01*
X1176448Y470369D01*
X1181378Y471355D01*
X1219529Y463726D01*
X1245454Y449853D01*
X1252750Y442979D01*
X1253399Y442367D01*
X1256777Y441502D01*
X1294340Y406120D01*
X1295000Y385409D01*
X1295304Y375869D01*
X1295000Y375109D01*
X1292637Y369200D01*
X1291900Y367358D01*
X1289217Y360651D01*
X1288658Y359253D01*
X1288657Y359250D01*
X1288651Y359235D01*
X1288648Y359227D01*
X1288647Y359224D01*
X1282134Y342942D01*
X1281602Y322500D01*
X1281260Y309380D01*
X1280747Y308459D01*
X1256121Y264272D01*
X1234304Y249926D01*
X1231047Y248574D01*
X1231046Y248573D01*
Y248574D01*
X1227697Y247185D01*
X1224995D01*
G01X584181Y360208D02*
X583785Y362188D01*
X584177Y362776D01*
X584001Y363659D01*
X583412Y364052D01*
X583201Y365107D01*
X583594Y365695D01*
X583417Y366579D01*
X582828Y366971D01*
X582652Y367853D01*
X583045Y368441D01*
X582868Y369325D01*
X582279Y369717D01*
X582103Y370599D01*
X582495Y371187D01*
X582318Y372071D01*
X581729Y372463D01*
X581553Y373345D01*
X581945Y373933D01*
X581768Y374817D01*
X581179Y375209D01*
X581003Y376091D01*
X581395Y376680D01*
X581219Y377563D01*
X580629Y377955D01*
X580337Y379418D01*
X580729Y380006D01*
X580552Y380890D01*
X579963Y381282D01*
X578637Y387912D01*
X580499Y397222D01*
X582788Y401350D01*
X607677Y431543D01*
X616839Y437749D01*
X616900Y437772D01*
X631762Y443438D01*
X642813Y444918D01*
X643156Y445146D01*
X644191Y445833D01*
X646044Y447544D01*
X652051Y454702D01*
X674815Y467846D01*
X684331Y470719D01*
X718248Y472847D01*
X759073Y486578D01*
X781049Y487535D01*
X794018Y485800D01*
X819754Y487473D01*
X892370Y472901D01*
X981846Y477387D01*
X1035707Y471009D01*
X1119308Y479502D01*
X1140378Y475288D01*
X1146163Y476445D01*
X1153796Y477971D01*
X1173039Y474120D01*
X1174239Y474360D01*
X1174827Y473968D01*
X1175711Y474145D01*
X1176103Y474734D01*
X1177772Y475068D01*
X1179457Y474731D01*
X1179849Y474142D01*
X1180733Y473965D01*
X1181321Y474358D01*
X1220359Y466547D01*
X1254218Y448427D01*
X1297761Y407407D01*
X1298786Y375260D01*
X1292178Y358739D01*
X1292177Y358736D01*
X1291900Y358043D01*
X1291879Y357989D01*
X1285570Y342217D01*
X1285565Y342036D01*
X1285564Y342018D01*
Y342017D01*
X1284844Y314300D01*
X1284695Y308557D01*
X1262872Y269400D01*
X1258624Y261777D01*
X1235886Y246827D01*
X1228419Y243737D01*
X1224340D01*
G01X1224130Y264969D02*
X1226666Y266332D01*
X1229478Y267582D01*
X1229486Y267586D01*
X1234453Y269400D01*
X1246223Y273698D01*
X1268110Y312969D01*
X1268145Y314300D01*
X1268358Y322500D01*
X1268958Y345624D01*
X1269820Y347780D01*
X1275408Y361749D01*
X1275407D01*
X1281993Y378216D01*
X1281276Y400721D01*
X1249700Y430473D01*
X1247925Y431357D01*
X1237984Y440723D01*
X1216356Y452297D01*
X1149417Y465679D01*
X1146163Y465028D01*
X1130400Y461875D01*
X1130360Y461867D01*
X1130353Y461866D01*
X1115806Y464776D01*
X1035622Y456636D01*
X981012Y463036D01*
X890876Y458518D01*
X847100Y467309D01*
X818395Y473073D01*
X793400Y471441D01*
X780095Y473185D01*
X761715Y472392D01*
X721012Y458703D01*
X687713Y456615D01*
X679766Y454214D01*
X665367Y445893D01*
X664772Y445183D01*
X664771Y445184D01*
X658783Y438046D01*
X632907Y419243D01*
X628805Y416262D01*
X626546Y413472D01*
X625489Y412167D01*
X618034Y406473D01*
X616900Y400947D01*
X613485Y384304D01*
X603117Y372455D01*
X600568Y359708D01*
G01X581747Y647323D02*
X580407Y648663D01*
X579366D01*
X576941Y646238D01*
G01Y652238D02*
X579366Y649813D01*
X580297D01*
X581747Y651263D01*
G01X632584Y147965D02*
X636368Y146653D01*
X646861Y148751D01*
X659815Y145824D01*
X660478Y145956D01*
X662390Y146238D01*
X664175Y145828D01*
Y145827D01*
X666040Y145399D01*
X670560Y141086D01*
X688178Y139007D01*
X689646Y138823D01*
X723537Y129558D01*
X736958Y133143D01*
Y133142D01*
X737140Y133191D01*
X737141Y133192D01*
X742100Y134512D01*
X774808Y132561D01*
X812300Y140058D01*
X824174Y145599D01*
X830540Y146545D01*
X875578Y155553D01*
X888865Y158211D01*
X936069Y148772D01*
X944161Y143892D01*
X974613Y137801D01*
X977187Y137369D01*
X997936Y141446D01*
X1009966Y140169D01*
X1019417Y141745D01*
X1102219Y158305D01*
X1129498Y152849D01*
X1129528Y152842D01*
X1130400Y152668D01*
X1147242Y149298D01*
X1155264Y150903D01*
X1159831Y153946D01*
X1170005Y166543D01*
X1169945Y167105D01*
X1170795Y168156D01*
X1171357Y168216D01*
X1172205Y169266D01*
X1172592Y170703D01*
X1172310Y171193D01*
X1172661Y172498D01*
X1173152Y172780D01*
X1173503Y174083D01*
X1173221Y174573D01*
X1173572Y175878D01*
X1174063Y176160D01*
X1174414Y177463D01*
X1174132Y177953D01*
X1174484Y179258D01*
X1174975Y179540D01*
X1175326Y180843D01*
X1175043Y181333D01*
X1175395Y182638D01*
X1175886Y182920D01*
X1176237Y184223D01*
X1175954Y184713D01*
X1176306Y186018D01*
X1176797Y186300D01*
X1177148Y187603D01*
X1176866Y188093D01*
X1177218Y189398D01*
X1177709Y189680D01*
X1178060Y190983D01*
X1177778Y191474D01*
X1178130Y192778D01*
X1178621Y193060D01*
X1178972Y194363D01*
X1179054Y194502D01*
Y197400D01*
G01X622421Y126575D02*
X628617Y122801D01*
X630918Y122341D01*
Y122340D01*
X654840Y117555D01*
X674385Y121464D01*
X679228Y120732D01*
X684772Y117706D01*
X695850Y116505D01*
X723563Y111506D01*
X727267Y112339D01*
X747093Y119223D01*
X773216Y118826D01*
X777693Y119536D01*
X818829Y126807D01*
X825878Y129343D01*
X833488Y129713D01*
X875578Y138634D01*
X886805Y141013D01*
X932430Y131522D01*
X936481Y131977D01*
X981470Y122978D01*
X996328Y123645D01*
X1006559Y122210D01*
X1103281Y141556D01*
X1147665Y132678D01*
X1168823Y138415D01*
X1169521Y139000D01*
X1193161Y158825D01*
X1198732Y190420D01*
X1195556Y200773D01*
Y201235D01*
G01X1171982Y200513D02*
X1171439Y198597D01*
X1171429Y198592D01*
X1164686Y182411D01*
X1154425Y175570D01*
X1144641Y173612D01*
X1131881Y164171D01*
X1103126Y165483D01*
X1024976Y149853D01*
X1011068Y148006D01*
X1001879Y148314D01*
X1001864D01*
X1000926Y148313D01*
X996499Y148399D01*
X986818Y144792D01*
X976403Y142709D01*
X952155Y147560D01*
X940839Y155105D01*
X890018Y165269D01*
X830684Y153401D01*
X823212Y152197D01*
X810339Y144866D01*
X775092Y137816D01*
X750492Y139134D01*
X738799Y140799D01*
X731059Y139140D01*
X720133Y141387D01*
X678851Y155529D01*
X673967Y156831D01*
X657233Y153372D01*
X647244Y155866D01*
X637231Y153863D01*
X625112Y158422D01*
X608497Y155191D01*
X601995Y156616D01*
G01X649591Y138067D02*
X654578Y139065D01*
X658357Y138307D01*
X661573Y137658D01*
X684027Y135364D01*
X684182Y135335D01*
X723057Y124696D01*
X744116Y131296D01*
X774658Y129417D01*
X814392Y137364D01*
X825579Y142273D01*
X830521Y142651D01*
X830608Y142664D01*
X875578Y151659D01*
X888441Y154232D01*
X936359Y144647D01*
X941270Y141374D01*
X977249Y134178D01*
X996605Y137215D01*
X1009383Y135856D01*
X1102181Y154417D01*
X1147611Y145331D01*
X1160688Y149268D01*
X1172223Y161681D01*
X1172202Y162246D01*
X1173122Y163236D01*
X1173688Y163257D01*
X1174606Y164245D01*
X1174585Y164810D01*
X1175505Y165800D01*
X1176070Y165821D01*
X1176989Y166809D01*
X1177629Y169266D01*
X1177343Y169754D01*
X1177683Y171061D01*
X1178172Y171347D01*
X1178512Y172653D01*
X1178226Y173141D01*
X1178567Y174448D01*
X1179056Y174734D01*
X1179396Y176040D01*
X1179110Y176528D01*
X1179451Y177835D01*
X1179940Y178121D01*
X1180280Y179427D01*
X1179994Y179915D01*
X1180335Y181222D01*
X1180824Y181508D01*
X1181164Y182814D01*
X1180878Y183302D01*
X1181219Y184609D01*
X1181708Y184895D01*
X1182048Y186201D01*
X1181762Y186689D01*
X1182103Y187996D01*
X1182592Y188282D01*
X1182932Y189588D01*
X1182948Y197409D01*
G01X1128650Y207950D02*
X1127118D01*
X1125283Y208155D01*
X1124788Y207760D01*
X1124495Y205135D01*
X1123385Y204244D01*
X1120265Y204594D01*
X1119375Y205704D01*
X1119668Y208330D01*
X1119269Y208825D01*
X1111966Y209637D01*
X1104605Y208165D01*
X1103905Y207698D01*
X1103343Y204895D01*
X1101997Y203998D01*
X1099054Y204587D01*
X1098265Y205771D01*
X1098854Y208709D01*
X1098501Y209237D01*
X1095452Y209847D01*
X1093500Y209455D01*
X1092383Y207782D01*
X1093184Y203776D01*
X1092397Y202590D01*
X1089321Y201974D01*
X1088134Y202761D01*
X1087387Y206496D01*
X1086062Y207381D01*
X1084332Y207794D01*
X1083791Y207462D01*
X1082958Y203965D01*
X1081747Y203219D01*
X1078693Y203948D01*
X1077947Y205159D01*
X1078780Y208656D01*
X1078448Y209196D01*
X1074942Y210030D01*
X1073686Y209222D01*
X1071457Y205638D01*
X1068401Y202110D01*
X1066868Y201215D01*
X1063566Y200555D01*
X1055970Y202073D01*
X1052907Y201461D01*
X1050690Y199983D01*
X1048588Y199563D01*
X1045791Y200122D01*
X1043400Y199643D01*
X1043027D01*
X1038520Y200545D01*
X1034116Y203481D01*
X1032339Y203837D01*
X1029042Y203177D01*
X1027366Y202061D01*
X1012700Y199127D01*
X1008011Y200064D01*
Y200065D01*
X1003320Y201004D01*
X993493Y198550D01*
X987633D01*
X986376Y200130D01*
X985117Y201389D01*
X979780Y204911D01*
X973252Y206514D01*
X973251D01*
X970288Y206454D01*
X967550Y204465D01*
X967538Y204455D01*
X967515Y204435D01*
X967479Y204402D01*
X958501Y194624D01*
X958435Y194570D01*
X958431Y194567D01*
X958417Y194555D01*
X958286Y194449D01*
X953594Y191662D01*
X949007Y190686D01*
X948586Y190691D01*
X938837Y193047D01*
X938829Y193048D01*
X930795Y194654D01*
X897785Y202169D01*
X897392Y202173D01*
X815940Y185872D01*
X790325Y168853D01*
X781316Y167048D01*
X772764Y170798D01*
X756049Y183530D01*
X727847Y183108D01*
X726746Y183326D01*
X726743D01*
X726739Y183327D01*
X683414Y191883D01*
X659346Y202046D01*
X634264Y197080D01*
G01X634044Y184570D02*
X655255Y188965D01*
X679481Y180842D01*
X726496Y171438D01*
X752487Y171711D01*
X766482Y161660D01*
X777785Y157040D01*
X796781Y160833D01*
X817014Y174322D01*
X817264Y174489D01*
X875578Y186154D01*
X893134Y189666D01*
X948158Y178662D01*
X978472Y184724D01*
X979748Y184523D01*
X1010011Y177937D01*
X1011207Y178703D01*
X1011439Y179769D01*
X1011973Y180113D01*
X1014271Y179611D01*
X1014615Y179077D01*
X1014383Y178014D01*
X1015153Y176817D01*
X1018225Y176149D01*
X1019421Y176915D01*
X1019969Y179429D01*
X1020503Y179773D01*
X1022801Y179271D01*
X1023145Y178737D01*
X1022597Y176225D01*
X1023063Y175500D01*
X1023367Y175028D01*
X1026306Y174388D01*
X1028902Y174874D01*
X1029331Y175500D01*
X1029705Y176047D01*
X1029440Y177460D01*
X1029800Y177984D01*
X1032111Y178418D01*
X1032635Y178059D01*
X1032888Y176702D01*
X1034073Y175903D01*
X1102145Y189444D01*
X1108334Y189017D01*
X1109404Y189953D01*
X1109451Y190623D01*
X1109929Y191041D01*
X1112275Y190879D01*
X1112694Y190399D01*
X1112648Y189730D01*
X1113582Y188659D01*
X1116719Y188443D01*
X1118232Y189763D01*
X1119976Y189643D01*
X1121328Y188096D01*
X1128889Y187578D01*
X1134218Y190230D01*
X1134819Y190971D01*
X1140009Y197367D01*
X1147628Y205344D01*
X1149071Y206787D01*
G01X652282Y184964D02*
X655704Y185670D01*
X679754Y177733D01*
X706967Y172289D01*
X725781Y168525D01*
X743800Y168730D01*
X744052Y168733D01*
X745068Y167739D01*
X745090Y165855D01*
X745545Y165410D01*
X747096Y165428D01*
X747195Y165529D01*
X747540Y165882D01*
X747518Y167767D01*
X748512Y168783D01*
X751909Y168821D01*
X763916Y159465D01*
X766099Y158034D01*
X777659Y154763D01*
X798336Y158900D01*
X818447Y171527D01*
X831303Y174377D01*
X875578Y183236D01*
X892669Y186656D01*
X948613Y175468D01*
X976592Y181064D01*
X1025973Y171189D01*
X1102491Y186488D01*
X1109397Y186002D01*
X1109824Y186373D01*
X1111172Y186278D01*
X1111542Y185850D01*
X1117672Y185419D01*
X1118099Y185790D01*
X1119446Y185695D01*
X1119817Y185267D01*
X1122655Y185067D01*
X1123082Y185438D01*
X1124430Y185343D01*
X1124801Y184914D01*
X1126147Y184820D01*
X1126574Y185191D01*
X1127922Y185096D01*
X1128293Y184667D01*
Y184668D01*
X1129639Y184573D01*
X1138586Y190230D01*
X1141974Y195352D01*
X1147555Y201974D01*
X1148776Y202753D01*
X1148899Y203305D01*
X1150038Y204032D01*
X1150590Y203910D01*
X1151728Y204635D01*
X1152401Y205692D01*
G01X601747Y170876D02*
X611272Y168476D01*
X627498Y171630D01*
X637308Y167495D01*
X648545Y169741D01*
X649622Y169536D01*
X652482Y168834D01*
X658078Y167088D01*
X673349Y171088D01*
X714334Y162903D01*
X732284Y158024D01*
X746051Y155116D01*
X747195Y154378D01*
X750747Y152085D01*
X757165Y149243D01*
X775518Y148123D01*
X804169Y153854D01*
X819530Y164020D01*
X875578Y175229D01*
X891222Y178357D01*
X945995Y167402D01*
X963943Y155438D01*
X976392Y152950D01*
X980791Y153830D01*
X994573Y162163D01*
X1018981Y162574D01*
Y162575D01*
X1028742Y163332D01*
X1099460Y177476D01*
X1102387Y178173D01*
X1129990Y176865D01*
X1130400Y177126D01*
X1141221Y184003D01*
X1143393Y184565D01*
X1147892Y188198D01*
X1151608Y192958D01*
X1156120Y198482D01*
X1156064Y199045D01*
X1156919Y200091D01*
X1157481Y200148D01*
X1158335Y201193D01*
X1158689Y201547D01*
G01X653000Y261300D02*
Y264800D01*
G01X656100Y275500D02*
Y267900D01*
X653000Y264800D01*
G01X637681Y332390D02*
Y333531D01*
X638232Y334082D01*
X639308D01*
X641390Y332000D01*
G01X637681Y337390D02*
Y335720D01*
X638369Y335032D01*
X639422D01*
X641390Y337000D01*
G01X637600Y302000D02*
Y303533D01*
X637967Y303900D01*
X639000D01*
X640900Y302000D01*
G01Y307000D02*
X639000Y305100D01*
X637943D01*
X637600Y305443D01*
Y307000D01*
G01X659000Y345500D02*
X660389D01*
X661098Y346209D01*
Y350613D01*
X660505Y351206D01*
X659694D01*
G01X664000Y345500D02*
X662951D01*
X662048Y346403D01*
Y350169D01*
X663085Y351206D01*
X664194D01*
G01X649000Y345500D02*
X650117D01*
X651098Y346481D01*
Y350441D01*
X650333Y351206D01*
X649194D01*
G01X654000Y345500D02*
X652951D01*
X652048Y346403D01*
Y350313D01*
X652941Y351206D01*
X654194D01*
G01X638108Y385368D02*
X640946Y396648D01*
X653583Y409691D01*
X668384Y420827D01*
X690718Y428469D01*
X701460Y438346D01*
X731174Y440234D01*
X732299Y440306D01*
X741899Y445653D01*
X743800Y448037D01*
X745373Y450009D01*
X767671Y457508D01*
X779481Y458020D01*
X812507Y453597D01*
X817120Y453899D01*
X889460Y439373D01*
X928108Y441310D01*
X972314Y424227D01*
X978787Y423985D01*
X1018155Y435713D01*
X1113299Y445369D01*
X1126621Y442707D01*
X1143627Y429796D01*
X1146163Y429218D01*
X1150172Y428304D01*
X1195408Y438523D01*
X1206319Y435106D01*
X1222255Y426024D01*
X1222365Y425910D01*
X1236946Y410747D01*
X1240843Y390649D01*
X1241885Y383846D01*
X1244794Y379794D01*
X1247627Y375849D01*
X1247387Y366609D01*
X1247388D01*
X1246216Y321512D01*
X1246214Y321511D01*
X1246147Y318870D01*
X1231058Y291796D01*
X1217934Y287000D01*
X1214900D01*
X1214300Y286400D01*
G01X634137Y404629D02*
X634395Y404947D01*
X636301Y407302D01*
X641708Y411228D01*
X665500Y428502D01*
X666001Y428866D01*
X672812Y436983D01*
X678783Y440429D01*
X683951Y443412D01*
X690238Y445309D01*
X706967Y446358D01*
X729688Y447783D01*
X737004Y453229D01*
X737996Y453967D01*
X766349Y463501D01*
X779733Y464087D01*
X804741Y460726D01*
X817625Y461570D01*
X847100Y455652D01*
X890032Y447032D01*
X979972Y451540D01*
X1035034Y445086D01*
X1114592Y453160D01*
X1125340Y451011D01*
X1146163Y455235D01*
X1150107Y456035D01*
X1194630Y446920D01*
X1194735Y446899D01*
X1212792Y440589D01*
X1227436Y432744D01*
X1268225Y394837D01*
X1268422Y388672D01*
X1268681Y380558D01*
X1255790Y348329D01*
X1255119Y322500D01*
X1254968Y316671D01*
X1236989Y284415D01*
X1219230Y277926D01*
X1219225Y277900D01*
X1217900D01*
G01X621422Y647247D02*
X622917Y648742D01*
X624931D01*
X629280Y648405D01*
X634609Y649297D01*
X636752Y651933D01*
X637089Y653842D01*
X637609Y654205D01*
X639028Y653955D01*
X639393Y653435D01*
X637867Y644780D01*
X638684Y643614D01*
X640878Y643229D01*
X642046Y644046D01*
X643755Y653747D01*
X644275Y654111D01*
X645693Y653861D01*
X646057Y653340D01*
X644547Y644769D01*
X645362Y643600D01*
X647556Y643215D01*
X648724Y644032D01*
X650436Y653749D01*
X650956Y654113D01*
X652375Y653863D01*
X652740Y653344D01*
X651243Y644850D01*
X652058Y643683D01*
X654254Y643299D01*
X655422Y644114D01*
X657120Y653761D01*
X657640Y654126D01*
X659058Y653876D01*
X659422Y653355D01*
X657928Y644872D01*
X658743Y643703D01*
X660937Y643318D01*
X662105Y644135D01*
X663799Y653755D01*
X664319Y654119D01*
X665739Y653871D01*
X666103Y653351D01*
X664606Y644856D01*
X665423Y643690D01*
X667615Y643305D01*
X668784Y644120D01*
X670493Y653822D01*
X671012Y654185D01*
X672432Y653937D01*
X672796Y653417D01*
X671291Y644876D01*
X672108Y643710D01*
X674301Y643325D01*
X675469Y644142D01*
X677173Y653814D01*
X677706Y654187D01*
X679102Y653941D01*
X679478Y653406D01*
X677971Y644854D01*
X678787Y643687D01*
X680979Y643302D01*
X682148Y644119D01*
X683856Y653828D01*
X684376Y654192D01*
X685797Y653942D01*
X686160Y653422D01*
X684652Y644855D01*
X685469Y643689D01*
X687660Y643305D01*
X688829Y644122D01*
X690533Y653795D01*
X691053Y654159D01*
X692473Y653910D01*
X692838Y653388D01*
X691336Y644871D01*
X692151Y643702D01*
X694344Y643317D01*
X695512Y644134D01*
X697212Y653765D01*
X697735Y654131D01*
X699151Y653882D01*
X699516Y653359D01*
X698014Y644841D01*
X698831Y643674D01*
X701026Y643289D01*
X702191Y644104D01*
X703895Y653777D01*
X704419Y654143D01*
X705835Y653895D01*
X706200Y653374D01*
X704692Y644808D01*
X705505Y643642D01*
X707703Y643256D01*
X708868Y644071D01*
X710576Y653780D01*
X711099Y654146D01*
X712516Y653897D01*
X712881Y653376D01*
X711373Y644822D01*
X712202Y643643D01*
X714373Y643260D01*
X715551Y644085D01*
X717255Y653757D01*
X717778Y654123D01*
X719196Y653874D01*
X719561Y653353D01*
X718056Y644812D01*
X718872Y643647D01*
X721066Y643262D01*
X722231Y644077D01*
X723940Y653778D01*
X724463Y654143D01*
X725881Y653894D01*
X726246Y653373D01*
X724749Y644878D01*
X725565Y643713D01*
X727759Y643328D01*
X728925Y644144D01*
X730619Y653764D01*
X731142Y654130D01*
X732559Y653881D01*
X732924Y653358D01*
X731429Y644874D01*
X732245Y643708D01*
X734439Y643322D01*
X735604Y644138D01*
X737302Y653784D01*
X737825Y654149D01*
X739245Y653901D01*
X739609Y653380D01*
X738112Y644885D01*
X738928Y643721D01*
X741122Y643334D01*
X742288Y644150D01*
X744000Y653867D01*
X744523Y654233D01*
X745940Y653984D01*
X746305Y653461D01*
X744794Y644889D01*
X745610Y643723D01*
X747804Y643336D01*
X748969Y644152D01*
X750678Y653853D01*
X751201Y654219D01*
X752620Y653970D01*
X752985Y653449D01*
X751459Y644794D01*
X752275Y643629D01*
X754469Y643243D01*
X755635Y644057D01*
X757344Y653758D01*
X757864Y654122D01*
X759282Y653872D01*
X759646Y653351D01*
X758136Y644780D01*
X758951Y643611D01*
X761145Y643226D01*
X762313Y644043D01*
X764025Y653760D01*
X764545Y654124D01*
X765964Y653874D01*
X766329Y653355D01*
X764832Y644861D01*
X765647Y643694D01*
X767843Y643310D01*
X769011Y644125D01*
X770709Y653772D01*
X771229Y654137D01*
X772647Y653887D01*
X773011Y653366D01*
X771503Y644803D01*
X772318Y643634D01*
X774512Y643249D01*
X775680Y644066D01*
X777388Y653766D01*
X777908Y654130D01*
X779328Y653882D01*
X779692Y653362D01*
X778178Y644770D01*
X778995Y643604D01*
X781187Y643219D01*
X782356Y644034D01*
X784082Y653833D01*
X784601Y654196D01*
X786021Y653948D01*
X786385Y653428D01*
X784863Y644790D01*
X785680Y643624D01*
X787873Y643239D01*
X789041Y644056D01*
X790762Y653825D01*
X791295Y654198D01*
X792691Y653952D01*
X793067Y653417D01*
X791546Y644785D01*
X792362Y643618D01*
X794554Y643233D01*
X795723Y644050D01*
X797445Y653839D01*
X797969Y654205D01*
X799385Y653957D01*
X799750Y653436D01*
X798242Y644870D01*
X799055Y643704D01*
X801253Y643318D01*
X802418Y644133D01*
X804126Y653842D01*
X804649Y654208D01*
X806066Y653959D01*
X806431Y653438D01*
X804906Y644787D01*
X805735Y643608D01*
X807906Y643225D01*
X809084Y644050D01*
X810805Y653819D01*
X811328Y654185D01*
X812746Y653936D01*
X813111Y653415D01*
X811589Y644777D01*
X812405Y643612D01*
X814599Y643227D01*
X815764Y644042D01*
X817490Y653840D01*
X818013Y654205D01*
X819431Y653956D01*
X819796Y653435D01*
X818282Y644843D01*
X819098Y643678D01*
X821292Y643293D01*
X822458Y644109D01*
X824169Y653803D01*
X824692Y654169D01*
X826108Y653920D01*
X826473Y653397D01*
X824971Y644879D01*
X825788Y643712D01*
X827983Y643327D01*
X829148Y644142D01*
X830852Y653815D01*
X831376Y654181D01*
X832792Y653933D01*
X833157Y653412D01*
X831649Y644846D01*
X832462Y643680D01*
X834660Y643294D01*
X835825Y644109D01*
X837533Y653818D01*
X838056Y654184D01*
X839473Y653935D01*
X839838Y653414D01*
X838330Y644860D01*
X839159Y643681D01*
X841330Y643298D01*
X842508Y644123D01*
X844212Y653795D01*
X844735Y654161D01*
X846153Y653912D01*
X846518Y653391D01*
X845013Y644850D01*
X845829Y643685D01*
X848023Y643300D01*
X849188Y644115D01*
X850897Y653816D01*
X851420Y654181D01*
X852838Y653932D01*
X853203Y653411D01*
X851706Y644916D01*
X852522Y643751D01*
X854716Y643366D01*
X855882Y644182D01*
X857576Y653802D01*
X858099Y654168D01*
X859516Y653919D01*
X859881Y653396D01*
X858386Y644912D01*
X859202Y643746D01*
X861396Y643360D01*
X862561Y644176D01*
X864259Y653822D01*
X864782Y654187D01*
X866202Y653939D01*
X866566Y653418D01*
X865069Y644923D01*
X865885Y643759D01*
X868079Y643372D01*
X869245Y644188D01*
X870957Y653905D01*
X871480Y654271D01*
X872897Y654022D01*
X873262Y653499D01*
X871751Y644927D01*
X872567Y643761D01*
X874761Y643374D01*
X875926Y644190D01*
X877635Y653891D01*
X878158Y654257D01*
X879577Y654008D01*
X879942Y653487D01*
X878416Y644832D01*
X879232Y643667D01*
X881426Y643281D01*
X882592Y644094D01*
X882954Y646149D01*
X884715Y648315D01*
X889575Y649128D01*
X893845Y648798D01*
X895896D01*
X897391Y647303D01*
G01X621422Y651187D02*
X622917Y649692D01*
X624968D01*
X629238Y649362D01*
X634098Y650175D01*
X635859Y652341D01*
X636221Y654396D01*
X637387Y655209D01*
X639581Y654823D01*
X640397Y653658D01*
X638871Y645003D01*
X639236Y644482D01*
X640655Y644233D01*
X641178Y644599D01*
X642887Y654300D01*
X644052Y655116D01*
X646246Y654729D01*
X647062Y653563D01*
X645551Y644991D01*
X645916Y644468D01*
X647333Y644219D01*
X647856Y644585D01*
X649568Y654302D01*
X650734Y655118D01*
X652928Y654731D01*
X653744Y653567D01*
X652247Y645072D01*
X652611Y644551D01*
X654031Y644303D01*
X654554Y644668D01*
X656252Y654314D01*
X657417Y655130D01*
X659611Y654744D01*
X660427Y653578D01*
X658932Y645094D01*
X659297Y644571D01*
X660714Y644322D01*
X661237Y644688D01*
X662931Y654308D01*
X664097Y655124D01*
X666291Y654739D01*
X667107Y653574D01*
X665610Y645079D01*
X665975Y644558D01*
X667393Y644309D01*
X667916Y644674D01*
X669625Y654375D01*
X670790Y655190D01*
X672984Y654805D01*
X673800Y653640D01*
X672295Y645099D01*
X672660Y644578D01*
X674078Y644329D01*
X674601Y644695D01*
X676305Y654367D01*
X677483Y655192D01*
X679654Y654809D01*
X680483Y653630D01*
X678975Y645076D01*
X679340Y644555D01*
X680757Y644306D01*
X681280Y644672D01*
X682988Y654381D01*
X684153Y655196D01*
X686351Y654810D01*
X687164Y653644D01*
X685656Y645078D01*
X686021Y644557D01*
X687437Y644309D01*
X687961Y644675D01*
X689665Y654348D01*
X690830Y655163D01*
X693025Y654778D01*
X693842Y653611D01*
X692340Y645093D01*
X692705Y644570D01*
X694121Y644321D01*
X694644Y644687D01*
X696344Y654318D01*
X697512Y655135D01*
X699705Y654750D01*
X700520Y653581D01*
X699018Y645064D01*
X699383Y644542D01*
X700803Y644293D01*
X701323Y644657D01*
X703027Y654330D01*
X704196Y655147D01*
X706387Y654763D01*
X707204Y653597D01*
X705696Y645030D01*
X706059Y644510D01*
X707480Y644260D01*
X708000Y644624D01*
X709708Y654333D01*
X710877Y655150D01*
X713069Y654765D01*
X713885Y653598D01*
X712378Y645046D01*
X712754Y644511D01*
X714150Y644265D01*
X714683Y644638D01*
X716387Y654310D01*
X717555Y655127D01*
X719748Y654742D01*
X720565Y653576D01*
X719060Y645035D01*
X719424Y644515D01*
X720844Y644267D01*
X721363Y644630D01*
X723072Y654332D01*
X724241Y655147D01*
X726433Y654762D01*
X727250Y653596D01*
X725753Y645101D01*
X726117Y644581D01*
X727537Y644333D01*
X728057Y644697D01*
X729751Y654317D01*
X730919Y655134D01*
X733113Y654749D01*
X733928Y653580D01*
X732434Y645097D01*
X732798Y644576D01*
X734216Y644326D01*
X734736Y644691D01*
X736434Y654338D01*
X737602Y655153D01*
X739798Y654769D01*
X740613Y653602D01*
X739116Y645108D01*
X739481Y644589D01*
X740900Y644339D01*
X741420Y644703D01*
X743132Y654420D01*
X744300Y655237D01*
X746494Y654852D01*
X747309Y653683D01*
X745799Y645112D01*
X746163Y644591D01*
X747581Y644341D01*
X748101Y644705D01*
X749810Y654406D01*
X750978Y655223D01*
X753172Y654838D01*
X753989Y653672D01*
X752463Y645017D01*
X752828Y644497D01*
X754247Y644247D01*
X754767Y644610D01*
X756476Y654311D01*
X757641Y655127D01*
X759835Y654740D01*
X760651Y653574D01*
X759140Y645002D01*
X759505Y644479D01*
X760922Y644230D01*
X761445Y644596D01*
X763157Y654313D01*
X764323Y655129D01*
X766517Y654742D01*
X767333Y653578D01*
X765836Y645083D01*
X766200Y644562D01*
X767620Y644314D01*
X768143Y644679D01*
X769841Y654325D01*
X771006Y655141D01*
X773200Y654755D01*
X774016Y653589D01*
X772507Y645025D01*
X772872Y644502D01*
X774289Y644253D01*
X774812Y644619D01*
X776520Y654319D01*
X777686Y655135D01*
X779880Y654750D01*
X780696Y653585D01*
X779182Y644993D01*
X779547Y644472D01*
X780965Y644223D01*
X781488Y644588D01*
X783214Y654386D01*
X784379Y655201D01*
X786573Y654816D01*
X787389Y653651D01*
X785867Y645013D01*
X786232Y644492D01*
X787650Y644243D01*
X788173Y644609D01*
X789894Y654378D01*
X791072Y655203D01*
X793243Y654820D01*
X794072Y653641D01*
X792550Y645007D01*
X792915Y644486D01*
X794332Y644237D01*
X794855Y644603D01*
X796577Y654392D01*
X797746Y655209D01*
X799937Y654825D01*
X800754Y653659D01*
X799246Y645092D01*
X799609Y644572D01*
X801030Y644322D01*
X801550Y644686D01*
X803258Y654395D01*
X804427Y655212D01*
X806619Y654827D01*
X807435Y653660D01*
X805911Y645011D01*
X806287Y644476D01*
X807683Y644230D01*
X808216Y644603D01*
X809937Y654372D01*
X811105Y655189D01*
X813298Y654804D01*
X814115Y653638D01*
X812593Y645000D01*
X812957Y644480D01*
X814377Y644232D01*
X814896Y644595D01*
X816622Y654394D01*
X817791Y655209D01*
X819983Y654824D01*
X820800Y653658D01*
X819286Y645066D01*
X819650Y644546D01*
X821070Y644298D01*
X821590Y644662D01*
X823301Y654356D01*
X824469Y655173D01*
X826662Y654788D01*
X827477Y653619D01*
X825975Y645102D01*
X826340Y644580D01*
X827760Y644331D01*
X828280Y644695D01*
X829984Y654368D01*
X831153Y655185D01*
X833344Y654801D01*
X834161Y653635D01*
X832653Y645068D01*
X833016Y644548D01*
X834437Y644298D01*
X834957Y644662D01*
X836665Y654371D01*
X837834Y655188D01*
X840026Y654803D01*
X840842Y653636D01*
X839335Y645084D01*
X839711Y644549D01*
X841107Y644303D01*
X841640Y644676D01*
X843344Y654348D01*
X844512Y655165D01*
X846705Y654780D01*
X847522Y653614D01*
X846017Y645073D01*
X846381Y644553D01*
X847801Y644305D01*
X848320Y644668D01*
X850029Y654370D01*
X851198Y655185D01*
X853390Y654800D01*
X854207Y653634D01*
X852710Y645139D01*
X853074Y644619D01*
X854494Y644371D01*
X855014Y644735D01*
X856708Y654355D01*
X857876Y655172D01*
X860070Y654787D01*
X860885Y653618D01*
X859391Y645135D01*
X859755Y644614D01*
X861173Y644364D01*
X861693Y644729D01*
X863391Y654376D01*
X864559Y655191D01*
X866755Y654807D01*
X867570Y653640D01*
X866073Y645146D01*
X866438Y644627D01*
X867857Y644377D01*
X868377Y644741D01*
X870089Y654458D01*
X871257Y655275D01*
X873451Y654890D01*
X874266Y653721D01*
X872756Y645150D01*
X873120Y644629D01*
X874538Y644379D01*
X875058Y644743D01*
X876767Y654444D01*
X877935Y655261D01*
X880129Y654876D01*
X880946Y653710D01*
X879420Y645055D01*
X879785Y644535D01*
X881204Y644285D01*
X881724Y644648D01*
X882061Y646557D01*
X884204Y649193D01*
X889533Y650085D01*
X893882Y649748D01*
X895896D01*
X897391Y651243D01*
G01X671037Y176163D02*
X675261Y174686D01*
X722556Y165228D01*
X729233Y163640D01*
Y163641D01*
X735910Y162052D01*
X741458Y162422D01*
X749403Y157159D01*
X751927Y155551D01*
X758228Y152944D01*
X775251Y151182D01*
X801188Y156370D01*
X818224Y167728D01*
X891872Y182459D01*
X948529Y171127D01*
X976893Y176801D01*
X990174Y174144D01*
X990963Y172961D01*
X990191Y169100D01*
X990544Y168571D01*
X992849Y168109D01*
X993378Y168462D01*
X994150Y172323D01*
X995333Y173112D01*
X998416Y172494D01*
X999205Y171311D01*
X998433Y167450D01*
X998786Y166921D01*
X1001091Y166459D01*
X1001620Y166812D01*
X1002392Y170673D01*
X1003575Y171462D01*
X1025576Y167063D01*
X1102362Y182419D01*
X1129821Y180720D01*
X1142351Y188250D01*
X1142992Y189279D01*
X1143018Y189323D01*
X1148745Y196616D01*
X1148677Y197177D01*
X1149512Y198240D01*
X1150074Y198308D01*
X1150907Y199369D01*
Y199379D01*
X1150982Y199454D01*
G01X1135357Y204482D02*
X1130410Y199536D01*
X1130400Y199530D01*
X1127318Y197713D01*
X1125171Y197396D01*
X1123299Y197990D01*
X1122579Y198529D01*
X1122479Y199230D01*
X1121758Y199770D01*
X1121058Y199670D01*
X1120135Y200362D01*
X1120035Y201063D01*
X1119314Y201603D01*
X1118614Y201503D01*
X1116639Y202983D01*
X1109595Y204389D01*
X1107134Y203898D01*
X1100316Y199355D01*
X1099080Y199105D01*
X1097541Y200133D01*
X1094254Y199476D01*
X1092832Y197343D01*
X1090846Y196946D01*
X1089875Y197597D01*
X1086407Y196903D01*
X1085800Y195993D01*
X1082050Y195242D01*
X1081523Y195594D01*
X1080649Y199966D01*
X1079465Y200756D01*
X1076388Y200141D01*
X1075598Y198957D01*
X1076471Y194585D01*
X1076118Y194057D01*
X1070776Y192992D01*
X1070247Y193345D01*
X1069408Y197542D01*
X1068226Y198331D01*
X1065142Y197714D01*
X1064353Y196531D01*
X1065191Y192334D01*
X1064838Y191805D01*
X1062532Y191344D01*
X1062003Y191697D01*
X1061119Y196119D01*
X1060877Y197327D01*
X1059696Y198116D01*
X1056612Y197499D01*
X1055823Y196316D01*
X1056737Y191737D01*
X1056947Y190686D01*
X1056594Y190157D01*
X1054288Y189696D01*
X1053759Y190049D01*
X1052515Y196274D01*
X1051333Y197063D01*
X1048249Y196446D01*
X1047460Y195263D01*
X1048703Y189038D01*
X1048350Y188509D01*
X1047063Y188252D01*
X1046639Y188242D01*
X1043825Y189566D01*
X1039654Y192914D01*
X1039585Y193544D01*
X1040131Y194222D01*
X1039911Y196232D01*
X1038123Y197668D01*
X1036114Y197448D01*
X1035567Y196769D01*
X1034053Y196603D01*
X1031888Y198341D01*
X1029122Y199335D01*
X1011174Y195799D01*
X1007817Y197113D01*
X1003989Y197077D01*
X986539Y191686D01*
X982119Y192139D01*
X981681Y192677D01*
X980785Y192769D01*
X980247Y192331D01*
X977184Y192645D01*
X949621Y187255D01*
X928744Y191430D01*
X895819Y198936D01*
X875578Y194888D01*
X815401Y182853D01*
X791605Y166989D01*
X780941Y164856D01*
X771931Y168737D01*
X754591Y180331D01*
X727302Y180122D01*
X682314Y189118D01*
X671372Y193310D01*
X671371D01*
G01X707550Y223500D02*
X705500D01*
G01X693500Y305500D02*
X695611Y303389D01*
X696398D01*
X697120Y304111D01*
Y305349D01*
G01Y300349D02*
Y301659D01*
X696340Y302439D01*
X695439D01*
X693500Y300500D01*
G01X693920Y325500D02*
X695821Y323599D01*
X696571D01*
X697521Y324549D01*
Y325500D01*
G01X693920Y320500D02*
X695819Y322399D01*
X696697D01*
X697521Y321575D01*
Y320500D01*
G01X669000Y345500D02*
X670132D01*
X670954Y346322D01*
Y349446D01*
X669194Y351206D01*
G01X674000Y345500D02*
X672766D01*
X671904Y346362D01*
Y348916D01*
X674194Y351206D01*
G01X774490Y369520D02*
X775857Y370887D01*
X775987D01*
X777100Y372000D01*
G01X1102000Y-42431D02*
X914200D01*
G03Y-46181I0J-1875D01*
G01X1103500D01*
G02Y-51831I0J-2825D01*
G01X910187D01*
X905888Y-47532D01*
X903509D01*
X898984Y-52057D01*
G01X1102000Y-41481D02*
X914200D01*
G03Y-47131I0J-2825D01*
G01X1103499D01*
G02Y-50881I0J-1875D01*
G01X910581D01*
X906282Y-46582D01*
X903509D01*
X898984Y-42057D01*
G01X937076Y647236D02*
X938499Y648659D01*
X939458D01*
X941883Y646234D01*
G01X937076Y651176D02*
X938443Y649809D01*
X939458D01*
X941883Y652234D01*
G01X1027202Y-11005D02*
Y-11002D01*
X1027021Y-10821D01*
Y-8361D01*
G01X1224391Y365477D02*
X1224229Y359229D01*
X1223837Y344087D01*
X1223782Y341961D01*
X1223071Y338885D01*
X1219282Y322500D01*
X1217473Y314680D01*
X1217261Y314300D01*
X1216782Y313440D01*
X1210837Y307493D01*
G01X1229071Y340046D02*
X1229014Y337836D01*
X1223866Y315136D01*
X1223400Y314300D01*
X1219688Y307643D01*
X1213589Y302949D01*
X1212788D01*
G01X1246438Y366646D02*
X1245281Y322107D01*
X1245279Y322106D01*
X1245203Y319128D01*
X1244198Y317324D01*
X1243530Y317134D01*
X1243043Y316260D01*
X1243233Y315593D01*
X1230400Y292567D01*
X1217765Y287950D01*
X1214506D01*
X1213700Y287144D01*
G01X1228715Y362963D02*
X1228120Y340070D01*
X1228066Y337955D01*
X1225428Y326327D01*
X1224879Y325982D01*
X1224678Y325102D01*
X1225027Y324552D01*
X1224827Y323673D01*
X1224277Y323328D01*
X1224088Y322500D01*
X1224076Y322448D01*
X1224425Y321898D01*
X1224225Y321019D01*
X1223675Y320674D01*
X1223474Y319794D01*
X1223823Y319244D01*
X1223624Y318369D01*
X1223623Y318365D01*
X1223073Y318020D01*
X1222872Y317140D01*
X1223221Y316590D01*
X1222969Y315480D01*
X1218953Y308277D01*
X1213265Y303899D01*
X1212788D01*
G01X1242459Y344788D02*
X1242047Y328923D01*
X1239255Y315443D01*
X1228093Y295423D01*
X1216265Y291100D01*
X1213400D01*
X1211836Y289568D01*
G01X1250110Y336170D02*
X1249640Y318051D01*
X1233481Y289061D01*
X1221480Y284436D01*
G01X1217078Y295811D02*
X1219166Y296824D01*
X1220954Y297461D01*
X1226723Y302137D01*
X1227913Y304273D01*
X1233501Y314300D01*
X1234113Y315399D01*
X1235635Y322500D01*
X1237743Y332336D01*
X1238475Y360530D01*
G01X1223453Y336318D02*
X1220257Y322500D01*
X1218369Y314335D01*
X1218350Y314300D01*
X1217548Y312861D01*
X1211509Y306821D01*
G01X1212528Y299769D02*
X1213460D01*
X1213463Y299770D01*
X1213464Y299769D01*
X1213762D01*
X1214061Y299771D01*
X1222597Y305751D01*
X1227362Y314300D01*
X1227827Y315135D01*
X1228033Y316043D01*
X1228036Y316055D01*
X1227691Y316605D01*
X1227896Y317484D01*
X1228447Y317825D01*
X1228652Y318702D01*
X1228309Y319251D01*
X1228514Y320130D01*
X1229065Y320471D01*
X1229270Y321348D01*
X1228927Y321897D01*
X1229068Y322500D01*
X1229132Y322776D01*
X1229683Y323117D01*
X1229888Y323994D01*
X1229545Y324543D01*
X1229750Y325422D01*
X1230301Y325763D01*
X1230506Y326640D01*
X1230163Y327189D01*
X1230368Y328068D01*
X1230919Y328409D01*
X1231124Y329286D01*
X1230781Y329835D01*
X1230986Y330714D01*
X1231537Y331055D01*
X1231742Y331932D01*
X1231399Y332481D01*
X1231604Y333360D01*
X1232155Y333701D01*
X1232424Y334849D01*
X1232900Y353150D01*
X1233239Y366212D01*
G01X1216663Y296666D02*
X1218798Y297702D01*
X1219640Y298002D01*
X1219641D01*
X1220482Y298302D01*
X1225982Y302760D01*
X1232412Y314300D01*
X1233213Y315738D01*
X1233566Y317383D01*
X1233205Y317939D01*
X1233395Y318821D01*
X1233952Y319181D01*
X1234142Y320063D01*
X1233781Y320619D01*
X1233971Y321501D01*
X1234528Y321861D01*
X1234666Y322500D01*
X1234718Y322743D01*
X1234357Y323299D01*
X1234547Y324181D01*
X1235104Y324541D01*
X1235294Y325423D01*
X1234933Y325979D01*
X1235123Y326861D01*
X1235680Y327221D01*
X1235870Y328103D01*
X1235509Y328659D01*
X1235699Y329541D01*
X1236247Y329896D01*
X1236795Y332449D01*
X1236921Y337307D01*
G01X1210917Y647292D02*
X1209578Y648631D01*
X1208535D01*
X1206110Y646206D01*
G01X1210917Y651232D02*
X1209466Y649781D01*
X1208535D01*
X1206110Y652206D01*
G01X1250574Y647266D02*
X1251997Y648689D01*
X1252956D01*
X1255381Y646264D01*
G01X1250574Y651206D02*
X1251941Y649839D01*
X1252956D01*
X1255381Y652264D01*
G01X1319247Y266720D02*
Y249754D01*
X1316090Y246597D01*
Y242970D01*
X1317889Y241171D01*
G01X1322260Y282730D02*
X1320980Y281450D01*
Y278809D01*
X1319247Y277076D01*
Y266720D01*
G01X1324460Y260962D02*
Y274845D01*
X1325750Y276135D01*
Y278170D01*
X1327243Y279663D01*
G01X1328889Y241171D02*
Y242511D01*
X1326693Y244707D01*
Y247807D01*
X1324460Y250040D01*
Y260962D01*
G01X1329815Y255507D02*
Y253487D01*
X1337712Y245590D01*
Y243348D01*
X1339889Y241171D01*
G01X1333680Y276035D02*
X1332200Y274555D01*
Y270800D01*
X1329815Y268415D01*
Y255507D01*
G01X1346683Y251175D02*
X1338801Y259057D01*
Y270308D01*
X1340248Y271755D01*
G01X1318297Y255241D02*
Y250148D01*
X1315140Y246991D01*
Y243922D01*
X1312389Y241171D01*
G01X1318751Y282730D02*
X1320030Y281451D01*
Y279203D01*
X1318297Y277470D01*
Y255241D01*
G01X1323510Y272768D02*
Y275239D01*
X1324800Y276529D01*
Y278597D01*
X1323734Y279663D01*
G01X1323389Y241171D02*
Y242289D01*
X1325743Y244643D01*
Y247413D01*
X1323510Y249646D01*
Y272768D01*
G01X1328865Y266711D02*
Y253093D01*
X1336762Y245196D01*
Y243544D01*
X1334389Y241171D01*
G01X1330171Y276035D02*
X1331253Y274952D01*
X1331250Y274949D01*
Y271194D01*
X1328865Y268809D01*
Y266711D01*
G01X1339862Y256652D02*
X1347723Y248791D01*
Y243505D01*
X1345389Y241171D01*
G01X1336448Y271755D02*
X1337851Y270352D01*
Y258663D01*
X1339862Y256652D01*
G01X1320289Y237671D02*
X1317889D01*
G01X1328889D02*
X1331171D01*
X1331400Y237900D01*
G01X1339889Y237671D02*
X1342171D01*
X1342400Y237900D01*
G01X1312389Y237671D02*
X1315000D01*
Y237645D01*
X1315100D01*
G01X1323389Y237671D02*
X1325671D01*
X1325900Y237900D01*
G01X1334389Y237671D02*
X1336671D01*
X1336900Y237900D01*
G01X1317889Y234171D02*
X1318347D01*
X1320400Y232118D01*
G01X1328889Y234171D02*
X1329347D01*
X1331400Y232118D01*
G01X1339889Y234171D02*
X1340347D01*
X1342400Y232118D01*
G01X1312389Y234171D02*
X1312847D01*
X1314900Y232118D01*
G01X1323389Y234171D02*
X1323847D01*
X1325900Y232118D01*
G01X1334389Y234171D02*
X1334847D01*
X1336900Y232118D01*
G01X1341375Y314675D02*
Y316369D01*
X1340924Y316820D01*
X1339030D01*
X1336900Y314690D01*
Y312150D01*
X1337390Y311660D01*
X1338790D01*
X1339240Y311210D01*
Y309384D01*
G01X1341375Y319675D02*
Y318524D01*
X1340621Y317770D01*
X1338636D01*
X1335950Y315084D01*
Y312150D01*
X1333740Y309940D01*
Y309384D01*
G01X1339240Y305884D02*
X1340890D01*
X1341740Y306734D01*
Y306760D01*
G01X1333740Y305884D02*
X1335390D01*
X1336240Y306734D01*
Y306760D01*
G01X1339240Y302384D02*
X1340599D01*
X1341740Y301243D01*
G01X1333740Y302384D02*
X1335099D01*
X1336240Y301243D01*
G01X1337600Y438600D02*
X1339000D01*
X1340100Y437500D01*
Y432500D01*
G01X1332075Y438600D02*
X1337600D01*
G01X1350889Y241171D02*
X1348673Y243387D01*
Y249185D01*
X1346683Y251175D01*
G01X1353668Y255112D02*
X1359673Y249107D01*
Y243387D01*
X1361889Y241171D01*
G01X1347468Y268095D02*
X1346055Y266682D01*
Y262725D01*
X1353668Y255112D01*
G01X1368828Y247672D02*
X1370573Y245927D01*
Y243487D01*
X1372889Y241171D01*
G01X1356268Y265695D02*
X1354843Y264270D01*
Y261657D01*
X1368828Y247672D01*
G01X1371834Y263088D02*
X1365651Y256905D01*
Y256269D01*
X1367434Y254486D01*
X1368070D01*
X1371148Y257564D01*
X1372570D01*
X1374914Y255220D01*
Y253798D01*
X1371836Y250720D01*
Y250084D01*
X1373619Y248301D01*
X1374255D01*
X1377642Y251688D01*
X1379064D01*
X1382233Y248519D01*
Y242827D01*
X1383889Y241171D01*
G01X1362803Y265525D02*
X1363678Y266400D01*
Y268678D01*
X1365040Y270040D01*
X1370143D01*
X1373010Y267173D01*
Y264264D01*
X1371834Y263088D01*
G01X1382472Y256172D02*
X1392423Y246221D01*
Y243637D01*
X1394889Y241171D01*
G01X1381031Y265600D02*
X1379752Y264321D01*
Y258892D01*
X1382472Y256172D01*
G01X1346640Y260796D02*
X1358723Y248713D01*
Y243505D01*
X1356389Y241171D01*
G01X1343668Y268095D02*
X1345105Y266658D01*
Y262331D01*
X1346640Y260796D01*
G01X1362848Y252308D02*
X1353893Y261263D01*
Y264270D01*
X1352468Y265695D01*
G01X1367389Y241171D02*
X1369623Y243405D01*
Y245533D01*
X1362848Y252308D01*
G01X1366331Y258929D02*
X1364701Y257299D01*
Y255875D01*
X1367040Y253536D01*
X1368464D01*
X1371542Y256614D01*
X1372176D01*
X1373964Y254826D01*
Y254192D01*
X1370886Y251114D01*
Y249690D01*
X1373225Y247351D01*
X1374649D01*
X1378036Y250738D01*
X1378670D01*
X1381283Y248125D01*
Y247235D01*
X1380833Y246785D01*
Y245435D01*
X1381283Y244985D01*
Y243277D01*
X1380833Y242827D01*
X1380045D01*
X1378389Y241171D01*
G01X1366331Y258929D02*
X1372060Y264658D01*
Y266779D01*
X1369749Y269090D01*
X1368834D01*
X1368384Y268640D01*
X1367034D01*
X1366584Y269090D01*
X1365434D01*
X1364628Y268284D01*
Y265911D01*
X1365014Y265525D01*
X1366312D01*
G01X1387012Y250288D02*
X1391473Y245827D01*
Y243255D01*
X1389389Y241171D01*
G01X1377522Y265600D02*
X1378802Y264320D01*
Y258498D01*
X1387012Y250288D01*
G01X1350889Y237671D02*
X1353171D01*
X1353400Y237900D01*
G01X1361889Y237671D02*
X1364171D01*
X1364400Y237900D01*
G01X1372889Y237671D02*
X1375171D01*
X1375400Y237900D01*
G01X1383889Y237671D02*
X1386171D01*
X1386400Y237900D01*
G01X1394889Y237671D02*
X1397171D01*
X1397400Y237900D01*
G01X1345389Y237671D02*
X1347671D01*
X1347900Y237900D01*
G01X1356389Y237671D02*
X1358671D01*
X1358900Y237900D01*
G01X1367389Y237671D02*
X1369671D01*
X1369900Y237900D01*
G01X1378389Y237671D02*
X1380671D01*
X1380900Y237900D01*
G01X1389389Y237671D02*
X1391671D01*
X1391900Y237900D01*
G01X1353400Y232118D02*
X1351347Y234171D01*
X1350889D01*
G01X1361889D02*
X1362347D01*
X1364400Y232118D01*
G01X1372889Y234171D02*
X1374942Y232118D01*
X1375400D01*
G01X1383889Y234171D02*
X1384347D01*
X1386400Y232118D01*
G01X1394889Y234171D02*
X1395347D01*
X1397400Y232118D01*
G01X1345389Y234171D02*
X1345847D01*
X1347900Y232118D01*
G01X1356389Y234171D02*
X1356847D01*
X1358900Y232118D01*
G01X1367389Y234171D02*
X1367847D01*
X1369900Y232118D01*
G01X1378389Y234171D02*
X1378847D01*
X1380900Y232118D01*
G01X1389389Y234171D02*
X1389847D01*
X1391900Y232118D01*
G01X1349134Y317436D02*
X1347755Y318815D01*
X1347200D01*
X1346750Y318365D01*
Y312140D01*
X1347200Y311690D01*
X1348790D01*
X1348800Y311700D01*
X1350642Y309858D01*
Y309384D01*
G01X1360294Y315025D02*
X1358928Y316391D01*
X1358291D01*
X1357440Y315540D01*
Y312320D01*
X1357930Y311830D01*
X1359366D01*
X1361544Y309652D01*
Y309384D01*
G01X1371090Y315395D02*
X1370065Y316420D01*
X1367851D01*
X1367010Y315579D01*
Y312694D01*
X1367536Y312168D01*
X1370194D01*
X1372340Y310022D01*
Y309754D01*
G01X1380904Y315947D02*
X1379546Y317305D01*
X1379215D01*
X1378750Y316840D01*
Y313250D01*
X1379200Y312800D01*
X1381100D01*
X1383548Y310352D01*
Y309934D01*
G01X1392226Y315658D02*
X1390734Y317150D01*
X1388210D01*
X1387760Y316700D01*
Y313680D01*
X1388430Y313010D01*
X1390385D01*
X1390945Y312450D01*
X1393097D01*
X1395135Y310412D01*
Y310254D01*
G01X1400558Y320157D02*
X1401943Y318772D01*
X1403472D01*
X1404878Y317366D01*
Y312413D01*
X1406037Y311254D01*
Y310254D01*
G01X1345142Y309384D02*
X1345800Y310042D01*
Y311559D01*
X1345350Y312009D01*
Y313359D01*
X1345800Y313809D01*
Y315159D01*
X1345350Y315609D01*
Y316959D01*
X1345800Y317409D01*
Y318759D01*
X1346806Y319765D01*
X1347754D01*
X1349134Y321145D01*
G01X1360294Y318825D02*
X1358810Y317341D01*
X1357897D01*
X1356490Y315934D01*
Y315044D01*
X1356040Y314594D01*
Y313244D01*
X1356490Y312794D01*
Y311926D01*
X1356974Y311442D01*
Y310764D01*
X1356044Y309834D01*
Y309384D01*
G01X1366840Y309754D02*
Y311520D01*
X1366060Y312300D01*
Y312803D01*
X1365610Y313253D01*
Y314603D01*
X1366060Y315053D01*
Y315973D01*
X1367457Y317370D01*
X1370620D01*
X1371090Y317840D01*
Y319195D01*
G01X1380904Y319747D02*
X1379412Y318255D01*
X1378821D01*
X1377800Y317234D01*
Y316349D01*
X1377350Y315899D01*
Y314549D01*
X1377800Y314099D01*
Y312856D01*
X1378814Y311842D01*
Y311204D01*
X1378048Y310438D01*
Y309934D01*
G01X1392226Y319458D02*
Y318644D01*
X1391682Y318100D01*
X1387816D01*
X1386810Y317094D01*
Y316057D01*
X1386360Y315607D01*
Y314257D01*
X1386810Y313807D01*
Y313286D01*
X1388036Y312060D01*
X1389991D01*
X1390310Y311741D01*
Y310929D01*
X1389635Y310254D01*
G01X1400558Y316357D02*
X1402023Y317822D01*
X1403078D01*
X1403928Y316972D01*
Y313480D01*
X1402888Y312440D01*
X1401500D01*
X1400537Y311477D01*
Y310254D01*
G01X1353142Y306760D02*
Y306734D01*
X1352292Y305884D01*
X1350642D01*
G01X1361544D02*
X1363238D01*
X1364044Y306690D01*
G01X1372340Y306254D02*
X1373990D01*
X1374840Y307104D01*
Y307130D01*
G01X1383548Y306434D02*
X1385198D01*
X1386048Y307284D01*
Y307310D01*
G01X1395135Y306754D02*
X1396785D01*
X1397635Y307604D01*
Y307630D01*
G01X1345142Y305884D02*
X1346792D01*
X1347642Y306734D01*
Y306760D01*
G01X1356044Y305884D02*
X1357764D01*
X1358544Y306664D01*
Y306690D01*
G01X1366840Y306254D02*
X1368490D01*
X1369340Y307104D01*
Y307130D01*
G01X1378048Y306434D02*
X1379698D01*
X1380548Y307284D01*
Y307310D01*
G01X1389635Y306754D02*
X1391285D01*
X1392135Y307604D01*
Y307630D01*
G01X1400537Y306754D02*
X1402187D01*
X1403037Y307604D01*
Y307630D01*
G01X1353672Y299605D02*
Y300653D01*
X1351941Y302384D01*
X1350642D01*
G01X1361544D02*
X1362772D01*
X1364014Y301142D01*
Y300815D01*
G01X1372340Y302754D02*
X1373806D01*
X1374820Y301740D01*
Y301219D01*
G01X1383548Y302934D02*
X1384632D01*
X1386101Y301465D01*
G01X1395135Y303254D02*
X1396432D01*
X1397635Y302051D01*
G01X1347892Y299741D02*
Y300933D01*
X1346441Y302384D01*
X1345142D01*
G01X1358514Y300815D02*
Y301384D01*
X1357514Y302384D01*
X1356044D01*
G01X1369320Y301219D02*
Y301562D01*
X1368128Y302754D01*
X1366840D01*
G01X1380601Y301465D02*
X1379132Y302934D01*
X1378048D01*
G01X1392135Y302051D02*
X1390932Y303254D01*
X1389635D01*
G01X1400537D02*
X1401829D01*
X1403037Y302046D01*
G01X1378550Y344550D02*
X1377513Y343513D01*
X1373950D01*
G01X1381800Y347518D02*
X1380650D01*
X1380200Y347068D01*
Y346200D01*
X1378550Y344550D01*
G01X1382400Y353803D02*
X1380313D01*
X1378880Y352370D01*
G01D02*
X1377519Y351009D01*
Y350497D01*
X1375259Y348237D01*
X1373950D01*
G01X1380741Y487489D02*
Y487395D01*
X1382563Y485573D01*
X1391441D01*
X1392341Y486473D01*
Y487323D01*
G01X1372441Y482123D02*
Y483233D01*
X1371876Y483798D01*
X1362988D01*
X1360863Y481673D01*
G01X1362841Y492823D02*
X1364716Y494698D01*
X1374090D01*
X1374541Y494247D01*
Y493023D01*
G01X1383263Y493673D02*
X1385488Y495898D01*
X1394198D01*
X1394841Y495255D01*
Y494223D01*
G01X1381041Y482575D02*
X1383089Y484623D01*
X1391593D01*
X1392341Y483875D01*
Y482923D01*
G01X1360741Y486523D02*
X1362516Y484748D01*
X1371890D01*
X1372341Y485199D01*
Y486523D01*
G01X1374541Y497423D02*
Y496099D01*
X1374090Y495648D01*
X1364788D01*
X1362880Y497556D01*
G01X1394841Y498523D02*
Y497299D01*
X1394390Y496848D01*
X1385094D01*
X1385069Y496823D01*
X1385013D01*
X1383241Y498595D01*
G01X1402430Y483176D02*
X1405334Y481268D01*
X1407736Y474602D01*
X1433716Y467231D01*
X1442371Y468831D01*
X1447432Y467688D01*
X1456079Y469244D01*
X1462947Y467933D01*
X1468593Y469289D01*
X1469343D01*
G01X1395841Y487323D02*
X1397741Y485423D01*
X1399010D01*
X1402430Y483176D01*
G01X1395841Y482923D02*
X1397391Y484473D01*
X1398725D01*
X1401907Y482381D01*
X1404547Y480647D01*
X1407007Y473820D01*
X1410808Y472742D01*
G01X1435500Y462230D02*
X1432198D01*
X1379395Y477594D01*
X1377958Y480117D01*
Y483142D01*
X1377289Y483811D01*
X1376417D01*
X1375941Y483335D01*
Y482123D01*
G01X1448000Y463180D02*
X1432334D01*
X1380030Y478399D01*
X1378908Y480369D01*
Y483536D01*
X1377683Y484761D01*
X1376317D01*
X1375841Y485237D01*
Y486523D01*
G01X1378041Y493023D02*
Y494334D01*
X1378492Y494785D01*
X1379389D01*
X1380300Y493874D01*
Y491820D01*
X1381886Y490234D01*
X1405076D01*
X1412354Y497512D01*
X1449941Y505944D01*
X1458388Y503874D01*
X1462112Y500150D01*
X1465206D01*
X1467721Y497635D01*
X1474371D01*
X1476206Y495800D01*
X1479303D01*
G01X1378041Y497423D02*
Y496185D01*
X1378491Y495735D01*
X1379783D01*
X1381250Y494268D01*
Y492214D01*
X1382280Y491184D01*
X1404682D01*
X1411877Y498379D01*
X1449951Y506920D01*
X1458872Y504734D01*
X1462506Y501100D01*
X1465600D01*
X1468115Y498585D01*
X1471829D01*
G01X1398341Y494223D02*
X1400016Y495898D01*
X1405148D01*
X1410369Y501119D01*
X1449981Y510005D01*
X1460718Y507374D01*
X1463592Y504500D01*
X1466355D01*
X1469417Y501438D01*
X1479300D01*
G01X1398341Y498523D02*
X1400016Y496848D01*
X1404754D01*
X1409892Y501986D01*
X1410161Y502047D01*
Y502046D01*
X1449991Y510981D01*
X1461202Y508234D01*
X1463986Y505450D01*
X1466749D01*
X1469811Y502388D01*
X1487200D01*
G01X1449933Y49950D02*
X1440806D01*
X1429750Y38894D01*
Y33094D01*
X1424756Y28100D01*
X1414144D01*
X1409521Y32723D01*
Y42666D01*
X1409971Y43116D01*
X1411546D01*
G01X1469689Y49000D02*
X1441200D01*
X1430700Y38500D01*
Y32700D01*
X1425150Y27150D01*
X1413750D01*
X1408571Y32329D01*
Y42666D01*
X1408121Y43116D01*
X1406546D01*
G01X1558100Y138025D02*
X1556275Y136200D01*
X1550456D01*
X1547758Y133502D01*
X1547122D01*
X1546167Y132547D01*
Y131911D01*
X1544677Y130421D01*
X1540877D01*
X1537406Y126950D01*
X1533697D01*
X1533247Y127400D01*
X1531897D01*
X1531447Y126950D01*
X1530097D01*
X1529647Y127400D01*
X1528297D01*
X1527847Y126950D01*
X1522606D01*
X1519857Y124201D01*
X1508557D01*
X1503850Y119494D01*
Y97559D01*
X1503400Y97109D01*
Y95759D01*
X1503850Y95309D01*
Y93959D01*
X1503400Y93509D01*
Y92159D01*
X1503850Y91709D01*
Y77894D01*
X1475906Y49950D01*
X1449933D01*
G01X1411220Y310284D02*
Y311166D01*
X1412289Y312235D01*
Y312871D01*
X1411970Y313190D01*
X1409465D01*
X1407759Y314896D01*
Y317248D01*
X1409425Y318914D01*
X1412268D01*
X1413387Y320033D01*
G01X1416720Y310284D02*
Y310480D01*
X1413060Y314140D01*
X1409859D01*
X1408709Y315290D01*
Y316854D01*
X1409819Y317964D01*
X1411656D01*
X1413387Y316233D01*
G01X1406037Y306754D02*
X1407687D01*
X1408537Y307604D01*
Y307630D01*
G01X1411220Y306784D02*
X1412870D01*
X1413720Y307634D01*
G01X1416720Y306784D02*
X1418519D01*
X1419333Y307598D01*
G01X1406037Y303254D02*
X1407329D01*
X1408537Y302046D01*
G01X1411220Y303284D02*
X1412419D01*
X1413720Y301983D01*
G01X1419220D02*
X1417919Y303284D01*
X1416720D01*
G01X1420075Y388402D02*
Y389977D01*
X1420709Y390611D01*
X1422535D01*
X1423566Y391427D01*
X1423660Y391614D01*
Y391615D01*
X1424557Y393400D01*
X1423504Y398666D01*
X1422191Y405229D01*
X1424207Y415888D01*
X1423689Y418958D01*
X1421398Y432544D01*
X1423957Y440669D01*
X1428118Y444830D01*
X1450453D01*
X1451000Y444283D01*
Y442500D01*
G01X1435500Y448000D02*
Y449825D01*
X1435050Y450275D01*
X1428012D01*
X1421267Y445103D01*
X1416846Y432267D01*
X1419507Y418960D01*
X1420100Y415997D01*
X1417694Y403967D01*
X1417983Y402523D01*
X1418688Y398999D01*
X1418592Y398666D01*
X1417983Y396553D01*
X1417920Y396334D01*
X1415600Y393329D01*
X1414513D01*
X1413735Y392551D01*
Y391302D01*
G01X1435500Y442500D02*
Y440775D01*
X1435050Y440325D01*
X1427988D01*
X1426755Y439093D01*
X1426098Y437705D01*
X1424655Y430490D01*
X1427582Y415855D01*
X1425446Y405176D01*
X1426748Y398666D01*
X1428302Y390898D01*
X1424316Y382796D01*
X1421994Y381350D01*
X1420525D01*
X1420075Y381800D01*
Y383375D01*
G01X1420515Y368585D02*
Y369950D01*
X1421180Y370615D01*
X1423339D01*
X1431980Y383576D01*
X1433511Y391232D01*
X1432024Y398666D01*
X1430521Y406178D01*
X1432707Y417107D01*
X1431595Y422663D01*
G01X1420075Y393402D02*
Y391942D01*
X1420456Y391561D01*
X1422204D01*
X1422811Y392042D01*
X1423561Y393534D01*
X1422535Y398666D01*
X1421223Y405224D01*
X1423241Y415898D01*
X1422725Y418958D01*
X1420423Y432611D01*
X1423120Y441177D01*
X1427724Y445780D01*
X1450589D01*
X1451000Y446191D01*
Y448000D01*
G01X1435500Y453500D02*
Y451675D01*
X1435050Y451225D01*
X1427689D01*
X1420461Y445683D01*
X1415863Y432333D01*
X1417983Y421735D01*
X1418538Y418960D01*
X1419131Y415997D01*
X1416725Y403967D01*
X1417710Y399040D01*
X1417602Y398666D01*
X1417057Y396771D01*
X1415133Y394279D01*
X1414471D01*
X1413735Y395015D01*
Y396302D01*
G01X1420075Y378375D02*
Y379950D01*
X1420525Y380400D01*
X1422266D01*
X1425049Y382133D01*
X1425169Y382376D01*
Y382377D01*
X1429297Y390768D01*
X1427717Y398666D01*
X1426415Y405176D01*
X1428551Y415855D01*
X1425624Y430490D01*
X1427014Y437438D01*
X1427027Y437446D01*
X1427544Y438537D01*
X1428382Y439375D01*
X1434950D01*
X1435500Y438825D01*
Y437000D01*
G01X1420515Y373585D02*
Y372259D01*
X1421209Y371565D01*
X1422830D01*
X1431085Y383947D01*
X1432542Y391232D01*
X1431055Y398666D01*
X1429552Y406178D01*
X1431738Y417107D01*
X1430321Y424183D01*
X1430158Y425002D01*
X1431034Y429384D01*
X1433473Y433041D01*
X1443127Y434725D01*
X1450550D01*
X1451000Y435175D01*
Y437000D01*
G01X1431595Y422663D02*
X1431253Y424370D01*
X1431127Y425002D01*
X1431929Y429013D01*
X1434038Y432175D01*
X1443210Y433775D01*
X1450550D01*
X1451000Y433325D01*
Y431500D01*
G01X1470768Y446550D02*
X1460826D01*
X1456601Y444800D01*
X1454999D01*
X1454500Y444301D01*
Y442500D01*
G01X1442169Y450250D02*
X1439500D01*
X1439000Y449750D01*
Y448000D01*
G01X1448300Y451572D02*
X1447169D01*
X1443977Y450250D01*
X1442169D01*
G01X1464704Y443284D02*
X1463406D01*
X1460372Y440250D01*
X1442646D01*
G01X1439000Y442500D02*
Y440750D01*
X1439500Y440250D01*
X1442646D01*
G01X1454500Y431500D02*
Y433388D01*
X1455043Y433931D01*
X1456208D01*
X1458845Y435023D01*
X1475523D01*
X1478500Y438000D01*
Y439713D01*
G01X1472100Y447500D02*
X1460637D01*
X1458271Y446520D01*
G01D02*
X1456412Y445750D01*
X1454950D01*
X1454500Y446200D01*
Y448000D01*
G01X1439000Y453500D02*
Y451600D01*
X1439400Y451200D01*
X1443788D01*
X1446980Y452522D01*
X1448300D01*
G01X1458100Y439300D02*
X1460766D01*
X1463800Y442334D01*
X1464704D01*
G01X1439000Y437000D02*
Y438708D01*
X1439592Y439300D01*
X1458100D01*
G01X1476265Y437109D02*
X1475129Y435973D01*
X1474195D01*
X1473966Y436202D01*
Y436203D01*
X1473737Y436432D01*
X1472387D01*
X1472158Y436203D01*
Y436202D01*
X1471929Y435973D01*
X1470579D01*
X1470350Y436202D01*
Y436203D01*
X1470121Y436432D01*
X1468771D01*
X1468542Y436203D01*
Y436202D01*
X1468313Y435973D01*
X1466963D01*
X1466734Y436202D01*
Y436203D01*
X1466505Y436432D01*
X1465155D01*
X1464926Y436203D01*
Y436202D01*
X1464697Y435973D01*
X1463347D01*
X1463118Y436202D01*
Y436203D01*
X1462889Y436432D01*
X1461539D01*
X1461310Y436203D01*
Y436202D01*
X1461081Y435973D01*
X1458656D01*
X1456019Y434881D01*
X1454819D01*
X1454500Y435200D01*
Y437000D01*
G01X1435500Y462230D02*
X1457666D01*
G01X1448000Y463180D02*
X1457666D01*
G01X1424341Y489923D02*
Y490705D01*
X1423452Y491594D01*
X1415012D01*
X1412941Y489523D01*
G01X1424514Y482323D02*
Y481629D01*
X1423483Y480598D01*
X1415127D01*
X1413193Y482532D01*
G01X1448114Y482523D02*
Y481474D01*
X1447442Y480802D01*
X1438698D01*
X1436600Y482900D01*
G01X1448141Y494123D02*
Y493023D01*
X1447541Y492423D01*
X1438141D01*
X1436541Y494023D01*
Y494423D01*
G01X1424341Y494323D02*
Y493429D01*
X1423456Y492544D01*
X1414420D01*
X1412741Y494223D01*
G01X1424514Y477923D02*
Y478660D01*
X1423526Y479648D01*
X1415266D01*
X1413041Y477423D01*
G01X1448114Y478123D02*
Y479166D01*
X1447428Y479852D01*
X1438557D01*
X1436396Y477691D01*
G01X1448141Y489723D02*
Y490723D01*
X1447391Y491473D01*
X1438591D01*
X1436441Y489323D01*
G01X1427841Y489923D02*
X1429566Y491648D01*
X1432031D01*
X1433371Y492988D01*
Y495137D01*
X1436934Y498700D01*
X1447168D01*
X1447618Y498250D01*
X1448968D01*
X1449418Y498700D01*
X1457814D01*
X1460496Y496018D01*
X1463851D01*
X1467449Y492420D01*
X1484200D01*
G01X1474488Y493370D02*
X1467843D01*
X1464245Y496968D01*
X1460890D01*
X1458208Y499650D01*
X1436540D01*
X1432421Y495531D01*
Y493382D01*
X1431637Y492598D01*
X1429566D01*
X1427841Y494323D01*
G01X1446392Y472057D02*
X1447709Y471813D01*
X1462764Y475049D01*
X1468822D01*
G01X1428014Y482323D02*
X1429739Y480598D01*
X1431352D01*
X1432591Y479359D01*
Y476757D01*
X1436701Y473852D01*
X1437044Y473788D01*
X1446392Y472057D01*
G01X1438283Y472592D02*
X1447723Y470844D01*
X1462866Y474099D01*
X1468822D01*
G01X1438283Y472592D02*
X1436325Y472955D01*
X1436323D01*
X1431641Y476265D01*
Y478965D01*
X1430958Y479648D01*
X1429739D01*
X1428014Y477923D01*
G01X1410808Y472742D02*
X1433671Y466256D01*
X1442352Y467861D01*
X1447411Y466718D01*
X1456074Y468277D01*
X1462970Y466961D01*
X1468706Y468339D01*
X1469343D01*
G01X1467570Y481702D02*
X1464626Y480873D01*
X1462948D01*
X1462498Y481323D01*
X1461098D01*
X1460648Y480873D01*
X1453264D01*
X1451614Y482523D01*
G01X1451641Y494123D02*
X1453199Y492565D01*
X1462835D01*
X1464645Y490755D01*
Y489420D01*
X1465593Y488472D01*
X1473172D01*
X1473700Y489000D01*
X1477353D01*
G01X1473246Y482312D02*
X1464759Y479923D01*
X1453414D01*
X1451614Y478123D01*
G01X1451641Y489723D02*
X1453533Y491615D01*
X1462441D01*
X1463695Y490361D01*
Y489026D01*
X1465199Y487522D01*
X1473566D01*
X1474094Y488050D01*
X1475483D01*
G01X1420841Y489923D02*
X1418641D01*
X1418241Y489523D01*
G01X1421014Y482323D02*
X1418641D01*
X1418441Y482523D01*
G01X1444641Y494123D02*
X1442341D01*
X1442041Y494423D01*
G01X1420841Y494323D02*
X1418441D01*
X1418341Y494423D01*
G01X1421014Y477923D02*
X1418941D01*
X1418341Y477323D01*
G01X1444641Y489723D02*
X1442541D01*
X1442041Y489223D01*
G01X1513335Y92921D02*
X1514390Y93976D01*
X1516606D01*
G01X1520106D02*
X1521731Y95601D01*
X1524408D01*
X1526744Y93265D01*
G01X1558100Y133526D02*
Y133900D01*
X1556750Y135250D01*
X1550850D01*
X1545071Y129471D01*
X1541271D01*
X1537800Y126000D01*
X1523000D01*
X1520251Y123251D01*
X1508951D01*
X1504800Y119100D01*
Y77500D01*
X1476300Y49000D01*
X1469689D01*
G01X1513935Y116343D02*
X1515360Y117768D01*
X1515997D01*
X1517110Y116655D01*
Y116361D01*
G01X1513935Y104532D02*
X1515360Y105957D01*
X1515972D01*
X1517571Y104358D01*
G01X1513935Y120143D02*
X1515360Y118718D01*
X1515997D01*
X1517110Y119831D01*
Y120361D01*
G01X1513935Y108332D02*
X1515360Y106907D01*
X1516120D01*
X1517571Y108358D01*
G01X1513013Y96546D02*
X1514443Y97976D01*
X1516606D01*
G01X1520610Y116361D02*
X1522146Y117897D01*
X1524385D01*
X1524661Y117621D01*
X1524707D01*
X1525688Y116640D01*
Y116594D01*
X1526513Y115769D01*
G01X1521071Y104358D02*
X1522521Y105808D01*
X1524663D01*
X1526513Y103958D01*
G01X1520610Y120361D02*
X1522124Y118847D01*
X1524591D01*
X1526513Y120769D01*
G01X1521071Y108358D02*
X1522585Y106844D01*
X1524699D01*
X1526813Y108958D01*
G01X1520106Y97976D02*
X1521531Y96551D01*
X1525030D01*
X1526744Y98265D01*
G01X1472100Y446550D02*
X1470768D01*
G01X1477550Y439713D02*
Y438394D01*
X1476265Y437109D01*
G01X1525700Y511810D02*
X1526463Y511047D01*
Y509058D01*
X1528400Y507121D01*
Y502500D01*
G01X1484200Y492420D02*
X1490283D01*
G01X1474488Y493370D02*
X1490283D01*
G01X1479303Y495800D02*
X1488903D01*
G01X1471829Y498585D02*
X1474765D01*
X1476600Y496750D01*
X1488903D01*
G01X1479300Y501438D02*
X1488598D01*
X1489666Y500370D01*
X1491873D01*
G01X1487200Y502388D02*
X1488992D01*
X1490060Y501320D01*
X1491873D01*
G01X1467570Y481702D02*
X1476927Y484335D01*
X1479054D01*
G01X1473246Y482312D02*
X1477056Y483385D01*
X1479054D01*
G01X1475483Y488050D02*
X1477353D01*
G01X1524415Y647322D02*
X1523076Y648661D01*
X1522033D01*
X1519608Y646236D01*
G01X1524415Y651262D02*
X1522964Y649811D01*
X1522033D01*
X1519608Y652236D01*
G01X1565671Y534929D02*
X1564532Y533790D01*
G02X1563543Y533380I-990J990D01*
G01X1559479D01*
G01X1576454Y547056D02*
X1563860Y534462D01*
G02X1563542Y534330I-318J318D01*
G01X1559479D01*
G01X1595851Y499678D02*
X1592537D01*
X1592087Y499228D01*
X1590737D01*
X1590287Y499678D01*
X1588937D01*
X1588487Y499228D01*
X1587137D01*
X1586687Y499678D01*
X1585337D01*
X1583255Y497596D01*
G01X1586771Y500628D02*
X1597816D01*
X1599810Y498634D01*
Y496386D01*
X1600780Y495416D01*
G01X1583255Y502596D02*
X1585223Y500628D01*
X1586771D01*
G01X1576075Y499693D02*
X1577658D01*
X1579755Y497596D01*
G01X1576075Y499693D02*
X1573387D01*
G01X1579755Y502596D02*
X1577802Y500643D01*
X1573387D01*
G01X1528400Y502500D02*
Y501318D01*
X1529456Y500262D01*
X1530963D01*
X1531685Y499540D01*
G01X1528368Y508532D02*
X1528333D01*
X1527413Y509452D01*
Y511305D01*
X1527918Y511810D01*
X1529000D01*
G01X1531685Y502040D02*
X1530857Y501212D01*
X1529850D01*
X1529375Y501687D01*
Y503801D01*
X1529350Y503826D01*
Y503915D01*
X1529800Y504365D01*
Y505715D01*
X1529350Y506165D01*
Y507515D01*
X1528350Y508515D01*
X1528351D01*
X1528368Y508532D01*
G01X1587815Y493308D02*
X1589724D01*
X1590460Y494044D01*
Y494540D01*
X1589025Y495975D01*
G01X1576456Y494596D02*
X1577744Y493308D01*
X1579094D01*
X1579544Y493758D01*
X1580894D01*
X1581344Y493308D01*
X1583671D01*
X1584121Y493758D01*
X1585471D01*
X1585921Y493308D01*
X1587815D01*
G01X1592025Y495975D02*
X1591410Y495360D01*
Y493650D01*
X1590118Y492358D01*
X1577718D01*
X1576456Y491096D01*
G01X1565671Y534929D02*
X1581417Y550675D01*
G02X1583450Y551517I2033J-2032D01*
G01X1612807D01*
G02X1613511Y551225I0J-996D01*
G01X1613903Y550833D01*
G03X1615106Y550335I1203J1204D01*
G01X1616456D01*
G02X1616906Y550110I-43J-649D01*
G03X1617356Y549885I493J424D01*
G01X1618706D01*
G03X1619156Y550110I-43J649D01*
G02X1619606Y550335I493J-424D01*
G01X1620956D01*
G02X1621406Y550110I-43J-649D01*
G03X1621856Y549885I493J424D01*
G01X1623206D01*
G03X1623656Y550110I-43J649D01*
G02X1624106Y550335I493J-424D01*
G01X1625456D01*
G02X1625906Y550110I-43J-649D01*
G03X1626356Y549885I493J424D01*
G01X1627706D01*
G03X1628156Y550110I-43J649D01*
G02X1628606Y550335I493J-424D01*
G01X1634962D01*
G02X1647942Y544958I0J-18356D01*
G01X1652428Y540472D01*
X1652799Y540044D01*
G02X1653160Y539473I-1700J-1474D01*
G02X1653349Y538569I-2061J-903D01*
G01X1653350Y538570D01*
Y532291D01*
G03X1655019Y530622I1669J0D01*
G01X1667392D01*
G03X1669262Y531396I0J2646D01*
G01X1674719Y536853D01*
G02X1675838Y537317I1119J-1117D01*
G01X1679487D01*
G03X1680527Y537748I-1J1472D01*
G01X1682387Y539609D01*
G02X1682865Y539768I428J-489D01*
G03X1683342Y539927I49J648D01*
G01X1684296Y540882D01*
G03X1684455Y541359I-489J428D01*
G02X1684615Y541836I648J48D01*
G01X1685569Y542791D01*
G02X1686046Y542951I429J-488D01*
G03X1686523Y543110I49J648D01*
G01X1687478Y544065D01*
G03X1687637Y544542I-489J428D01*
G02X1687796Y545019I648J49D01*
G01X1688750Y545974D01*
G03X1689160Y546965I-993J991D01*
G01Y559834D01*
G02X1691026Y561700I1866J0D01*
G01X1696876D01*
G02X1697326Y561475I-43J-649D01*
G03X1697776Y561250I493J424D01*
G01X1699126D01*
G03X1699576Y561475I-43J649D01*
G02X1700026Y561700I493J-424D01*
G01X1702219D01*
G02X1702870Y561430I0J-921D01*
G01X1703140Y561160D01*
G03X1704131Y560750I991J993D01*
G01X1710696D01*
G02X1711300Y560500I0J-854D01*
G02X1711500Y560017I-483J-483D01*
G02X1710111Y558628I-1389J0D01*
G01X1710101D01*
G01X1576454Y547056D02*
X1580745Y551347D01*
G02X1583451Y552467I2704J-2705D01*
G01X1612808D01*
G02X1614183Y551897I-1J-1946D01*
G01X1614575Y551505D01*
G03X1615107Y551285I532J532D01*
G01X1634963D01*
G02X1648614Y545630I-1J-19306D01*
G01X1653125Y541120D01*
X1653518Y540667D01*
G02X1654031Y539854I-2420J-2095D01*
G02X1654300Y538569I-2932J-1284D01*
G01Y532291D01*
G03X1655019Y531572I719J0D01*
G01X1667392D01*
G03X1668590Y532068I0J1695D01*
G01X1674047Y537525D01*
G02X1675838Y538267I1791J-1791D01*
G01X1679486D01*
G03X1679855Y538420I0J521D01*
G01X1683966Y542532D01*
Y542533D01*
X1688077Y546646D01*
G03X1688210Y546965I-319J320D01*
G01Y559834D01*
G02X1691026Y562650I2816J0D01*
G01X1702220D01*
G02X1703542Y562102I-1J-1871D01*
G01X1703812Y561832D01*
G03X1704131Y561700I319J319D01*
G01X1710696D01*
G02X1711972Y561172I1J-1804D01*
G02X1712450Y560016I-1155J-1154D01*
G03X1713838Y558628I1388J0D01*
G01X1714101D01*
G01X1621942Y173237D02*
X1622592D01*
X1624064Y174709D01*
G01X1595851Y499678D02*
X1597422D01*
X1598860Y498240D01*
Y496060D01*
X1598216Y495416D01*
X1597380D01*
G01X1625094Y559200D02*
Y558125D01*
G03X1625544Y557675I450J0D01*
G01X1626889D01*
G03X1627207Y557807I0J450D01*
G01X1628600Y559200D01*
G01X1618000Y576500D02*
X1616637Y575137D01*
G02X1616319Y575005I-318J318D01*
G01X1608617D01*
G03X1607443Y574519I0J-1661D01*
G01X1603856Y570932D01*
G02X1603538Y570800I-318J318D01*
G01X1602275D01*
G02X1601825Y571250I0J450D01*
G01Y572325D01*
G01X1615000Y559200D02*
X1613875Y558075D01*
G02X1613556Y557943I-319J319D01*
G01X1612622D01*
G02X1612303Y558075I0J451D01*
G01X1611257Y559121D01*
G03X1610266Y559531I-991J-993D01*
G01X1609333D01*
G02X1609014Y559663I0J451D01*
G01X1607665Y561012D01*
G02X1607533Y561330I318J318D01*
G01Y561644D01*
G01X1609100Y582500D02*
X1607707Y581107D01*
G02X1607389Y580975I-318J318D01*
G01X1606444D01*
G02X1605994Y581425I0J450D01*
G01Y582500D01*
G01X1625094Y555200D02*
Y556275D01*
G02X1625544Y556725I450J0D01*
G01X1626889D01*
G02X1627207Y556593I0J-450D01*
G01X1628600Y555200D01*
G01X1618000Y572500D02*
X1616577Y573923D01*
G03X1616259Y574055I-318J-318D01*
G01X1608617D01*
G03X1608115Y573847I0J-710D01*
G01X1604528Y570260D01*
G02X1603538Y569850I-990J990D01*
G01X1602275D01*
G03X1601825Y569400I0J-450D01*
G01Y568325D01*
G01X1607533Y557644D02*
Y558131D01*
G02X1607983Y558581I450J0D01*
G01X1610266D01*
G02X1610585Y558448I-1J-452D01*
G01X1611631Y557403D01*
G03X1612622Y556993I991J993D01*
G01X1613021D01*
G02X1613339Y556861I0J-450D01*
G01X1615000Y555200D01*
G01X1609100Y578500D02*
X1607707Y579893D01*
G03X1607389Y580025I-318J-318D01*
G01X1606444D01*
G03X1605994Y579575I0J-450D01*
G01Y578500D01*
G01X1619500Y586880D02*
X1620633Y588013D01*
G02X1620951Y588145I318J-318D01*
G01X1623593D01*
G03X1624607Y588565I0J1434D01*
G01X1624747Y588705D01*
G02X1625067Y588838I320J-319D01*
G01X1629149D01*
G03X1630140Y589248I0J1403D01*
G01X1635024Y594131D01*
G03X1635433Y595121I-991J989D01*
G01Y596347D01*
G02X1635565Y596665I450J0D01*
G01X1635804Y596904D01*
G02X1635910Y596982I317J-319D01*
G01X1636247Y597163D01*
G02X1636857Y596979I213J-396D01*
G01X1634945Y570630D02*
X1636084Y568507D01*
G02X1635889Y567887I-400J-215D01*
G01X1635556Y567709D01*
G03X1634934Y567375I167989J-313588D01*
G01X1634931Y567373D01*
X1634778Y567290D01*
G03X1633988Y565962I720J-1327D01*
G01Y562944D01*
G03X1634398Y561955I1400J1D01*
G01X1634685Y561668D01*
G02X1634816Y561350I-319J-317D01*
G01Y560534D01*
X1634817Y560535D01*
Y558257D01*
G02X1634235Y557675I-582J0D01*
G01X1633810D01*
G02X1633493Y557807I1J450D01*
G01X1632100Y559200D01*
G01Y555200D02*
X1633493Y556593D01*
G02X1633811Y556725I318J-318D01*
G01X1634235D01*
G03X1635767Y558257I0J1532D01*
G01Y561350D01*
G03X1635357Y562340I-1400J0D01*
G01X1635070Y562627D01*
G02X1634938Y562945I318J318D01*
G01Y565962D01*
G02X1635231Y566454I560J0D01*
G01X1635386Y566538D01*
G02X1636405Y567084I168079J-312461D01*
G02X1636923Y566935I182J-341D01*
G01X1637898Y565118D01*
G01X1634945Y585591D02*
X1635985Y583653D01*
G02X1635801Y583043I-396J-213D01*
G01X1635797Y583041D01*
Y583040D01*
X1635462Y582860D01*
G03X1635133Y582617I658J-1235D01*
G01X1634850Y582334D01*
G03X1634440Y581345I990J-990D01*
G01Y578725D01*
X1634439Y578726D01*
G02X1634308Y578408I-450J-1D01*
G01X1630978Y575078D01*
G02X1630659Y574946I-319J319D01*
G01X1627740D01*
G02X1627290Y575171I43J649D01*
G03X1626840Y575396I-493J-424D01*
G01X1625490D01*
G03X1625040Y575171I43J-649D01*
G02X1624590Y574946I-493J424D01*
G01X1623240D01*
G02X1622922Y575078I0J450D01*
G01X1621500Y576500D01*
G01Y572500D02*
X1622864Y573864D01*
G02X1623182Y573996I318J-318D01*
G01X1630659D01*
G03X1631650Y574406I0J1403D01*
G01X1634980Y577736D01*
G03X1635390Y578726I-990J990D01*
G01Y581344D01*
G02X1635522Y581662I450J0D01*
G01X1635804Y581944D01*
G02X1635910Y582022I317J-319D01*
G01X1636247Y582203D01*
G02X1636857Y582019I213J-396D01*
G01D02*
X1637898Y580079D01*
G01X1626087Y570630D02*
X1627200Y568551D01*
G02X1627005Y567909I-418J-224D01*
G01X1625972Y567355D01*
X1621706Y563087D01*
G03X1621296Y562098I990J-990D01*
G01Y558142D01*
G02X1620846Y557692I-450J0D01*
G01X1620194D01*
G02X1619876Y557824I0J450D01*
G01X1618500Y559200D01*
G01Y555200D02*
X1619910Y556610D01*
G02X1620228Y556742I318J-318D01*
G01X1620846D01*
G03X1622246Y558142I0J1400D01*
G01Y562097D01*
G02X1622378Y562415I450J0D01*
G01X1626545Y566584D01*
X1627477Y567082D01*
G02X1628087Y566898I213J-398D01*
G01X1629039Y565118D01*
G01X1612600Y582500D02*
X1613993Y581107D01*
G03X1614311Y580975I318J318D01*
G01X1615661D01*
G03X1616111Y581200I-43J649D01*
G02X1616561Y581425I493J-424D01*
G01X1617911D01*
G02X1618361Y581200I-43J-649D01*
G03X1618811Y580975I493J424D01*
G01X1619954D01*
G02X1620943Y580565I-1J-1400D01*
G01X1621325Y580183D01*
X1621326D01*
G03X1621835Y579971I510J508D01*
G01X1623442D01*
G03X1623762Y580104I0J452D01*
G01X1626273Y582616D01*
G02X1626604Y582862I992J-989D01*
G01X1626941Y583041D01*
X1626942D01*
G03X1627126Y583650I-213J397D01*
G01X1626087Y585591D01*
G01X1612600Y578500D02*
X1613993Y579893D01*
G02X1614311Y580025I318J-318D01*
G01X1619953D01*
G02X1620271Y579893I0J-450D01*
G01X1620653Y579511D01*
G03X1621835Y579021I1182J1181D01*
G01X1623443D01*
G03X1624434Y579432I-1J1402D01*
G01X1626946Y581944D01*
G02X1627052Y582023I319J-318D01*
G01X1627387Y582201D01*
X1627391Y582203D01*
G02X1628001Y582019I213J-396D01*
G01X1629039Y580079D01*
G01X1616000Y586880D02*
X1615195Y587685D01*
X1612969D01*
G03X1612519Y587235I0J-450D01*
G01Y586004D01*
G01X1616000Y590380D02*
X1614255Y588635D01*
X1612969D01*
G02X1612519Y589085I0J450D01*
G01Y590004D01*
G01X1613349Y603250D02*
Y602175D01*
G03X1613799Y601725I450J0D01*
G01X1614538D01*
G03X1614754Y601780I0J452D01*
G01X1614857Y601857D01*
X1616000Y603000D01*
G01X1603919Y596750D02*
Y595675D01*
G03X1604369Y595225I450J0D01*
G01X1606039D01*
G03X1606357Y595357I0J450D01*
G01X1607500Y596500D01*
G01X1606900Y608200D02*
X1606215Y607515D01*
G02X1604792Y606925I-1424J1423D01*
G01X1604319D01*
G02X1603869Y607375I0J450D01*
G01Y608450D01*
G01X1619500Y590380D02*
X1620653Y589227D01*
G03X1620971Y589095I318J318D01*
G01X1623592D01*
G03X1623935Y589237I0J484D01*
G01X1624075Y589377D01*
G02X1625066Y589788I992J-991D01*
G01X1629149D01*
G03X1629468Y589920I0J451D01*
G01X1630423Y590875D01*
G03X1630582Y591352I-489J428D01*
G02X1630741Y591829I648J49D01*
G01X1631695Y592784D01*
G02X1632173Y592943I428J-489D01*
G03X1632650Y593102I49J648D01*
G01X1634351Y594803D01*
G03X1634482Y595121I-319J317D01*
G01X1634483Y595120D01*
Y596348D01*
G02X1634893Y597337I1400J-1D01*
G01X1635133Y597577D01*
G02X1635462Y597820I987J-992D01*
G01X1635797Y598000D01*
Y598001D01*
X1635801Y598003D01*
G03X1635985Y598613I-212J397D01*
G01X1634945Y600551D01*
G01X1636857Y596979D02*
X1637898Y595039D01*
G01X1619500Y603000D02*
X1620643Y601857D01*
G03X1620961Y601725I318J318D01*
G01X1621476D01*
G03X1621796Y601858I0J452D01*
G01X1625524Y605586D01*
G02X1626513Y605996I990J-990D01*
G01X1629914D01*
G03X1630231Y606128I-1J450D01*
G01X1632759Y608656D01*
G03X1632890Y608974I-319J317D01*
G01X1632891Y608973D01*
Y609717D01*
G02X1633301Y610706I1400J-1D01*
G01X1635133Y612538D01*
G02X1635462Y612781I987J-992D01*
G01X1635797Y612961D01*
Y612962D01*
X1635801Y612964D01*
G03X1635985Y613574I-212J397D01*
G01X1634945Y615512D01*
G01X1619500Y599500D02*
X1620643Y600643D01*
G02X1620961Y600775I318J-318D01*
G01X1621477D01*
G03X1622468Y601186I-1J1402D01*
G01X1626196Y604914D01*
G02X1626514Y605046I318J-318D01*
G01X1629913D01*
G03X1630903Y605456I0J1400D01*
G01X1633431Y607984D01*
G03X1633841Y608974I-990J990D01*
G01Y609716D01*
G02X1633973Y610034I450J0D01*
G01X1635804Y611865D01*
G02X1635910Y611943I317J-319D01*
G01X1636247Y612124D01*
G02X1636857Y611940I213J-396D01*
G01D02*
X1637898Y610000D01*
G01X1611000Y596500D02*
X1612148Y595352D01*
G03X1612756Y595100I608J607D01*
G01X1619040D01*
G03X1619490Y595325I-43J649D01*
G02X1619940Y595550I493J-424D01*
G01X1621290D01*
G02X1621740Y595325I-43J-649D01*
G03X1622190Y595100I493J424D01*
G01X1623540D01*
G03X1623981Y595283I0J623D01*
G01X1626271Y597574D01*
G02X1626605Y597822I993J-989D01*
G01X1626941Y598001D01*
X1626942D01*
G03X1627126Y598610I-213J397D01*
G01X1626087Y600551D01*
G01X1611000Y593000D02*
X1612018Y594018D01*
G02X1612337Y594150I319J-319D01*
G01X1623540D01*
G03X1624654Y594611I1J1573D01*
G01X1626943Y596902D01*
X1626945Y596903D01*
G02X1627052Y596983I320J-317D01*
G01X1627388Y597161D01*
X1627391Y597163D01*
G02X1628001Y596979I213J-396D01*
G01X1629039Y595039D01*
G01X1626087Y615512D02*
X1627126Y613571D01*
G02X1626942Y612962I-397J-212D01*
G01X1626941D01*
X1626604Y612783D01*
G03X1626273Y612537I661J-1235D01*
G01X1623319Y609582D01*
G02X1623002Y609450I-318J318D01*
G01X1620636D01*
G02X1620186Y609675I43J649D01*
G03X1619736Y609900I-493J-424D01*
G01X1618386D01*
G03X1617936Y609675I43J-649D01*
G02X1617486Y609450I-493J424D01*
G01X1616136D01*
G03X1615146Y609040I0J-1400D01*
G01X1613085Y606979D01*
G02X1612767Y606847I-318J318D01*
G01X1611939D01*
G02X1611621Y606979I0J450D01*
G01X1610400Y608200D01*
G01X1629039Y610000D02*
X1628001Y611940D01*
G03X1627391Y612124I-397J-212D01*
G01X1627387Y612122D01*
X1627052Y611944D01*
G03X1626946Y611865I213J-397D01*
G01X1623991Y608910D01*
G02X1623001Y608500I-990J990D01*
G01X1616135D01*
G03X1615818Y608368I1J-450D01*
G01X1613757Y606307D01*
G02X1612768Y605897I-990J990D01*
G01X1611783D01*
G03X1611465Y605765I0J-450D01*
G01X1610400Y604700D01*
G01X1616000Y599500D02*
X1614857Y600643D01*
X1614754Y600720D01*
G03X1614545Y600775I-216J-396D01*
G02X1614538I-4J1402D01*
G01X1613799D01*
G03X1613349Y600325I0J-450D01*
G01Y599250D01*
G01X1607500Y593000D02*
X1606357Y594143D01*
G03X1606039Y594275I-318J-318D01*
G01X1604369D01*
G03X1603919Y593825I0J-450D01*
G01Y592750D01*
G01X1606900Y604700D02*
X1606215Y605385D01*
G03X1604792Y605975I-1424J-1423D01*
G01X1604319D01*
G03X1603869Y605525I0J-450D01*
G01Y604450D01*
G01X1654800Y100300D02*
X1652000Y97500D01*
G01X1714101Y555128D02*
X1712708Y553735D01*
G03X1712576Y553417I318J-318D01*
G01Y543230D01*
G02X1712166Y542240I-1400J0D01*
G01X1710312Y540386D01*
G03X1710180Y540068I318J-318D01*
G01Y539002D01*
G03X1710312Y538684I449J0D01*
G01X1712205Y536791D01*
G01X1710101Y555128D02*
X1711494Y553735D01*
G02X1711626Y553417I-318J-318D01*
G01Y543229D01*
X1711625Y543230D01*
G02X1711494Y542912I-450J-1D01*
G01X1709640Y541058D01*
G03X1709230Y540069I990J-990D01*
G01Y539002D01*
G02X1709098Y538684I-449J0D01*
G01X1707205Y536791D01*
G01X1696280Y555517D02*
X1695106Y556691D01*
G03X1694753Y556837I-353J-354D01*
G01X1694306D01*
G03X1693059Y555590I0J-1247D01*
G01Y555033D01*
G03X1693284Y554583I649J43D01*
G02X1693509Y554133I-424J-493D01*
G01Y552783D01*
G02X1693284Y552333I-649J43D01*
G03X1693059Y551883I424J-493D01*
G01Y550533D01*
G03X1693284Y550083I649J43D01*
G02X1693509Y549633I-424J-493D01*
G01Y548283D01*
G02X1693284Y547833I-649J43D01*
G03X1693059Y547383I424J-493D01*
G01Y546033D01*
G03X1693284Y545583I649J43D01*
G02X1693509Y545133I-424J-493D01*
G01Y543783D01*
G02X1693284Y543333I-649J43D01*
G03X1693059Y542883I424J-493D01*
G01Y542185D01*
G03X1693207Y541831I501J2D01*
G01X1693617Y541420D01*
X1694755Y540282D01*
G02X1695180Y539255I-1028J-1027D01*
G01Y538519D01*
G03X1697205Y536791I1750J0D01*
G01X1692205D02*
X1694084Y538670D01*
G03X1694230Y539023I-354J353D01*
G01Y539255D01*
G03X1694083Y539610I-502J0D01*
G01X1692535Y541158D01*
G02X1692109Y542183I1025J1027D01*
G01Y555590D01*
G02X1694306Y557787I2197J0D01*
G01X1695043D01*
G03X1695396Y557933I0J500D01*
G01X1696280Y558817D01*
G01X1700348Y546633D02*
X1702411D01*
G03X1702911Y547133I0J500D01*
G01Y547733D01*
G02X1703336Y548759I1450J0D01*
G01X1705025Y550448D01*
G03X1705171Y550801I-354J353D01*
G01Y552385D01*
G03X1704946Y552835I-649J-43D01*
G02X1704721Y553285I424J493D01*
G01Y554635D01*
G02X1704946Y555085I649J-43D01*
G03X1705171Y555535I-424J493D01*
G01Y556147D01*
G03X1704411Y556907I-760J0D01*
G01X1701584D01*
G03X1700877Y556614I0J-1000D01*
G01X1699780Y555517D01*
G01Y558817D02*
X1700594Y558003D01*
G03X1700947Y557857I353J354D01*
G01X1704411D01*
G02X1706121Y556147I0J-1710D01*
G01Y550800D01*
G02X1705698Y549776I-1450J0D01*
G01X1705159Y549238D01*
X1704008Y548087D01*
G03X1703862Y547733I354J-353D01*
G01X1703861Y547734D01*
Y547133D01*
G03X1704361Y546633I500J0D01*
G01X1705348D01*
G01X1680000Y555900D02*
X1681379Y554521D01*
G02X1681525Y554168I-354J-353D01*
G01Y552981D01*
X1682025Y552481D01*
Y551044D01*
G02X1681525Y550544I-500J0D01*
G01X1680000D01*
G01X1658754Y551000D02*
X1660278D01*
G03X1660778Y551500I0J500D01*
G01Y553915D01*
G03X1660632Y554268I-500J0D01*
G01X1659500Y555400D01*
G01X1670000Y555500D02*
X1671481Y554019D01*
G02X1671627Y553666I-354J-353D01*
G01Y551940D01*
X1671625Y551938D01*
Y551044D01*
G02X1671125Y550544I-500J0D01*
G01X1669600D01*
G01X1652669Y582350D02*
Y581175D01*
G03X1653119Y580725I450J0D01*
G01X1654539D01*
G03X1654857Y580857I0J450D01*
G01X1656000Y582000D01*
G01X1684000Y555900D02*
X1682621Y554521D01*
G03X1682475Y554168I354J-353D01*
G01Y553375D01*
X1682975Y552875D01*
Y551044D01*
G03X1683475Y550544I500J0D01*
G01X1685000D01*
G01X1663754Y551000D02*
X1662228D01*
G02X1661728Y551500I0J500D01*
G01Y553921D01*
G02X1661874Y554274I500J0D01*
G01X1663000Y555400D01*
G01X1674000Y555500D02*
X1672723Y554223D01*
G03X1672577Y553870I354J-353D01*
G01Y551546D01*
X1672575Y551544D01*
Y551044D01*
G03X1673075Y550544I500J0D01*
G01X1674600D01*
G01X1652669Y578350D02*
Y579325D01*
G02X1653119Y579775I450J0D01*
G01X1654539D01*
G02X1654857Y579643I0J-450D01*
G01X1656000Y578500D01*
G01X1685142Y595039D02*
X1684101Y596979D01*
G03X1683491Y597163I-397J-212D01*
G01X1683154Y596982D01*
G03X1683048Y596904I211J-397D01*
G01X1681715Y595571D01*
G03X1681583Y595253I318J-318D01*
G01Y593027D01*
G02X1681173Y592037I-1400J0D01*
G01X1679125Y589989D01*
G02X1678135Y589579I-990J990D01*
G01X1672006D01*
G03X1671688Y589447I0J-450D01*
G01X1670926Y588685D01*
G02X1669936Y588275I-990J990D01*
G01X1669141D01*
G03X1668823Y588143I0J-450D01*
G01X1667680Y587000D01*
G01X1682189Y570630D02*
X1682808Y569476D01*
G02X1682439Y568249I-799J-429D01*
G01X1682261Y568153D01*
G03X1681525Y566919I665J-1233D01*
G01Y561132D01*
G02X1681379Y560779I-500J0D01*
G01X1680000Y559400D01*
G01X1684000D02*
X1682621Y560779D01*
G02X1682475Y561132I354J353D01*
G01Y566920D01*
X1682476Y566919D01*
G02X1682713Y567316I451J0D01*
G01X1683005Y567474D01*
G03X1683044Y567495I-799J1530D01*
G02X1683136Y567537I346J-635D01*
G01X1683324Y567607D01*
G02X1683931Y567377I172J-463D01*
G01X1685142Y565118D01*
G01X1659500Y558900D02*
X1660629Y560029D01*
G03X1660775Y560382I-354J353D01*
G01Y560667D01*
G02X1661186Y561658I1402J-1D01*
G01X1664034Y564506D01*
X1664033D01*
X1665976Y566448D01*
G03X1666122Y566802I-354J353D01*
G01X1666123Y566801D01*
Y570012D01*
G02X1666548Y571038I1450J0D01*
G01X1670605Y575095D01*
G02X1671631Y575520I1026J-1025D01*
G01X1677064D01*
G03X1677383Y575652I0J451D01*
G01X1681245Y579514D01*
G03X1681377Y579833I-319J319D01*
G01Y581058D01*
G02X1681875Y582260I1701J-1D01*
G01X1682064Y582450D01*
G02X1682395Y582694I990J-996D01*
G01X1682809Y582916D01*
X1682812Y582919D01*
X1682815Y582921D01*
X1683000Y583019D01*
X1683001Y583020D01*
G03X1683205Y583696I-237J440D01*
G01X1682189Y585591D01*
G01X1663000Y558900D02*
X1661871Y560029D01*
G02X1661725Y560382I354J353D01*
G01Y560666D01*
G02X1661858Y560986I452J0D01*
G01X1662813Y561941D01*
G02X1663290Y562100I428J-489D01*
G03X1663767Y562259I49J648D01*
G01X1664722Y563213D01*
G03X1664881Y563691I-489J428D01*
G02X1665040Y564168I648J49D01*
G01X1666648Y565776D01*
G03X1667073Y566802I-1025J1026D01*
G01Y570013D01*
X1667074Y570012D01*
G02X1667220Y570366I500J1D01*
G01X1668095Y571241D01*
G02X1668572Y571400I428J-489D01*
G03X1669050Y571559I50J648D01*
G01X1670004Y572514D01*
G03X1670163Y572991I-489J428D01*
G02X1670322Y573468I648J49D01*
G01X1671277Y574423D01*
G02X1671630Y574570I354J-353D01*
G01X1673066D01*
G02X1673516Y574345I-43J-649D01*
G03X1673966Y574120I493J424D01*
G01X1675316D01*
G03X1675766Y574345I-43J649D01*
G02X1676216Y574570I493J-424D01*
G01X1677064D01*
G03X1678055Y574980I0J1403D01*
G01X1681917Y578842D01*
G03X1682327Y579833I-993J991D01*
G01Y581057D01*
G02X1682547Y581588I751J0D01*
G01X1682736Y581777D01*
G02X1682843Y581856I320J-321D01*
G01X1683259Y582079D01*
X1683262Y582081D01*
X1683447Y582180D01*
G02X1684125Y581976I237J-440D01*
G01X1685142Y580079D01*
G01X1673331Y570630D02*
X1673949Y569476D01*
G02X1673580Y568249I-799J-429D01*
G01X1673403Y568153D01*
G03X1672667Y566918I665J-1233D01*
G01Y564137D01*
G02X1672521Y563784I-500J0D01*
G01X1671948Y563212D01*
G03X1671525Y562188I1027J-1024D01*
G01Y560732D01*
G02X1671379Y560379I-500J0D01*
G01X1670000Y559000D01*
G01X1676283Y565118D02*
X1675072Y567377D01*
G03X1674465Y567607I-435J-233D01*
G01X1674277Y567537D01*
G03X1674185Y567495I254J-677D01*
G02X1674146Y567474I-838J1509D01*
G01X1673854Y567316D01*
G03X1673617Y566919I214J-397D01*
G01Y564136D01*
G02X1673193Y563112I-1450J1D01*
G01X1672621Y562540D01*
G03X1672475Y562187I354J-353D01*
G01Y560732D01*
G03X1672621Y560379I500J0D01*
G01X1674000Y559000D01*
G01X1659500Y582000D02*
X1660643Y580857D01*
G03X1660961Y580725I318J318D01*
G01X1662311D01*
G03X1662761Y580950I-43J649D01*
G02X1663211Y581175I493J-424D01*
G01X1664561D01*
G02X1665011Y580950I-43J-649D01*
G03X1665461Y580725I493J424D01*
G01X1667437D01*
G02X1668428Y580314I-1J-1402D01*
G01X1668786Y579956D01*
G03X1669106Y579823I320J319D01*
G01X1670539D01*
G03X1670857Y579955I0J450D01*
G01X1671514Y580612D01*
X1673200Y582299D01*
G02X1673533Y582547I994J-987D01*
G01X1674247Y582926D01*
G03X1674432Y583535I-211J397D01*
G01X1673331Y585591D01*
G01X1659500Y578500D02*
X1660643Y579643D01*
G02X1660960Y579775I318J-318D01*
G01X1667436D01*
G02X1667756Y579642I0J-452D01*
G01X1668114Y579284D01*
G03X1669105Y578873I992J991D01*
G01X1670540D01*
G03X1671529Y579283I-1J1400D01*
G01X1673874Y581628D01*
G02X1673981Y581708I320J-317D01*
G01X1674693Y582086D01*
G02X1675307Y581904I214J-404D01*
G01X1676283Y580079D01*
G01X1660680Y586750D02*
Y587823D01*
G02X1661130Y588273I450J0D01*
G01X1662721D01*
G02X1663039Y588141I0J-450D01*
G01X1664180Y587000D01*
G01X1660680Y590750D02*
Y589673D01*
G03X1661130Y589223I450J0D01*
G01X1662717D01*
G03X1663035Y589355I0J450D01*
G01X1664180Y590500D01*
G01X1664000Y606000D02*
X1662857Y604857D01*
G02X1662539Y604725I-318J318D01*
G01X1658819D01*
G02X1658369Y605175I0J450D01*
G01Y606250D01*
G01X1652499Y597950D02*
Y596738D01*
G03X1652949Y596288I450J0D01*
G01X1654601D01*
G03X1654920Y596420I0J451D01*
G01X1656000Y597500D01*
G01X1650869Y614200D02*
Y612675D01*
G03X1651319Y612225I450J0D01*
G01X1654539D01*
G03X1654857Y612357I0J450D01*
G01X1656000Y613500D01*
G01X1682189Y600551D02*
X1683229Y598613D01*
G02X1683045Y598003I-396J-213D01*
G01X1683041Y598001D01*
Y598000D01*
X1682706Y597820D01*
G03X1682377Y597577I658J-1235D01*
G01X1681043Y596243D01*
G03X1680633Y595254I990J-990D01*
G01Y593026D01*
X1680632Y593027D01*
G02X1680501Y592709I-450J-1D01*
G01X1678453Y590661D01*
G02X1678136Y590529I-318J318D01*
G01X1676505D01*
G02X1676055Y590754I43J649D01*
G03X1675605Y590979I-493J-424D01*
G01X1674255D01*
G03X1673805Y590754I43J-649D01*
G02X1673355Y590529I-493J424D01*
G01X1672005D01*
G03X1671016Y590119I1J-1400D01*
G01X1670254Y589357D01*
G02X1669936Y589225I-318J318D01*
G01X1669141D01*
G02X1668823Y589357I0J450D01*
G01X1667680Y590500D01*
G01X1682189Y615512D02*
X1683230Y613572D01*
G02X1683046Y612962I-396J-213D01*
G01X1683042Y612960D01*
X1682704Y612778D01*
X1682703D01*
G03X1682378Y612535I667J-1231D01*
G01X1681398Y611555D01*
G03X1680988Y610566I990J-990D01*
G01Y609737D01*
G02X1680808Y609304I-611J0D01*
G01X1676467Y604963D01*
G02X1675712Y604650I-755J754D01*
G01X1673536D01*
G02X1673086Y604875I43J649D01*
G03X1672636Y605100I-493J-424D01*
G01X1671286D01*
G03X1670836Y604875I43J-649D01*
G02X1670386Y604650I-493J424D01*
G01X1669036D01*
G02X1668718Y604782I0J450D01*
G01X1667500Y606000D01*
G01Y602500D02*
X1668568Y603568D01*
G02X1668886Y603700I318J-318D01*
G01X1675712D01*
G03X1677139Y604291I0J2018D01*
G01X1681480Y608632D01*
G03X1681938Y609737I-1104J1105D01*
G01Y610565D01*
G02X1682070Y610883I450J0D01*
G01X1683050Y611863D01*
G02X1683155Y611941I318J-318D01*
G01X1683492Y612122D01*
G02X1684102Y611939I214J-396D01*
G01X1685142Y610000D01*
G01X1673331Y600551D02*
X1674370Y598610D01*
G02X1674186Y598001I-397J-212D01*
G01X1674185D01*
X1673848Y597822D01*
G03X1673517Y597576I661J-1235D01*
G01X1671230Y595288D01*
G02X1670913Y595156I-318J318D01*
G01X1669301D01*
G02X1668983Y595288I0J450D01*
G01X1668481Y595790D01*
G03X1667492Y596200I-990J-990D01*
G01X1665486D01*
G02X1665036Y596425I43J649D01*
G03X1664586Y596650I-493J-424D01*
G01X1663236D01*
G03X1662786Y596425I43J-649D01*
G02X1662336Y596200I-493J424D01*
G01X1660986D01*
G02X1660668Y596332I0J450D01*
G01X1659500Y597500D01*
G01Y594000D02*
X1660618Y595118D01*
G02X1660936Y595250I318J-318D01*
G01X1667491D01*
G02X1667809Y595118I0J-450D01*
G01X1668311Y594616D01*
G03X1669301Y594206I990J990D01*
G01X1670912D01*
G03X1671902Y594616I0J1400D01*
G01X1674190Y596904D01*
G02X1674296Y596983I319J-318D01*
G01X1674631Y597161D01*
X1674635Y597163D01*
G02X1675245Y596979I213J-396D01*
G01X1676283Y595039D01*
G01X1673331Y615512D02*
X1674370Y613571D01*
G02X1674186Y612962I-397J-212D01*
G01X1674185D01*
X1673972Y612848D01*
G03X1673642Y612603I660J-1234D01*
G01X1671220Y610181D01*
G02X1670902Y610049I-318J318D01*
G01X1669399D01*
G02X1669081Y610181I0J450D01*
G01X1667447Y611815D01*
G03X1666457Y612225I-990J-990D01*
G01X1665461D01*
G02X1665011Y612450I43J649D01*
G03X1664561Y612675I-493J-424D01*
G01X1663211D01*
G03X1662761Y612450I43J-649D01*
G02X1662311Y612225I-493J424D01*
G01X1660961D01*
G02X1660643Y612357I0J450D01*
G01X1659500Y613500D01*
G01Y610000D02*
X1660643Y611143D01*
G02X1660961Y611275I318J-318D01*
G01X1666458D01*
G02X1666775Y611143I-1J-450D01*
G01X1668409Y609509D01*
G03X1669398Y609099I990J990D01*
G01X1670903D01*
G03X1671892Y609509I-1J1400D01*
G01X1674314Y611931D01*
X1674315D01*
G02X1674401Y611999I320J-316D01*
G01X1674635Y612124D01*
G02X1675245Y611940I213J-396D01*
G01X1676283Y610000D01*
G01X1664000Y602500D02*
X1662857Y603643D01*
G03X1662539Y603775I-318J-318D01*
G01X1658819D01*
G03X1658369Y603325I0J-450D01*
G01Y602250D01*
G01X1656000Y594000D02*
X1654794Y595206D01*
G03X1654475Y595338I-319J-319D01*
G01X1652949D01*
G03X1652499Y594888I0J-450D01*
G01Y593950D01*
G01X1650869Y609200D02*
Y610825D01*
G02X1651319Y611275I450J0D01*
G01X1654539D01*
G02X1654857Y611143I0J-450D01*
G01X1656000Y610000D01*
G01X1763497Y206327D02*
Y207921D01*
X1763047Y208371D01*
X1762422D01*
X1761773Y209020D01*
Y209679D01*
X1763725Y211631D01*
G01X1750589Y206071D02*
Y207665D01*
X1750139Y208115D01*
X1749514D01*
X1749064Y208565D01*
Y209570D01*
X1751125Y211631D01*
G01X1737600Y205900D02*
Y207494D01*
X1736325Y208769D01*
Y209472D01*
X1738484Y211631D01*
G01X1771525Y206327D02*
Y207921D01*
X1771975Y208371D01*
X1772600D01*
X1773050Y208821D01*
Y209906D01*
X1771325Y211631D01*
G01X1759497Y206327D02*
Y207921D01*
X1759947Y208371D01*
X1760572D01*
X1760823Y208622D01*
Y209533D01*
X1758725Y211631D01*
G01X1746589Y206071D02*
Y207665D01*
X1747039Y208115D01*
X1747664D01*
X1748114Y208565D01*
Y209642D01*
X1746125Y211631D01*
G01X1734100Y205900D02*
Y207494D01*
X1735375Y208769D01*
Y209740D01*
X1733484Y211631D01*
G01X1763668Y196843D02*
X1762165D01*
X1761615Y197393D01*
Y198472D01*
X1761912Y198769D01*
Y200273D01*
X1762422Y200783D01*
X1763047D01*
X1763497Y201233D01*
Y202827D01*
G01X1750589Y202571D02*
Y200977D01*
X1750139Y200527D01*
X1749514D01*
X1748931Y199944D01*
Y197378D01*
X1749466Y196843D01*
X1751082D01*
G01X1737600Y202400D02*
Y200806D01*
X1736439Y199645D01*
Y196778D01*
X1736906Y196311D01*
X1738098D01*
X1738563Y196776D01*
G01X1771525Y202827D02*
Y201233D01*
X1771975Y200783D01*
X1772600D01*
X1773310Y200073D01*
Y197335D01*
X1772816Y196841D01*
X1771241D01*
G01X1758668Y196843D02*
X1760215D01*
X1760665Y197293D01*
Y198866D01*
X1760962Y199163D01*
Y200393D01*
X1760572Y200783D01*
X1759947D01*
X1759497Y201233D01*
Y202827D01*
G01X1746589Y202571D02*
Y200977D01*
X1747039Y200527D01*
X1747531D01*
X1747981Y200077D01*
Y197293D01*
X1747531Y196843D01*
X1746082D01*
G01X1734100Y202400D02*
Y201036D01*
X1735489Y199647D01*
Y196875D01*
X1734925Y196311D01*
X1734028D01*
X1733563Y196776D01*
G01X1768500Y458630D02*
X1770025Y460155D01*
Y461574D01*
X1769052Y463003D01*
X1758834Y470725D01*
X1757213Y474299D01*
X1759257Y483785D01*
X1755600Y492637D01*
Y495956D01*
X1755150Y496406D01*
X1753575D01*
G01X1743500Y458630D02*
X1745025Y460155D01*
Y461573D01*
X1745024Y461574D01*
X1744311Y462724D01*
X1739731Y466211D01*
X1729392Y490275D01*
X1730664Y495173D01*
Y499635D01*
X1730214Y500085D01*
X1728639D01*
G01X1756000Y458630D02*
X1757525Y460155D01*
Y461574D01*
X1756803Y462823D01*
X1753762Y465046D01*
X1749970Y478814D01*
X1745260Y484831D01*
X1744221Y491281D01*
X1745150Y494838D01*
Y495950D01*
X1744700Y496400D01*
X1743125D01*
G01X1772500Y458630D02*
X1770975Y460155D01*
Y461867D01*
X1769750Y463667D01*
X1759600Y471338D01*
X1758208Y474406D01*
X1760249Y483874D01*
X1756550Y492826D01*
Y495956D01*
X1757000Y496406D01*
X1758575D01*
G01X1747500Y458630D02*
X1745975Y460155D01*
Y461845D01*
X1745027Y463374D01*
X1740506Y466816D01*
X1730394Y490351D01*
X1731614Y495051D01*
Y499635D01*
X1732064Y500085D01*
X1733639D01*
G01X1760000Y458630D02*
X1758475Y460155D01*
Y461829D01*
X1757526Y463472D01*
X1754590Y465618D01*
X1750836Y479250D01*
X1746159Y485224D01*
X1745191Y491235D01*
X1746100Y494715D01*
Y495950D01*
X1746550Y496400D01*
X1748125D01*
G01X1768500Y455130D02*
X1770268Y453362D01*
Y450858D01*
X1769818Y450408D01*
X1768366D01*
G01X1743500Y455130D02*
X1745155Y453475D01*
Y450914D01*
X1744649Y450408D01*
X1743169D01*
G01X1756000Y455130D02*
X1757720Y453410D01*
Y450950D01*
X1757178Y450408D01*
X1755767D01*
G01X1772500Y455130D02*
X1771218Y453848D01*
Y450981D01*
X1771791Y450408D01*
X1773366D01*
G01X1747500Y455130D02*
X1746105Y453735D01*
Y450897D01*
X1746594Y450408D01*
X1748169D01*
G01X1760000Y455130D02*
X1758670Y453800D01*
Y450930D01*
X1759192Y450408D01*
X1760767D01*
G01X1781500Y458630D02*
X1783025Y460155D01*
Y461574D01*
X1782182Y462855D01*
X1771491Y469971D01*
X1769648Y472949D01*
X1770815Y477313D01*
X1767350Y485196D01*
Y486905D01*
X1766900Y487355D01*
X1765325D01*
G01X1785500Y458630D02*
X1783975Y460155D01*
Y461859D01*
X1782870Y463539D01*
X1772190Y470647D01*
X1770672Y473100D01*
X1771819Y477390D01*
X1768300Y485396D01*
Y486905D01*
X1768750Y487355D01*
X1770325D01*
G01X1826100Y206427D02*
Y208021D01*
X1825650Y208471D01*
X1825025D01*
X1824575Y208921D01*
Y210200D01*
X1826536Y212161D01*
X1826685D01*
G01X1814125Y212231D02*
X1812033Y210139D01*
Y209063D01*
X1812525Y208571D01*
X1813150D01*
X1813600Y208121D01*
Y206527D01*
G01X1801200Y206627D02*
Y208221D01*
X1800750Y208671D01*
X1800125D01*
X1799675Y209121D01*
Y210380D01*
X1801526Y212231D01*
G01X1788300Y206027D02*
Y207621D01*
X1787850Y208071D01*
X1787225D01*
X1786775Y208521D01*
Y209481D01*
X1788925Y211631D01*
G01X1775525Y206327D02*
Y207921D01*
X1775075Y208371D01*
X1774450D01*
X1774000Y208821D01*
Y209458D01*
X1776173Y211631D01*
X1776325D01*
G01X1822100Y206427D02*
Y208021D01*
X1822550Y208471D01*
X1823175D01*
X1823625Y208921D01*
Y210221D01*
X1821685Y212161D01*
G01X1809600Y206527D02*
Y208121D01*
X1810050Y208571D01*
X1810633D01*
X1811083Y209021D01*
Y210617D01*
X1809469Y212231D01*
X1809125D01*
G01X1797200Y206627D02*
Y208221D01*
X1797650Y208671D01*
X1798275D01*
X1798725Y209121D01*
Y210200D01*
X1796694Y212231D01*
X1796526D01*
G01X1784300Y206027D02*
Y207621D01*
X1784750Y208071D01*
X1785375D01*
X1785825Y208521D01*
Y209731D01*
X1783925Y211631D01*
G01X1775525Y202827D02*
Y201233D01*
X1775075Y200783D01*
X1774710D01*
X1774260Y200333D01*
Y197291D01*
X1774710Y196841D01*
X1776241D01*
G01X1826100Y202927D02*
Y201333D01*
X1825650Y200883D01*
X1825107D01*
X1824657Y200433D01*
Y197291D01*
X1825107Y196841D01*
X1826682D01*
G01X1813600Y203027D02*
Y201433D01*
X1813150Y200983D01*
X1812525D01*
X1812016Y200474D01*
Y197291D01*
X1812466Y196841D01*
X1814041D01*
G01X1801200Y203127D02*
Y201533D01*
X1800750Y201083D01*
X1800125D01*
X1799620Y200578D01*
Y197291D01*
X1800070Y196841D01*
X1801441D01*
G01X1788300Y202527D02*
Y200933D01*
X1787850Y200483D01*
X1787266D01*
X1786816Y200033D01*
Y197291D01*
X1787266Y196841D01*
X1788841D01*
G01X1822100Y202927D02*
Y201333D01*
X1822550Y200883D01*
X1823175D01*
X1823707Y200351D01*
Y197291D01*
X1823257Y196841D01*
X1821682D01*
G01X1809600Y203027D02*
Y201433D01*
X1810050Y200983D01*
X1810616D01*
X1811066Y200533D01*
Y197291D01*
X1810616Y196841D01*
X1809041D01*
G01X1797200Y203127D02*
Y201533D01*
X1797650Y201083D01*
X1798220D01*
X1798670Y200633D01*
Y197495D01*
X1798016Y196841D01*
X1796441D01*
G01X1784300Y202527D02*
Y200933D01*
X1784750Y200483D01*
X1785375D01*
X1785866Y199992D01*
Y197291D01*
X1785416Y196841D01*
X1783841D01*
G01X1794000Y458630D02*
X1795525Y460155D01*
Y461574D01*
X1794606Y463337D01*
X1791908Y465348D01*
X1785514Y477218D01*
X1786333Y480078D01*
X1785480Y483622D01*
X1786550Y487049D01*
Y488480D01*
X1786100Y488930D01*
X1784525D01*
G01X1806500Y458630D02*
X1808025Y460155D01*
Y461574D01*
X1806528Y463680D01*
X1799344Y468305D01*
X1797366Y474453D01*
X1799798Y480675D01*
X1798150Y486288D01*
Y488480D01*
X1797700Y488930D01*
X1796125D01*
G01X1819000Y458630D02*
X1820525Y460155D01*
Y461574D01*
X1819905Y462726D01*
X1816814Y464887D01*
Y464888D01*
X1813539Y467177D01*
X1809313Y474892D01*
X1807505Y482669D01*
X1809000Y487186D01*
Y488280D01*
X1808550Y488730D01*
X1806975D01*
G01X1832000Y458630D02*
X1833525Y460155D01*
Y461574D01*
X1832381Y463182D01*
X1828031Y465602D01*
X1826887Y467826D01*
X1822766Y470966D01*
Y470967D01*
X1819914Y482050D01*
X1821150Y486466D01*
Y488480D01*
X1820700Y488930D01*
X1819125D01*
G01X1798000Y458630D02*
X1796475Y460155D01*
Y461807D01*
X1795348Y463969D01*
X1792645Y465984D01*
X1786534Y477328D01*
X1787316Y480057D01*
X1786466Y483589D01*
X1787500Y486904D01*
Y488480D01*
X1787950Y488930D01*
X1789525D01*
G01X1810500Y458630D02*
X1808975Y460155D01*
Y461878D01*
X1807196Y464380D01*
X1800145Y468920D01*
X1798374Y474422D01*
X1800802Y480631D01*
X1799100Y486425D01*
Y488480D01*
X1799550Y488930D01*
X1801125D01*
G01X1823000Y458630D02*
X1821475Y460155D01*
Y461814D01*
X1820635Y463375D01*
X1820636D01*
X1820635Y463376D01*
X1814266Y467829D01*
X1810209Y475234D01*
X1808491Y482624D01*
X1809950Y487032D01*
Y488280D01*
X1810400Y488730D01*
X1811975D01*
G01X1836000Y458630D02*
X1834475Y460155D01*
Y461878D01*
X1833031Y463908D01*
X1828745Y466293D01*
X1827634Y468452D01*
X1823605Y471522D01*
X1820898Y482040D01*
X1822100Y486335D01*
Y488480D01*
X1822550Y488930D01*
X1824125D01*
G01X1781500Y455130D02*
X1782989Y453641D01*
Y450858D01*
X1782539Y450408D01*
X1780964D01*
G01X1794000Y455130D02*
X1795588Y453542D01*
Y450858D01*
X1795138Y450408D01*
X1793563D01*
G01X1806500Y455130D02*
X1808135Y453495D01*
Y450859D01*
X1807684Y450408D01*
X1806161D01*
G01X1819000Y455130D02*
X1820698Y453432D01*
Y450893D01*
X1820213Y450408D01*
X1818760D01*
G01X1832000Y455130D02*
X1833520Y453610D01*
Y451050D01*
X1833070Y450600D01*
X1831495D01*
G01X1785500Y455130D02*
X1783939Y453569D01*
Y450858D01*
X1784389Y450408D01*
X1785964D01*
G01X1798000Y455130D02*
X1796538Y453668D01*
Y450858D01*
X1796988Y450408D01*
X1798563D01*
G01X1810500Y455130D02*
X1809085Y453715D01*
Y450909D01*
X1809586Y450408D01*
X1811161D01*
G01X1823000Y455130D02*
X1821648Y453778D01*
Y450945D01*
X1822185Y450408D01*
X1823760D01*
G01X1836000Y455130D02*
X1834470Y453600D01*
Y451050D01*
X1834920Y450600D01*
X1836495D01*
G01X1854720Y253700D02*
X1856020Y255000D01*
Y256113D01*
X1856745Y257273D01*
X1857834Y257953D01*
X1859487Y258336D01*
X1865746Y256890D01*
X1870912Y253541D01*
X1876883Y251770D01*
X1882787Y242321D01*
X1887113Y239620D01*
X1893833Y238068D01*
X1896429Y238666D01*
X1901838Y237419D01*
X1901840Y237422D01*
X1901839Y237423D01*
X1904687Y235643D01*
X1906087Y233406D01*
Y231835D01*
X1906809Y231113D01*
X1907871D01*
X1908661Y231903D01*
X1911755D01*
G01X1899369Y237015D02*
X1899368Y237013D01*
X1896429Y237691D01*
X1893833Y237092D01*
X1890252Y237919D01*
X1889712Y237582D01*
X1888397Y237886D01*
X1888059Y238425D01*
X1886744Y238729D01*
X1885151Y239724D01*
X1884530Y239581D01*
X1883385Y240296D01*
X1883242Y240916D01*
X1882097Y241631D01*
X1876267Y250961D01*
X1870510Y252669D01*
X1865369Y256002D01*
X1862998Y256550D01*
X1862458Y256213D01*
X1861143Y256516D01*
X1860805Y257056D01*
X1859490Y257360D01*
X1858203Y257063D01*
X1857435Y256583D01*
X1856970Y255840D01*
Y254910D01*
X1858180Y253700D01*
X1858420D01*
G01X1846517Y253500D02*
X1847592Y254575D01*
Y255958D01*
X1850937Y261313D01*
X1859945Y263392D01*
Y263393D01*
X1865875Y262024D01*
X1872175Y257941D01*
X1880134Y255580D01*
X1886573Y245272D01*
X1888903Y243814D01*
X1894102Y242615D01*
X1896856Y243250D01*
X1903223Y241791D01*
X1908738Y238343D01*
X1909355D01*
X1910470Y239458D01*
G01X1910459Y236258D02*
X1909324Y237393D01*
X1908465D01*
X1902855Y240900D01*
X1896857Y242275D01*
X1894102Y241640D01*
X1888534Y242924D01*
X1885883Y244583D01*
X1879518Y254771D01*
X1871773Y257069D01*
X1865498Y261135D01*
X1859945Y262417D01*
X1858550Y262095D01*
X1858213Y261555D01*
X1856898Y261252D01*
X1856358Y261589D01*
X1855043Y261285D01*
X1854705Y260745D01*
X1853390Y260442D01*
X1852850Y260779D01*
X1851535Y260475D01*
X1850820Y259330D01*
X1850963Y258710D01*
X1850247Y257565D01*
X1849627Y257422D01*
X1848542Y255685D01*
Y254846D01*
X1849888Y253500D01*
X1850220D01*
G01X1856950Y488500D02*
X1855099D01*
X1853999Y489600D01*
X1853169D01*
X1852719Y489150D01*
Y487575D01*
G01X1856950Y491650D02*
X1855049D01*
X1853949Y490550D01*
X1853169D01*
X1852719Y491000D01*
Y492575D01*
G01X1875237Y489200D02*
X1876200D01*
X1876709Y489709D01*
X1877994D01*
X1879000Y490715D01*
Y495000D01*
X1881850Y497850D01*
X1898072D01*
X1901100Y500878D01*
Y502228D01*
X1901550Y502678D01*
Y504028D01*
X1901100Y504478D01*
Y505828D01*
X1901550Y506278D01*
Y507628D01*
X1901100Y508078D01*
Y509428D01*
X1901550Y509878D01*
Y511228D01*
X1901100Y511678D01*
Y513028D01*
X1901550Y513478D01*
Y514828D01*
X1901100Y515278D01*
Y519965D01*
X1902000Y520865D01*
X1904170Y521764D01*
X1905992D01*
X1907988Y519768D01*
Y518775D01*
X1907539Y518326D01*
X1907537Y518328D01*
X1904532D01*
G01X1872938Y489200D02*
X1875237D01*
G01X1864950Y488500D02*
X1866800D01*
X1868009Y489709D01*
X1871053D01*
X1871562Y489200D01*
X1872938D01*
G01Y491169D02*
X1871562D01*
X1871052Y490659D01*
X1867841D01*
X1866850Y491650D01*
X1864950D01*
G01X1875237Y491169D02*
X1876131D01*
X1876641Y490659D01*
X1877600D01*
X1878050Y491109D01*
Y495394D01*
X1881456Y498800D01*
X1897678D01*
X1900150Y501272D01*
Y520359D01*
X1901461Y521671D01*
X1903981Y522714D01*
X1906386D01*
X1908938Y520162D01*
Y518779D01*
X1909390Y518327D01*
X1912402D01*
X1912406Y518328D01*
G01X1872938Y491169D02*
X1875237D01*
G01X1956901Y218391D02*
X1955760Y217250D01*
X1955140D01*
X1952199Y215527D01*
X1951063Y215128D01*
X1950489Y215404D01*
X1949215Y214957D01*
X1948940Y214383D01*
X1947666Y213936D01*
X1947092Y214211D01*
X1945818Y213764D01*
X1945543Y213190D01*
X1944269Y212743D01*
X1943695Y213019D01*
X1942421Y212571D01*
X1942146Y211998D01*
X1941584Y211800D01*
X1940234D01*
X1939784Y212250D01*
X1938434D01*
X1937984Y211800D01*
X1935534D01*
X1933700Y212338D01*
X1931635Y214403D01*
X1930314Y218369D01*
Y218927D01*
X1930810Y219423D01*
Y220003D01*
G01X1931994Y212699D02*
X1933199Y211494D01*
X1935397Y210850D01*
X1941747D01*
X1952601Y214660D01*
X1955398Y216300D01*
X1955842D01*
X1956901Y215241D01*
G01X1931994Y212699D02*
X1930804Y213889D01*
X1929364Y218214D01*
Y218929D01*
X1928842Y219451D01*
Y220003D01*
G01X1943217Y221154D02*
Y220034D01*
X1942544Y219361D01*
X1940737D01*
X1939076Y217700D01*
X1936540D01*
X1935959Y218281D01*
Y218919D01*
X1936716Y219676D01*
Y220003D01*
G01X1943217Y217645D02*
X1942451Y218411D01*
X1941131D01*
X1939470Y216750D01*
X1936146D01*
X1935009Y217887D01*
Y219313D01*
X1935010Y219314D01*
X1934747Y219577D01*
Y220003D01*
G01X1919780Y239436D02*
X1917266D01*
X1916166Y238336D01*
X1915092D01*
X1913970Y239458D01*
G01X1919780Y236286D02*
X1917438D01*
X1916338Y237386D01*
X1915087D01*
X1913959Y236258D01*
G01X1930810Y222302D02*
Y222700D01*
X1930454Y223056D01*
Y224246D01*
X1928449Y226251D01*
G01X1930810Y222302D02*
Y220003D01*
G01X1928449Y226251D02*
X1923711Y230989D01*
X1922241D01*
X1921327Y231903D01*
X1919755D01*
G01X1928842Y222302D02*
Y220003D01*
G01Y222302D02*
Y222552D01*
X1929504Y223214D01*
Y223852D01*
X1928637Y224719D01*
X1928000D01*
X1927046Y225674D01*
Y226310D01*
X1926212Y227144D01*
X1925575D01*
X1924621Y228099D01*
Y228735D01*
X1923317Y230039D01*
X1922970D01*
X1922660Y229729D01*
Y229050D01*
X1922363Y228753D01*
X1919755D01*
G01X1936716Y222302D02*
Y223532D01*
X1936170Y224078D01*
Y233087D01*
G01X1936716Y222302D02*
Y220003D01*
G01X1927780Y239436D02*
X1931064D01*
X1931664Y238836D01*
X1933208D01*
X1936170Y235874D01*
Y233087D01*
G01X1934747Y222302D02*
Y223669D01*
X1935220Y224142D01*
Y226688D01*
G01X1934747Y222302D02*
Y220003D01*
G01X1927780Y236286D02*
X1931036D01*
X1931480Y236730D01*
Y237381D01*
X1931985Y237886D01*
X1932814D01*
X1935220Y235480D01*
Y231013D01*
X1934770Y230563D01*
Y229213D01*
X1935220Y228763D01*
Y226688D01*
G01X1911755Y228753D02*
X1908977D01*
X1907567Y230163D01*
X1906415D01*
X1905137Y231441D01*
Y233133D01*
X1903998Y234953D01*
X1901473Y236531D01*
X1901053Y236628D01*
X1899369Y237015D01*
G54D226*
G01X8940Y21090D02*
Y23440D01*
X10600Y25100D01*
G01X15480Y21330D02*
Y21730D01*
X16400Y22650D01*
Y24744D01*
G01X64200Y17389D02*
X62747Y15936D01*
X56520D01*
X53662Y13078D01*
X44542D01*
G01D02*
X41542D01*
G01X11980Y21330D02*
Y23125D01*
X13716Y24861D01*
G01X8580Y529080D02*
X6860Y530800D01*
X6700D01*
X6200Y531300D01*
G01X6500Y570300D02*
Y567600D01*
X6200Y567300D01*
G01X7000Y534500D02*
Y532100D01*
X6200Y531300D01*
G01Y567300D02*
X6890Y566610D01*
Y564000D01*
G01X3500Y534500D02*
Y531400D01*
X3600Y531300D01*
G01Y567300D02*
X2700Y566400D01*
Y564500D01*
G01X3000Y570300D02*
Y567900D01*
X3600Y567300D01*
G01X106200Y26500D02*
Y28892D01*
X103600Y31492D01*
Y31978D01*
G01Y-8400D02*
X99990Y-12010D01*
X99102D01*
G01X97500Y118500D02*
Y114100D01*
X98420Y113180D01*
Y112198D01*
G01X80500Y275000D02*
X85500D01*
G01X80500D02*
X76500D01*
X75500Y274000D01*
G01X97000Y223800D02*
X99500D01*
G01X93500D02*
X92900Y224400D01*
X90300D01*
G01D02*
X86600D01*
X86200Y224800D01*
X83500D01*
G01X102300Y338200D02*
Y336700D01*
X103200Y335800D01*
Y335190D01*
G01X82100Y368300D02*
X79500Y370900D01*
Y372600D01*
G01X70600Y368400D02*
X73500Y371300D01*
G01X75000Y376100D02*
Y379500D01*
X74800Y379700D01*
G01X79500Y376100D02*
Y379000D01*
X80200Y379700D01*
G01X105392Y572300D02*
Y574800D01*
G01X106392Y534500D02*
Y537000D01*
G01X105000Y614533D02*
Y614500D01*
X105892Y613608D01*
Y612000D01*
G01X143699Y22133D02*
Y26130D01*
X141893Y27936D01*
G01X120273Y27899D02*
Y22133D01*
G01D02*
Y16839D01*
G01X153738Y9114D02*
Y4023D01*
G01D02*
Y-1751D01*
G01X160431Y9114D02*
Y4023D01*
G01D02*
Y-1801D01*
G01X163391Y29949D02*
X163777Y29563D01*
Y22133D01*
G01D02*
Y15064D01*
X163427Y14714D01*
G01X123620Y9114D02*
Y4023D01*
G01X157084Y14814D02*
Y22133D01*
G01D02*
Y29949D01*
G01X150391D02*
X150392Y29948D01*
Y22133D01*
G01D02*
Y14815D01*
X150391Y14814D01*
G01X126580Y29949D02*
X126966Y29563D01*
Y22133D01*
G01D02*
Y17773D01*
X126616Y17423D01*
Y14714D01*
G01X132959Y30100D02*
X133659Y29400D01*
Y22133D01*
G01X132692Y17800D02*
Y15081D01*
X132959Y14814D01*
G01X123620Y4023D02*
Y-1801D01*
G01X167124Y-1751D02*
Y4023D01*
G01D02*
Y9064D01*
X167074Y9114D01*
X166974D01*
G01X169770Y30100D02*
X170470Y29400D01*
Y22133D01*
G01X169492Y18288D02*
Y15092D01*
X169770Y14814D01*
G01X137006Y4023D02*
Y-1575D01*
X136780Y-1801D01*
G01Y9098D02*
Y9024D01*
X137006Y8798D01*
Y4023D01*
G01X130313D02*
Y-1751D01*
G01X130163Y9114D02*
X130263D01*
X130313Y9064D01*
Y4023D01*
G01X147045D02*
Y-1751D01*
G01Y9114D02*
Y4023D01*
G01X141880Y17114D02*
X143699Y18933D01*
Y22133D01*
G01X123620Y41823D02*
Y35983D01*
G01Y46914D02*
Y41823D01*
G01X153738Y79623D02*
Y84714D01*
G01Y73849D02*
Y79623D01*
G01Y36049D02*
Y41823D01*
G01D02*
Y46914D01*
G01X150392Y59933D02*
Y67748D01*
X150391Y67749D01*
G01Y52614D02*
X150392Y52615D01*
Y59933D01*
G01X147045Y79623D02*
Y84714D01*
G01Y73849D02*
Y79623D01*
G01X120273Y59933D02*
Y66000D01*
G01Y54839D02*
Y59933D01*
G01X136780Y35999D02*
X137006Y36225D01*
Y41823D01*
G01D02*
Y46598D01*
X136780Y46824D01*
Y46898D01*
G01X130313Y35983D02*
Y41823D01*
G01D02*
Y46864D01*
X130263Y46914D01*
X130163D01*
G01X150392Y97733D02*
Y90415D01*
X150391Y90414D01*
G01X157084D02*
Y97733D01*
G01X163777D02*
Y90664D01*
X163427Y90314D01*
G01X143699Y97733D02*
Y94533D01*
X141880Y92714D01*
G01X132692Y93400D02*
Y90681D01*
X132959Y90414D01*
G01X126966Y97733D02*
Y93373D01*
X126616Y93023D01*
Y90314D01*
G01X120273Y92500D02*
Y97733D01*
G01X147045Y41823D02*
Y36049D01*
G01Y46914D02*
Y41823D01*
G01X143699Y59933D02*
Y63930D01*
X141893Y65736D01*
G01X141880Y54914D02*
X143699Y56733D01*
Y59933D01*
G01X132959Y67900D02*
X133659Y67200D01*
Y59933D01*
G01X132692Y55600D02*
Y52881D01*
X132959Y52614D01*
G01X126580Y67749D02*
X126966Y67363D01*
Y59933D01*
G01D02*
Y55573D01*
X126616Y55223D01*
Y52514D01*
G01X136780Y73799D02*
X137006Y74025D01*
Y79623D01*
G01D02*
Y84398D01*
X136780Y84624D01*
Y84698D01*
G01X130313Y79623D02*
Y84664D01*
X130263Y84714D01*
X130163D01*
G01X130313Y73849D02*
Y79623D01*
G01X163777Y59933D02*
Y67363D01*
X163391Y67749D01*
G01X163427Y52514D02*
X163777Y52864D01*
Y59933D01*
G01X160431Y35999D02*
Y41823D01*
G01D02*
Y46914D01*
G01X157084Y59933D02*
Y67749D01*
G01Y52614D02*
Y59933D01*
G01X160431Y79623D02*
Y84714D01*
G01Y73799D02*
Y79623D01*
G01X123620Y84714D02*
Y79623D01*
G01X170470Y59933D02*
Y67200D01*
X169770Y67900D01*
G01Y52614D02*
X169492Y52892D01*
Y56088D01*
G01X166974Y46914D02*
X167074D01*
X167124Y46864D01*
Y41823D01*
G01D02*
Y36049D01*
G01X166974Y73849D02*
X167124Y73999D01*
Y79623D01*
G01D02*
Y84664D01*
X167074Y84714D01*
X166974D01*
G01X169492Y93888D02*
Y90642D01*
G01X123620Y73799D02*
Y79623D01*
G01X130800Y214600D02*
X130937Y214463D01*
Y212646D01*
X130324Y212033D01*
G01D02*
X130624Y211733D01*
Y209293D01*
X130614Y209283D01*
G01X127300Y214600D02*
Y212307D01*
X127754Y211853D01*
G01X130700Y278700D02*
Y276409D01*
X130324Y276033D01*
G01Y244033D02*
X130500Y244209D01*
Y246600D01*
G01X130300Y273300D02*
Y276009D01*
X130324Y276033D01*
G01X127000Y246600D02*
Y244000D01*
X127500Y243500D01*
G01X127200Y278700D02*
Y275800D01*
X127500Y275500D01*
G01X130624Y305323D02*
Y307733D01*
X130324Y308033D01*
G01X130624Y337533D02*
Y339733D01*
X130205Y340152D01*
G01X130600Y310800D02*
Y308309D01*
X130324Y308033D01*
G01X129700Y340152D02*
X130205D01*
G01D02*
X130443D01*
X130600Y340309D01*
Y342600D01*
G01X127100Y310800D02*
Y307900D01*
X127500Y307500D01*
G01X127100Y342600D02*
Y341928D01*
X127000Y341828D01*
Y339000D01*
G01X130500Y374600D02*
Y372170D01*
X130585Y372085D01*
G01D02*
X130884Y371786D01*
Y369363D01*
G01X127000Y374600D02*
Y372010D01*
X127420Y371590D01*
G01D02*
X126056D01*
X125466Y371000D01*
X124409D01*
X123200Y369791D01*
X119018D01*
G01X248200Y366800D02*
X197986Y417014D01*
X158864D01*
X157862Y416012D01*
G01X167124Y505024D02*
Y510064D01*
X167074Y510114D01*
X166974D01*
G01X160431Y505024D02*
Y510114D01*
G01X150392Y523134D02*
Y515815D01*
X150391Y515814D01*
G01X163777Y523134D02*
Y516064D01*
X163427Y515714D01*
G01X169492Y519288D02*
Y516042D01*
G01X153738Y505024D02*
Y510114D01*
G01X157084Y523134D02*
Y515814D01*
G01X132692Y518800D02*
Y516081D01*
X132959Y515814D01*
G01X120273Y523134D02*
Y517900D01*
G01X126966Y523134D02*
Y518773D01*
X126616Y518423D01*
Y515714D01*
G01X147045Y505024D02*
Y510114D01*
G01X137006Y505024D02*
Y509798D01*
X136780Y510024D01*
Y510098D01*
G01X130313Y505024D02*
Y510064D01*
X130263Y510114D01*
X130163D01*
G01X123620D02*
Y505024D01*
G01X143699Y523134D02*
Y519933D01*
X141880Y518114D01*
G01X167124Y542824D02*
Y547864D01*
X167074Y547914D01*
X166974D01*
G01X160431Y542824D02*
Y547914D01*
G01X167124Y580624D02*
Y585664D01*
X167074Y585714D01*
X166974D01*
G01X160431Y580624D02*
Y585714D01*
G01X153738Y580624D02*
Y585714D01*
G01X150392Y560934D02*
Y553615D01*
X150391Y553614D01*
G01X163777Y560934D02*
Y553864D01*
X163427Y553514D01*
G01X169492Y557088D02*
Y553842D01*
G01X157084Y560934D02*
Y553614D01*
G01X153738Y542824D02*
Y547914D01*
G01X143699Y560934D02*
Y557733D01*
X141880Y555914D01*
G01X120273Y560934D02*
Y555700D01*
G01X123392Y570778D02*
Y574571D01*
X123620Y574799D01*
G01X147045Y580624D02*
Y585714D01*
G01X137006Y580624D02*
Y585398D01*
X136780Y585624D01*
Y585698D01*
G01X123620Y585714D02*
Y580624D01*
G01X130313D02*
Y585664D01*
X130263Y585714D01*
X130163D01*
G01X137006Y542824D02*
Y547598D01*
X136780Y547824D01*
Y547898D01*
G01X132692Y556600D02*
Y553881D01*
X132959Y553614D01*
G01X126966Y560934D02*
Y556573D01*
X126616Y556223D01*
Y553514D01*
G01X147045Y542824D02*
Y547914D01*
G01X123620D02*
Y542824D01*
G01X130313D02*
Y547864D01*
X130263Y547914D01*
X130163D01*
G01X123792Y532800D02*
Y536827D01*
X123620Y536999D01*
G01X120210Y529200D02*
X118692D01*
X116892Y531000D01*
G01X120092Y566900D02*
X120273Y566719D01*
Y560934D01*
G01X120092Y566900D02*
X119532D01*
X117632Y568800D01*
X115892D01*
G01X112392D02*
Y567300D01*
X113692Y566000D01*
G01X113392Y531000D02*
Y530000D01*
X114792Y528600D01*
G01X120292Y532800D02*
X119892Y533200D01*
Y536983D01*
G01X113392Y534500D02*
X116892D01*
G01X109892D02*
X113392D01*
G01X119892Y536983D02*
X117409Y534500D01*
X116892D01*
G01X119892Y570778D02*
Y574700D01*
G01X115892Y572300D02*
X112392D01*
G01D02*
X108892D01*
G01X119892Y574700D02*
X119210D01*
X116810Y572300D01*
X115892D01*
G01X120273Y580624D02*
Y585319D01*
X119892Y585700D01*
G01X116392Y608500D02*
Y607500D01*
X118992Y604900D01*
X120092D01*
G01X150392Y598734D02*
Y591415D01*
X150391Y591414D01*
G01X157084Y598734D02*
Y591414D01*
G01X163777Y598734D02*
Y591664D01*
X163427Y591314D01*
G01X169492Y594888D02*
Y591642D01*
G01X143699Y598734D02*
Y595533D01*
X141880Y593714D01*
G01X132692Y594400D02*
Y591681D01*
X132959Y591414D01*
G01X120273Y598734D02*
Y593081D01*
X117892Y590700D01*
X116992D01*
G01X126966Y598734D02*
Y594373D01*
X126616Y594023D01*
Y591314D01*
G01X123392Y608800D02*
Y612371D01*
X123620Y612599D01*
G01X112892Y608500D02*
Y606500D01*
X114792Y604600D01*
G01X112892Y612000D02*
X109392D01*
G01X116392D02*
X112892D01*
G01X116392D02*
X119309D01*
X119892Y612583D01*
G01D02*
Y608800D01*
G01X210628Y4023D02*
Y8798D01*
X210402Y9024D01*
Y9098D01*
G01Y-1801D02*
X210628Y-1575D01*
Y4023D01*
G01X190549D02*
Y-1751D01*
G01Y9114D02*
Y4023D01*
G01X197242D02*
Y-1801D01*
G01Y9114D02*
Y4023D01*
G01X193896Y22133D02*
Y20775D01*
X193895Y20774D01*
Y14814D01*
G01Y29949D02*
X193896Y29948D01*
Y22133D01*
G01X187203D02*
Y29948D01*
X187202Y29949D01*
G01Y14814D02*
Y20974D01*
X187203Y20975D01*
Y22133D01*
G01X206292Y17800D02*
Y15103D01*
X206581Y14814D01*
G01Y30100D02*
X207281Y29400D01*
Y22133D01*
G01X220667Y-1751D02*
Y4023D01*
G01D02*
Y9114D01*
G01X227360D02*
Y4023D01*
G01D02*
Y-1751D01*
G01X230707Y22133D02*
Y29948D01*
X230706Y29949D01*
G01Y14814D02*
Y21174D01*
X230707Y21175D01*
Y22133D01*
G01X217321D02*
Y26130D01*
X215515Y27936D01*
G01X215502Y17114D02*
X217321Y18933D01*
Y22133D01*
G01X224014D02*
Y29948D01*
X224013Y29949D01*
G01Y14814D02*
Y20774D01*
X224014Y20775D01*
Y22133D01*
G01X200202Y29949D02*
X200588Y29563D01*
Y22133D01*
G01D02*
Y15164D01*
X200238Y14814D01*
Y14714D01*
G01X203935Y-1751D02*
Y4023D01*
G01D02*
Y9064D01*
X203885Y9114D01*
X203785D01*
G01X183856Y-1751D02*
Y4023D01*
G01D02*
Y9114D01*
G01X180510Y22133D02*
Y26130D01*
X178704Y27936D01*
G01X178691Y17114D02*
X180510Y18933D01*
Y22133D01*
G01X173817Y4023D02*
Y-1575D01*
X173591Y-1801D01*
G01Y9098D02*
Y9024D01*
X173817Y8798D01*
Y4023D01*
G01X200588Y59933D02*
Y67363D01*
X200202Y67749D01*
G01X200238Y52514D02*
Y52614D01*
X200588Y52964D01*
Y59933D01*
G01X193896D02*
Y67748D01*
X193895Y67749D01*
G01Y52614D02*
Y58574D01*
X193896Y58575D01*
Y59933D01*
G01X187202Y67749D02*
X187203Y67748D01*
Y59933D01*
G01D02*
Y58775D01*
X187202Y58774D01*
Y52614D01*
G01X203935Y36049D02*
Y41823D01*
G01D02*
Y46864D01*
X203885Y46914D01*
X203785D01*
G01X210628Y41823D02*
Y46598D01*
X210402Y46824D01*
Y46898D01*
G01Y35999D02*
X210628Y36225D01*
Y41823D01*
G01X197242Y84714D02*
Y79623D01*
G01D02*
Y73799D01*
G01X224014Y59933D02*
Y67748D01*
X224013Y67749D01*
G01Y52614D02*
Y58574D01*
X224014Y58575D01*
Y59933D01*
G01X230706Y67749D02*
X230707Y67748D01*
Y59933D01*
G01D02*
Y58975D01*
X230706Y58974D01*
Y52614D01*
G01X224014Y97733D02*
Y96375D01*
X224013Y96374D01*
Y90414D01*
G01X230706D02*
Y96774D01*
X230707Y96775D01*
Y97733D01*
G01X227360Y79623D02*
Y73849D01*
G01Y84714D02*
Y79623D01*
G01X220667D02*
Y84714D01*
G01Y73849D02*
Y79623D01*
G01X217321Y97733D02*
Y94533D01*
X215502Y92714D01*
G01X220667Y36049D02*
Y41823D01*
G01D02*
Y46914D01*
G01X227360Y41823D02*
Y46914D01*
G01Y36049D02*
Y41823D01*
G01X217321Y59933D02*
Y63930D01*
X215515Y65736D01*
G01X215502Y54914D02*
X217321Y56733D01*
Y59933D01*
G01X187203Y97733D02*
Y96575D01*
X187202Y96574D01*
Y90414D01*
G01X200588Y97733D02*
Y90764D01*
X200238Y90414D01*
Y90314D01*
G01X206292Y93400D02*
Y90703D01*
X206581Y90414D01*
G01X193896Y97733D02*
Y96375D01*
X193895Y96374D01*
Y90414D01*
G01X203935Y73849D02*
Y79623D01*
G01D02*
Y84664D01*
X203885Y84714D01*
X203785D01*
G01X190549Y79623D02*
Y84714D01*
G01Y73849D02*
Y79623D01*
G01X210402Y73799D02*
X210628Y74025D01*
Y79623D01*
G01D02*
Y84398D01*
X210402Y84624D01*
Y84698D01*
G01X207281Y59933D02*
Y67200D01*
X206581Y67900D01*
G01Y52614D02*
X206292Y52903D01*
Y55600D01*
G01X197242Y41823D02*
Y46914D01*
G01Y35999D02*
Y41823D01*
G01X190549D02*
Y46914D01*
G01Y36049D02*
Y41823D01*
G01X180510Y59933D02*
Y63930D01*
X178704Y65736D01*
G01X178691Y54914D02*
X180510Y56733D01*
Y59933D01*
G01X173817Y79623D02*
Y84398D01*
X173591Y84624D01*
Y84698D01*
G01Y73799D02*
X173817Y74025D01*
Y79623D01*
G01X183856D02*
Y84714D01*
G01Y73849D02*
Y79623D01*
G01X173817Y41823D02*
Y36225D01*
X173591Y35999D01*
G01Y46898D02*
Y46824D01*
X173817Y46598D01*
Y41823D01*
G01X183856D02*
Y46914D01*
G01Y36049D02*
Y41823D01*
G01X180510Y97733D02*
Y94533D01*
X178691Y92714D01*
G01X230707Y97733D02*
Y100938D01*
X234053Y104284D01*
G01X227360Y505024D02*
Y510114D01*
G01X220667Y505024D02*
Y510114D01*
G01X224014Y523134D02*
Y521775D01*
X224013Y521774D01*
Y515814D01*
G01X230707Y523134D02*
Y522175D01*
X230706Y522174D01*
Y515814D01*
G01X217321Y523134D02*
Y519933D01*
X215502Y518114D01*
G01X193896Y523134D02*
Y521775D01*
X193895Y521774D01*
Y515814D01*
G01X187203Y523134D02*
Y521975D01*
X187202Y521974D01*
Y515814D01*
G01X210628Y505024D02*
Y509798D01*
X210402Y510024D01*
Y510098D01*
G01X206292Y518800D02*
Y516103D01*
X206581Y515814D01*
G01X203935Y505024D02*
Y510064D01*
X203885Y510114D01*
X203785D01*
G01X197242D02*
Y505024D01*
G01X190549D02*
Y510114D01*
G01X183856Y505024D02*
Y510114D01*
G01X200588Y523134D02*
Y516164D01*
X200238Y515814D01*
Y515714D01*
G01X180510Y523134D02*
Y519933D01*
X178691Y518114D01*
G01X173817Y505024D02*
Y509798D01*
X173591Y510024D01*
Y510098D01*
G01X227360Y542824D02*
Y547914D01*
G01X220667Y542824D02*
Y547914D01*
G01X227360Y580624D02*
Y585714D01*
G01X220667Y580624D02*
Y585714D01*
G01X217321Y560934D02*
Y557733D01*
X215502Y555914D01*
G01X224014Y560934D02*
Y559575D01*
X224013Y559574D01*
Y553614D01*
G01X230707Y560934D02*
Y559975D01*
X230706Y559974D01*
Y553614D01*
G01X210628Y580624D02*
Y585398D01*
X210402Y585624D01*
Y585698D01*
G01X203935Y580624D02*
Y585664D01*
X203885Y585714D01*
X203785D01*
G01X190549Y580624D02*
Y585714D01*
G01X183856Y580624D02*
Y585714D01*
G01X197242D02*
Y580624D01*
G01X173817D02*
Y585398D01*
X173591Y585624D01*
Y585698D01*
G01X180510Y560934D02*
Y557733D01*
X178691Y555914D01*
G01X190549Y542824D02*
Y547914D01*
G01X183856Y542824D02*
Y547914D01*
G01X206292Y556600D02*
Y553903D01*
X206581Y553614D01*
G01X210628Y542824D02*
Y547598D01*
X210402Y547824D01*
Y547898D01*
G01X200588Y560934D02*
Y553964D01*
X200238Y553614D01*
Y553514D01*
G01X193896Y560934D02*
Y559575D01*
X193895Y559574D01*
Y553614D01*
G01X187203Y560934D02*
Y559775D01*
X187202Y559774D01*
Y553614D01*
G01X197242Y547914D02*
Y542824D01*
G01X203935D02*
Y547864D01*
X203885Y547914D01*
X203785D01*
G01X173817Y542824D02*
Y547598D01*
X173591Y547824D01*
Y547898D01*
G01X217321Y598734D02*
Y595533D01*
X215502Y593714D01*
G01X224014Y598734D02*
Y597375D01*
X224013Y597374D01*
Y591414D01*
G01X230707Y598734D02*
Y597775D01*
X230706Y597774D01*
Y591414D01*
G01X206292Y594400D02*
Y591703D01*
X206581Y591414D01*
G01X193896Y598734D02*
Y597375D01*
X193895Y597374D01*
Y591414D01*
G01X187203Y598734D02*
Y597575D01*
X187202Y597574D01*
Y591414D01*
G01X200588Y598734D02*
Y591764D01*
X200238Y591414D01*
Y591314D01*
G01X180510Y598734D02*
Y595533D01*
X178691Y593714D01*
G01X264171Y-1751D02*
Y4023D01*
G01D02*
Y9114D01*
G01X240746Y4023D02*
Y9064D01*
X240696Y9114D01*
X240596D01*
G01X240746Y-1751D02*
Y4023D01*
G01X247213Y-1801D02*
X247439Y-1575D01*
Y4023D01*
G01D02*
Y8798D01*
X247213Y9024D01*
Y9098D01*
G01X234053Y4023D02*
Y-1801D01*
G01Y9114D02*
Y4023D01*
G01X267518Y22133D02*
Y29948D01*
X267517Y29949D01*
G01Y14814D02*
Y20974D01*
X267518Y20975D01*
Y22133D01*
G01X277557Y4023D02*
Y8964D01*
X277407Y9114D01*
G01X277557Y-1751D02*
Y4023D01*
G01X289124Y17114D02*
X290943Y18933D01*
Y22133D01*
G01D02*
Y26130D01*
X289137Y27936D01*
G01X280903Y22133D02*
Y29400D01*
X280203Y30100D01*
G01Y14814D02*
X279903Y15114D01*
Y17700D01*
G01X280203Y30100D02*
X277557Y32746D01*
Y36049D01*
G01X273824Y29949D02*
X274210Y29563D01*
Y22133D01*
G01D02*
Y15164D01*
X273860Y14814D01*
Y14714D01*
G01X284250Y4023D02*
Y-1575D01*
X284024Y-1801D01*
G01Y9098D02*
Y9024D01*
X284250Y8798D01*
Y4023D01*
G01X237399Y22133D02*
Y29563D01*
X237013Y29949D01*
G01X237049Y14714D02*
Y14814D01*
X237399Y15164D01*
Y22133D01*
G01X260825D02*
Y29948D01*
X260824Y29949D01*
G01Y14814D02*
Y20674D01*
X260825Y20675D01*
Y22133D01*
G01X244092D02*
Y29400D01*
X243392Y30100D01*
G01Y14814D02*
X243092Y15114D01*
Y17700D01*
G01X254132Y22133D02*
Y26130D01*
X252326Y27936D01*
G01X252313Y17114D02*
X254132Y18933D01*
Y22133D01*
G01X257478Y-1751D02*
Y4023D01*
G01D02*
Y9114D01*
G01X270864Y-1801D02*
Y4023D01*
G01D02*
Y9114D01*
G01X267517Y67749D02*
X267518Y67748D01*
Y59933D01*
G01D02*
Y58775D01*
X267517Y58774D01*
Y52614D01*
G01X243392Y67900D02*
X244092Y67200D01*
Y59933D01*
G01X243092Y55500D02*
Y52914D01*
X243392Y52614D01*
G01X247439Y41823D02*
Y46598D01*
X247213Y46824D01*
Y46898D01*
G01Y35999D02*
X247439Y36225D01*
Y41823D01*
G01X257478Y36049D02*
Y41823D01*
G01D02*
Y46914D01*
G01X240746Y41823D02*
Y46864D01*
X240696Y46914D01*
X240596D01*
G01X240746Y36049D02*
Y41823D01*
G01X264171Y36049D02*
Y41823D01*
G01D02*
Y46914D01*
G01X237013Y67749D02*
X237399Y67363D01*
Y59933D01*
G01D02*
Y52964D01*
X237049Y52614D01*
Y52514D01*
G01X270864Y73799D02*
Y79623D01*
G01D02*
Y84714D01*
G01X280903Y59933D02*
Y67200D01*
X280203Y67900D01*
G01Y52614D02*
X279903Y52914D01*
Y55500D01*
G01X284024Y73799D02*
X284250Y74025D01*
Y79623D01*
G01D02*
Y84398D01*
X284024Y84624D01*
Y84698D01*
G01X277407Y73849D02*
X277557Y73999D01*
Y79623D01*
G01D02*
Y84564D01*
X277407Y84714D01*
G01X273860Y90314D02*
Y90414D01*
X274210Y90764D01*
Y97733D01*
G01X280203Y90414D02*
X279903Y90714D01*
Y93300D01*
G01X289124Y92714D02*
X290943Y94533D01*
Y97733D01*
G01Y59933D02*
Y56733D01*
X289124Y54914D01*
G01X284250Y41823D02*
Y46598D01*
X284024Y46824D01*
Y46898D01*
G01Y35999D02*
X284250Y36225D01*
Y41823D01*
G01X277557D02*
Y46764D01*
X277407Y46914D01*
G01X277557Y36049D02*
Y41823D01*
G01X274210Y59933D02*
Y67363D01*
X273824Y67749D01*
G01X267517Y90414D02*
Y96574D01*
X267518Y96575D01*
Y97733D01*
G01X260824Y90414D02*
Y96274D01*
X260825Y96275D01*
Y97733D01*
G01X252313Y92714D02*
X254132Y94533D01*
Y97733D01*
G01X243392Y90414D02*
X243092Y90714D01*
Y93300D01*
G01X237049Y90314D02*
Y90414D01*
X237399Y90764D01*
Y97733D01*
G01X234053Y84714D02*
Y79623D01*
G01D02*
Y73799D01*
G01X240746Y79623D02*
Y84664D01*
X240696Y84714D01*
X240596D01*
G01X240746Y73849D02*
Y79623D01*
G01X264171D02*
Y73849D01*
G01Y84714D02*
Y79623D01*
G01X257478Y84714D02*
Y79623D01*
G01D02*
Y73849D01*
G01X247213Y73799D02*
X247439Y74025D01*
Y79623D01*
G01D02*
Y84398D01*
X247213Y84624D01*
Y84698D01*
G01X234053Y41823D02*
Y35999D01*
G01Y46914D02*
Y41823D01*
G01X270864D02*
Y46914D01*
G01Y35999D02*
Y41823D01*
G01X260824Y67749D02*
X260825Y67748D01*
Y59933D01*
G01D02*
Y58475D01*
X260824Y58474D01*
Y52614D01*
G01X254132Y59933D02*
Y63930D01*
X252326Y65736D01*
G01X252313Y54914D02*
X254132Y56733D01*
Y59933D01*
G01X274210Y97733D02*
Y101087D01*
X277407Y104284D01*
G01X280903Y97733D02*
Y102118D01*
X284050Y105265D01*
G01X290943Y97733D02*
Y103245D01*
X289137Y105051D01*
G01X267518Y97733D02*
Y100938D01*
X270864Y104284D01*
G01X260825Y97733D02*
Y100938D01*
X264171Y104284D01*
G01X254132Y97733D02*
Y103245D01*
X252326Y105051D01*
G01X244092Y97733D02*
Y102118D01*
X247239Y105265D01*
G01X237399Y97733D02*
Y101087D01*
X240596Y104284D01*
G01X249200Y358800D02*
Y362800D01*
G01Y354300D02*
Y358800D01*
G01Y349800D02*
Y354300D01*
G01X274210Y523134D02*
Y516164D01*
X273860Y515814D01*
Y515714D01*
G01X277557Y505024D02*
Y509964D01*
X277407Y510114D01*
G01X279903Y518700D02*
Y516114D01*
X280203Y515814D01*
G01X290943Y523134D02*
Y519933D01*
X289124Y518114D01*
G01X284250Y505024D02*
Y509798D01*
X284024Y510024D01*
Y510098D01*
G01X234053Y505024D02*
Y510114D01*
G01X260825Y523134D02*
Y521675D01*
X260824Y521674D01*
Y515814D01*
G01X237399Y523134D02*
Y516164D01*
X237049Y515814D01*
Y515714D01*
G01X243092Y518700D02*
Y516114D01*
X243392Y515814D01*
G01X254132Y523134D02*
Y519933D01*
X252313Y518114D01*
G01X264171Y505024D02*
Y510114D01*
G01X257478Y505024D02*
Y510114D01*
G01X267518Y523134D02*
Y521975D01*
X267517Y521974D01*
Y515814D01*
G01X270864Y505024D02*
Y510114D01*
G01X247439Y505024D02*
Y509798D01*
X247213Y510024D01*
Y510098D01*
G01X240746Y505024D02*
Y510064D01*
X240696Y510114D01*
X240596D01*
G01X290943Y560934D02*
Y557733D01*
X289124Y555914D01*
G01X277557Y580624D02*
Y585564D01*
X277407Y585714D01*
G01X284250Y580624D02*
Y585398D01*
X284024Y585624D01*
Y585698D01*
G01X274210Y560934D02*
Y553964D01*
X273860Y553614D01*
Y553514D01*
G01X277557Y542824D02*
Y547764D01*
X277407Y547914D01*
G01X279903Y556500D02*
Y553914D01*
X280203Y553614D01*
G01X284250Y542824D02*
Y547598D01*
X284024Y547824D01*
Y547898D01*
G01X264171Y542824D02*
Y547914D01*
G01X257478Y542824D02*
Y547914D01*
G01X247439Y542824D02*
Y547598D01*
X247213Y547824D01*
Y547898D01*
G01X240746Y542824D02*
Y547864D01*
X240696Y547914D01*
X240596D01*
G01X234053Y542824D02*
Y547914D01*
G01X267518Y560934D02*
Y559775D01*
X267517Y559774D01*
Y553614D01*
G01X270864Y542824D02*
Y547914D01*
G01X260825Y560934D02*
Y559475D01*
X260824Y559474D01*
Y553614D01*
G01X254132Y560934D02*
Y557733D01*
X252313Y555914D01*
G01X264171Y580624D02*
Y585714D01*
G01X257478Y580624D02*
Y585714D01*
G01X234053D02*
Y580624D01*
G01X270864D02*
Y585714D01*
G01X247439Y580624D02*
Y585398D01*
X247213Y585624D01*
Y585698D01*
G01X240746Y580624D02*
Y585664D01*
X240696Y585714D01*
X240596D01*
G01X237399Y560934D02*
Y553964D01*
X237049Y553614D01*
Y553514D01*
G01X243092Y556500D02*
Y553914D01*
X243392Y553614D01*
G01X274210Y598734D02*
Y591764D01*
X273860Y591414D01*
Y591314D01*
G01X279903Y594300D02*
Y591714D01*
X280203Y591414D01*
G01X290943Y598734D02*
Y595533D01*
X289124Y593714D01*
G01X260825Y598734D02*
Y597275D01*
X260824Y597274D01*
Y591414D01*
G01X237399Y598734D02*
Y591764D01*
X237049Y591414D01*
Y591314D01*
G01X243092Y594300D02*
Y591714D01*
X243392Y591414D01*
G01X254132Y598734D02*
Y595533D01*
X252313Y593714D01*
G01X267518Y598734D02*
Y597575D01*
X267517Y597574D01*
Y591414D01*
G01X294289Y4023D02*
Y-1751D01*
G01Y9114D02*
Y4023D01*
G01X300982D02*
Y-1751D01*
G01Y9114D02*
Y4023D01*
G01X307675D02*
Y-1843D01*
G01Y9300D02*
Y4023D01*
G01X297636Y22133D02*
Y29948D01*
X297635Y29949D01*
G01Y14814D02*
Y20674D01*
X297636Y20675D01*
Y22133D01*
G01X353500Y13200D02*
X354614Y14314D01*
X357492D01*
G01X324642Y13200D02*
X321192D01*
G01X312342D02*
X307992D01*
G01X304328Y14814D02*
X304329Y14815D01*
Y22133D01*
G01X353500Y32100D02*
X356286D01*
X357650Y30736D01*
X358592D01*
G01X304329Y22133D02*
Y29948D01*
G01D02*
X304328Y29949D01*
G01X311021Y22133D02*
Y28014D01*
G01Y17057D02*
Y22133D01*
G01X317714D02*
Y28014D01*
G01Y17057D02*
Y22133D01*
G01X327754Y28014D02*
Y22133D01*
G01D02*
Y17057D01*
G01X337793Y28014D02*
Y22133D01*
G01D02*
Y17057D01*
G01X347833Y22133D02*
Y17057D01*
G01Y28022D02*
Y22133D01*
G01X341140Y-1743D02*
Y4023D01*
G01D02*
Y9122D01*
G01X351179Y4023D02*
Y9122D01*
G01Y-4536D02*
Y4023D01*
G01X331100D02*
Y9114D01*
G01Y-4536D02*
Y4023D01*
G01X321061Y-1743D02*
Y4023D01*
G01D02*
Y9114D01*
G01X314368Y-1843D02*
Y4023D01*
G01D02*
Y9114D01*
G01X304328Y52614D02*
X304329Y52615D01*
Y59933D01*
G01X294289Y36049D02*
Y41823D01*
G01D02*
Y46914D01*
G01X300982Y41823D02*
Y46914D01*
G01Y36049D02*
Y41823D01*
G01X297636Y59933D02*
Y67748D01*
X297635Y67749D01*
G01Y52614D02*
Y58474D01*
X297636Y58475D01*
Y59933D01*
G01X307675Y35957D02*
Y41823D01*
G01D02*
Y49103D01*
X307950Y49378D01*
Y50729D01*
G01X337642Y69900D02*
X334292D01*
G01X353500D02*
X355065Y68335D01*
X357772D01*
G01X337642Y51000D02*
X334292D01*
G01X353500D02*
X354833Y52333D01*
X357762D01*
G01X324642Y69900D02*
X321334D01*
G01X304278Y90414D02*
X304328Y90464D01*
Y96074D01*
X304329Y96075D01*
Y97733D01*
G01X324642Y51000D02*
X321192D01*
G01X297636Y97733D02*
Y96275D01*
X297635Y96274D01*
Y90414D01*
G01X307675Y79623D02*
Y86903D01*
X308166Y87394D01*
G01X294289Y73849D02*
Y79623D01*
G01D02*
Y84714D01*
G01X300982Y79623D02*
Y84714D01*
G01Y73849D02*
Y79623D01*
G01X307950Y50729D02*
X308221Y51000D01*
X312342D01*
G01X304329Y59933D02*
Y67748D01*
G01X307592Y73800D02*
X307675Y73883D01*
G01X304329Y67748D02*
X304328Y67749D01*
G01X307675Y73883D02*
Y79623D01*
G01X347833Y92757D02*
Y97733D01*
G01X314368Y41823D02*
Y35957D01*
G01Y46914D02*
Y41823D01*
G01X321061D02*
Y46914D01*
G01Y35957D02*
Y41823D01*
G01X327754Y54857D02*
Y59933D01*
G01D02*
Y65814D01*
G01X331100Y79623D02*
Y84714D01*
G01Y73757D02*
Y79623D01*
G01X337793Y65814D02*
Y59933D01*
G01D02*
Y54857D01*
G01X341140Y46922D02*
Y41823D01*
G01D02*
Y35957D01*
G01X351179Y79623D02*
Y73757D01*
G01Y84599D02*
Y79623D01*
G01X337793Y97733D02*
Y89964D01*
G01X341140Y73757D02*
Y79623D01*
G01X321061D02*
Y87392D01*
G01X311021Y97733D02*
Y89964D01*
G01X314368Y73757D02*
Y79623D01*
G01X321061Y73757D02*
Y79623D01*
G01X341140Y87392D02*
Y79623D01*
G01X351179Y41823D02*
Y35957D01*
G01Y46922D02*
Y41823D01*
G01X347833Y65822D02*
Y59933D01*
G01D02*
Y54857D01*
G01X317714Y89964D02*
Y97733D01*
G01X314368Y87392D02*
Y79623D01*
G01X331100Y41823D02*
Y35957D01*
G01Y46914D02*
Y41823D01*
G01X317714Y59933D02*
Y65814D01*
G01Y54857D02*
Y59933D01*
G01X311021D02*
Y65814D01*
G01Y54857D02*
Y59933D01*
G01X327754Y92757D02*
Y97733D01*
G01X307492Y109500D02*
Y107200D01*
X305292Y105000D01*
X304192D01*
G01D02*
X304329Y104863D01*
Y97733D01*
G01X323292Y104900D02*
Y107100D01*
G01X312992Y109500D02*
Y106370D01*
X313637Y105725D01*
G01D02*
X317714Y101648D01*
Y97733D01*
G01X307675Y505023D02*
Y505024D01*
G01X304329Y523133D02*
Y521475D01*
X304328Y521474D01*
Y515864D01*
X304278Y515814D01*
G01X297636Y523134D02*
Y521675D01*
X297635Y521674D01*
Y515814D01*
G01X307675Y505024D02*
Y512303D01*
X308166Y512794D01*
G01X300982Y505024D02*
Y510114D01*
G01X294289Y505024D02*
Y510114D01*
G01X323670Y494675D02*
Y499276D01*
X324187Y499793D01*
G01X311021Y523134D02*
Y515364D01*
G01X321061Y505024D02*
Y512792D01*
G01X337793Y523134D02*
Y515364D01*
G01Y523134D02*
Y528899D01*
G01X327754Y523134D02*
Y529014D01*
G01Y518157D02*
Y523134D01*
G01X331100Y505024D02*
Y510114D01*
G01X317714Y529014D02*
Y523134D01*
G01X311021D02*
Y529014D01*
G01X341140Y512792D02*
Y505024D01*
G01X337793Y515364D02*
X338568D01*
X341140Y512792D01*
G01X311021Y515364D02*
X313593Y512792D01*
X314368D01*
G01D02*
Y505024D01*
G01X311701Y499136D02*
X313192Y497645D01*
Y495600D01*
G01X321061Y512792D02*
X320286D01*
X317714Y515364D01*
G01D02*
Y523134D01*
G01X347833D02*
Y529022D01*
G01Y523134D02*
Y518157D01*
G01X311701Y499136D02*
X312238D01*
G01X318170Y494675D02*
Y498060D01*
G01X350882Y509999D02*
X351179Y509702D01*
G01X312238Y499136D02*
X314368Y501266D01*
Y505024D01*
G01X318170Y498060D02*
X321061Y500951D01*
Y505024D01*
G01X351179Y509702D02*
Y505024D01*
G01X353500Y533100D02*
X354036D01*
X355590Y531546D01*
X357661D01*
G01X353500Y552000D02*
X354989Y550511D01*
X357539D01*
G01X337642Y552000D02*
X334292D01*
G01X337642Y533100D02*
X334292D01*
G01X353500Y589800D02*
X354934Y588366D01*
X356798D01*
G01X300982Y580624D02*
Y585714D01*
G01X294289Y580624D02*
Y585714D01*
G01X307848Y588334D02*
Y588076D01*
X307675Y587903D01*
Y580624D01*
G01D02*
Y580623D01*
G01X312342Y552000D02*
X308100D01*
G01X324642D02*
X321123D01*
G01X324642Y533100D02*
X321334D01*
G01X304278Y553614D02*
X304328Y553664D01*
Y559274D01*
X304329Y559275D01*
Y560933D01*
G01X307675Y542823D02*
Y542824D01*
G01X297636Y560934D02*
Y559475D01*
X297635Y559474D01*
Y553614D01*
G01X307675Y542824D02*
Y548200D01*
G01X300982Y542824D02*
Y547914D01*
G01X294289Y542824D02*
Y547914D01*
G01X353500Y570900D02*
X354926Y569474D01*
X357724D01*
G01X351179Y585722D02*
Y580624D01*
G01X347833Y560934D02*
Y566822D01*
G01X341140Y547922D02*
Y542824D01*
G01X351179Y547922D02*
Y542824D01*
G01X337793Y560934D02*
Y566814D01*
G01X341140Y580624D02*
Y585722D01*
G01X331100Y580624D02*
Y585714D01*
G01X317714Y560934D02*
Y566814D01*
G01X321061Y585714D02*
Y580624D01*
G01X314368D02*
Y574757D01*
G01Y585714D02*
Y580624D01*
G01X311021Y560934D02*
Y566814D01*
G01X321061Y547914D02*
Y542824D01*
G01X331100D02*
Y547914D01*
G01X314368D02*
Y542824D01*
G01X327754Y560934D02*
Y566814D01*
G01X351179Y574757D02*
Y580624D01*
G01X337793Y560934D02*
Y555857D01*
G01X347833Y560934D02*
Y555857D01*
G01X341140Y580624D02*
Y574757D01*
G01Y542824D02*
Y537057D01*
G01X351179Y542824D02*
Y537013D01*
G01X331100Y580624D02*
Y574757D01*
G01X321061D02*
Y580624D01*
G01X314368Y536957D02*
Y542824D01*
G01X311021Y560934D02*
Y555857D01*
G01X317714Y560934D02*
Y555857D01*
G01X327754Y560934D02*
Y555857D01*
G01X321061Y542824D02*
Y537057D01*
G01X331100Y542824D02*
Y537308D01*
G01X337642Y589800D02*
X334292D01*
G01X324642D02*
X321192D01*
G01X297636Y598734D02*
Y597275D01*
X297635Y597274D01*
Y591414D01*
G01X304329Y598734D02*
Y597075D01*
X304328Y597074D01*
Y591464D01*
X304278Y591414D01*
G01X347833Y598734D02*
Y593657D01*
G01Y607292D02*
Y598734D01*
G01X337793Y604499D02*
Y598734D01*
G01D02*
Y593657D01*
G01X327754Y607292D02*
Y598734D01*
G01X317714Y604614D02*
Y598734D01*
G01X311021D02*
Y604614D01*
G01X327754Y598734D02*
Y593657D01*
G01X311021Y598734D02*
Y593657D01*
G01X317714D02*
Y598734D01*
G01X362392Y31800D02*
X360850Y33342D01*
X358619D01*
G01X380792Y24933D02*
Y27812D01*
G01X404700Y32100D02*
X408184D01*
G01X358619Y33342D02*
Y30763D01*
X358592Y30736D01*
G01X357492Y14314D02*
Y11714D01*
G01X380792Y27812D02*
Y30878D01*
X379692Y31978D01*
G01X377592Y-10880D02*
X377612Y-10900D01*
X380232D01*
G01X357492Y11714D02*
X359928D01*
X361042Y12828D01*
Y13078D01*
G01X357872Y-1858D02*
Y4023D01*
G01X398029D02*
Y9107D01*
G01Y-4536D02*
Y4023D01*
G01X411415Y22133D02*
X411416Y22134D01*
Y28022D01*
G01X408069Y9107D02*
Y4023D01*
G01D02*
Y-1742D01*
X408068Y-1743D01*
G01X357872Y22133D02*
Y17014D01*
G01Y28014D02*
Y22133D01*
G01X367911D02*
Y17042D01*
G01Y28014D02*
Y22133D01*
G01Y4023D02*
Y9114D01*
G01Y-1858D02*
Y4023D01*
G01X415892Y-15000D02*
Y-11917D01*
X418108Y-9701D01*
G01X411416Y17057D02*
X411415Y17058D01*
G01X357672Y9114D02*
X357872Y8914D01*
G01X401377Y28022D02*
X401376Y28021D01*
G01X411415Y17058D02*
Y22133D01*
G01X357872Y8914D02*
Y4023D01*
G01X401376Y28021D02*
Y22133D01*
G01X374292Y74100D02*
Y77200D01*
G01X404700Y69900D02*
X408184D01*
G01X404700Y51000D02*
X408184D01*
G01X357772Y68335D02*
Y70935D01*
G01X361592Y69400D02*
X360057Y70935D01*
X357772D01*
G01X367911Y79623D02*
Y87500D01*
G01X357872Y65736D02*
Y59933D01*
G01X398029Y41823D02*
Y35942D01*
G01Y46907D02*
Y41823D01*
G01Y79623D02*
Y73742D01*
G01X411415Y97733D02*
Y89964D01*
G01X408069Y73742D02*
Y79623D01*
G01X411416Y54857D02*
Y54957D01*
X411415Y54958D01*
Y59933D01*
G01X408069Y41823D02*
Y46907D01*
G01X401376Y54842D02*
Y59933D01*
G01X357872Y46914D02*
Y41823D01*
G01X398029Y84800D02*
Y79623D01*
G01X367911Y97733D02*
Y92900D01*
X368311Y92500D01*
G01X357872Y79623D02*
Y87500D01*
G01X411416Y65822D02*
X411415Y65821D01*
G01X401376Y59933D02*
Y65821D01*
G01X401375Y92757D02*
X401376Y92758D01*
G01X408068Y87392D02*
X408069Y87391D01*
G01X358491Y73479D02*
X357872Y74098D01*
G01Y59933D02*
Y55588D01*
G01X357965Y92500D02*
X357887Y92578D01*
Y92689D01*
X357872Y92704D01*
G01X358619Y36031D02*
X357872Y36778D01*
G01X411415Y65821D02*
Y59933D01*
G01X401376Y65821D02*
X401377Y65822D01*
G01X401376Y92758D02*
Y97733D01*
G01X408069Y87391D02*
Y79623D01*
G01X357872Y74098D02*
Y79623D01*
G01Y55588D02*
X358618Y54842D01*
G01X357872Y92704D02*
Y97733D01*
G01Y36778D02*
Y41823D01*
G01X367911Y505024D02*
Y505023D01*
X367913Y505025D01*
Y509066D01*
X366865Y510114D01*
G01X401376Y518158D02*
Y523134D01*
G01X411415D02*
Y529014D01*
G01X401376Y523134D02*
Y528684D01*
G01X411415Y515364D02*
Y523134D01*
G01X367911D02*
Y529057D01*
G01X357872Y505024D02*
Y509068D01*
X358918Y510114D01*
G01X357872Y528899D02*
Y523134D01*
G01X366865Y510114D02*
Y515152D01*
G01X357872Y523134D02*
Y516370D01*
G01X366865Y515152D02*
X367913Y516200D01*
G01X357872Y516370D02*
X359042Y515200D01*
G01X367913Y516200D02*
Y523131D01*
X367911Y523133D01*
Y523134D01*
G01X357661Y531546D02*
Y534000D01*
G01X356798Y588366D02*
Y590939D01*
G01X404700Y552000D02*
X408184D01*
G01X357724Y571973D02*
Y569474D01*
G01X360982Y570460D02*
X359469Y571973D01*
X357724D01*
G01X376785Y538305D02*
X379055Y536035D01*
Y533771D01*
X378262Y532978D01*
G01X401376Y555842D02*
Y560934D01*
G01X408069Y580624D02*
Y585707D01*
G01X398029Y580624D02*
Y585707D01*
G01Y542824D02*
Y547907D01*
G01X408069D02*
Y542824D01*
G01Y574742D02*
Y580624D01*
G01X398029Y574742D02*
Y580624D01*
G01Y542824D02*
Y536942D01*
G01X408069Y542824D02*
Y537058D01*
G01X357872Y580624D02*
Y574742D01*
G01X357025Y585714D02*
X357872Y584867D01*
Y580624D01*
G01X367911Y560934D02*
Y566095D01*
G01X357910Y566814D02*
X357872Y566776D01*
G01X367692Y547914D02*
X367911Y547695D01*
G01Y560934D02*
Y556542D01*
G01X357872Y542824D02*
Y547714D01*
G01Y560934D02*
Y555855D01*
G01X367911Y542824D02*
Y536419D01*
G01X357872Y542824D02*
Y536765D01*
G01X411415Y560934D02*
Y555858D01*
G01Y560934D02*
Y566821D01*
G01X401376Y560934D02*
Y566821D01*
G01X367911Y566095D02*
X367192Y566814D01*
G01X357872Y566776D02*
Y560934D01*
G01Y547714D02*
X357672Y547914D01*
G01X357872Y555855D02*
X357897D01*
X357910Y555842D01*
G01X367911Y547695D02*
Y542824D01*
G01Y556542D02*
X367211Y555842D01*
G01X357872Y536765D02*
X357910Y536727D01*
G01X367911Y536419D02*
X367692Y536200D01*
G01X411415Y555858D02*
X411416Y555857D01*
G01X411415Y566821D02*
X411416Y566822D01*
G01X401376Y566821D02*
X401377Y566822D01*
G01X404700Y589800D02*
X408184D01*
G01X399824Y617756D02*
Y623559D01*
G01X413324Y617756D02*
Y623559D01*
G01X357872Y598734D02*
Y594488D01*
X357026Y593642D01*
G01X367911D02*
Y598734D01*
G01D02*
Y604614D01*
G01X357872D02*
Y598734D01*
G01X408068Y612657D02*
Y616512D01*
X406824Y617756D01*
G01X411415Y604614D02*
Y598734D01*
G01Y604621D02*
Y604614D01*
G01X401376Y598734D02*
Y593642D01*
G01X411416Y593657D02*
Y593757D01*
X411415Y593758D01*
G01X401375Y607292D02*
X401376Y607291D01*
G01X411415Y593758D02*
Y598734D01*
G01X401376Y607291D02*
Y598734D01*
G01X448892Y17000D02*
X448226Y17666D01*
Y22133D01*
G01D02*
Y28100D01*
G01X474998Y4023D02*
Y-1751D01*
G01Y9114D02*
Y4023D01*
G01X454569Y14714D02*
Y14814D01*
X454919Y15164D01*
Y22133D01*
G01X478344Y29949D02*
Y22133D01*
G01D02*
Y14814D01*
G01X417150Y32100D02*
X421368D01*
G01X430150D02*
X433508D01*
G01X469832Y17114D02*
X471651Y18933D01*
Y22133D01*
G01D02*
Y26130D01*
X469845Y27936D01*
G01X460645Y15081D02*
Y17800D01*
G01X461612Y22133D02*
Y29400D01*
X460912Y30100D01*
G01X464732Y-1801D02*
X464958Y-1575D01*
Y4023D01*
G01D02*
Y8798D01*
X464732Y9024D01*
Y9098D01*
G01X458266Y-1751D02*
Y4023D01*
G01D02*
Y9064D01*
X458216Y9114D01*
X458116D01*
G01X451573Y-1801D02*
Y4023D01*
G01D02*
Y9114D01*
G01X454533Y29949D02*
X454919Y29563D01*
G01D02*
Y22133D01*
G01X441533Y28007D02*
Y22133D01*
G01X418108Y17042D02*
Y22133D01*
G01D02*
Y28007D01*
G01X441533Y4023D02*
Y-1843D01*
G01Y9107D02*
Y4023D01*
G01X418108Y9107D02*
Y4023D01*
G01D02*
Y-4536D01*
G01X424801Y9107D02*
Y4023D01*
G01D02*
Y-4536D01*
G01X431494Y9107D02*
Y4023D01*
G01D02*
Y-4536D01*
G01X441533Y22133D02*
Y17042D01*
G01X428149Y17057D02*
X428147Y17059D01*
G01X434842Y17057D02*
X434840Y17059D01*
G01X434842Y28268D02*
Y28022D01*
X434840Y28020D01*
G01X428147Y17059D02*
Y22133D01*
G01X434840Y17059D02*
Y22133D01*
G01Y28020D02*
Y22133D01*
G01X448226Y11100D02*
Y4023D01*
G01X451573Y79623D02*
Y84714D01*
G01Y73799D02*
Y79623D01*
G01X448226D02*
Y84912D01*
X448610Y85296D01*
G01X474998Y41823D02*
Y36049D01*
G01Y46914D02*
Y41823D01*
G01X464958D02*
Y36225D01*
X464732Y35999D01*
G01Y46898D02*
Y46824D01*
X464958Y46598D01*
Y41823D01*
G01X460912Y67900D02*
X461612Y67200D01*
Y59933D01*
G01X460645Y55600D02*
Y52881D01*
G01X464958Y79623D02*
Y84398D01*
X464732Y84624D01*
Y84698D01*
G01Y73799D02*
X464958Y74025D01*
Y79623D01*
G01X458266D02*
Y84664D01*
X458216Y84714D01*
X458116D01*
G01X458266Y73849D02*
Y79623D01*
G01X421368Y69900D02*
X417150D01*
G01X433508D02*
X430150D01*
G01Y51000D02*
X433508D01*
G01X417150D02*
X421368D01*
G01X454919Y97733D02*
Y90764D01*
X454569Y90414D01*
Y90314D01*
G01X460645Y93400D02*
Y90581D01*
X460912Y90314D01*
G01X471651Y97733D02*
Y94533D01*
X469832Y92714D01*
G01X478344Y90414D02*
Y97733D01*
G01X474998Y79623D02*
Y73849D01*
G01Y84714D02*
Y79623D01*
G01X471651Y59933D02*
Y63930D01*
X469845Y65736D01*
G01X469832Y54914D02*
X471651Y56733D01*
Y59933D01*
G01X478344Y67749D02*
Y59933D01*
G01D02*
Y52614D01*
G01X454919Y59933D02*
Y52964D01*
X454569Y52614D01*
Y52514D01*
G01X458266Y41823D02*
Y36049D01*
G01X458116Y46914D02*
X458216D01*
X458266Y46864D01*
Y41823D01*
G01X448226Y97733D02*
Y92614D01*
X448692Y92148D01*
Y89900D01*
G01X451573Y41823D02*
Y35999D01*
G01Y46900D02*
Y41823D01*
G01X448226D02*
Y46684D01*
X448517Y46975D01*
G01X448973Y54883D02*
X448226Y55630D01*
Y59933D01*
G01D02*
Y67689D01*
G01X454919Y59933D02*
Y67363D01*
G01X448599Y73589D02*
X448226Y73962D01*
G01X448414Y35761D02*
X448226Y35949D01*
G01Y67689D02*
X448627Y68090D01*
G01X454919Y67363D02*
X454533Y67749D01*
G01X448226Y73962D02*
Y79623D01*
G01Y35949D02*
Y41823D01*
G01X441533Y46907D02*
Y41823D01*
G01X418108D02*
Y35942D01*
G01Y46907D02*
Y41823D01*
G01X431494Y73742D02*
Y79623D01*
G01X441533Y73742D02*
Y79623D01*
G01D02*
Y87392D01*
G01X418108Y97733D02*
Y89964D01*
G01Y73742D02*
Y79623D01*
G01X424801D02*
Y73742D01*
G01X418108Y84599D02*
Y79623D01*
G01X424801Y41823D02*
Y35942D01*
G01Y46907D02*
Y41823D01*
G01X431494D02*
Y35942D01*
G01Y46907D02*
Y41823D01*
G01X434840Y92500D02*
Y97733D01*
G01X428147Y92500D02*
Y97733D01*
G01X441533Y92500D02*
Y97733D01*
G01X424801Y84800D02*
Y79623D01*
G01X418108Y59933D02*
Y65807D01*
G01Y59933D02*
Y54842D01*
G01X441533Y59933D02*
Y65807D01*
G01Y59933D02*
Y54842D01*
G01X434842Y65822D02*
X434840Y65820D01*
G01X428149Y54857D02*
X428147Y54859D01*
G01X434842Y54857D02*
X434840Y54859D01*
G01X431494Y79623D02*
Y84706D01*
G01X434840Y65820D02*
Y59933D01*
G01X428147Y54859D02*
Y59933D01*
G01X434840Y54859D02*
Y59933D01*
G01X431494Y84706D02*
X431400Y84800D01*
G01X464958Y505024D02*
Y509798D01*
X464732Y510024D01*
Y510098D01*
G01X474998Y505024D02*
Y510114D01*
G01X478344Y523134D02*
Y515814D01*
G01X471651Y519933D02*
X469832Y518114D01*
G01X454919Y523133D02*
Y516164D01*
X454569Y515814D01*
Y515714D01*
G01X458266Y505024D02*
Y510064D01*
X458216Y510114D01*
X458116D01*
G01X451573D02*
Y505024D01*
G01X448226D02*
Y512303D01*
X447735Y512794D01*
G01X448226Y523133D02*
Y518014D01*
X448692Y517548D01*
Y515300D01*
G01X441533Y505024D02*
Y512792D01*
G01X434840Y518157D02*
Y523134D01*
G01X428147Y518157D02*
Y523134D01*
G01X418108D02*
Y515364D01*
G01Y528899D02*
Y523134D01*
G01X428147D02*
Y528955D01*
G01X431494Y509999D02*
Y505024D01*
G01X441533D02*
Y495713D01*
G01Y523134D02*
Y529007D01*
G01Y523134D02*
Y518057D01*
G01X430272Y498722D02*
X431494Y499944D01*
G01D02*
Y505024D01*
G01X434840Y529020D02*
Y523134D01*
G01X474998Y542824D02*
Y547914D01*
G01X478344Y560934D02*
Y553614D01*
G01X464958Y542824D02*
Y547598D01*
X464732Y547824D01*
Y547898D01*
G01X464958Y580624D02*
Y585398D01*
X464732Y585624D01*
Y585698D01*
G01X474998Y580624D02*
Y585714D01*
G01X471651Y560934D02*
Y557733D01*
X469832Y555914D01*
G01X458266Y580624D02*
Y585664D01*
X458216Y585714D01*
X458116D01*
G01X454569Y553514D02*
Y553614D01*
X454919Y553964D01*
Y560933D01*
G01X458266Y542824D02*
Y547864D01*
X458216Y547914D01*
X458116D01*
G01X448226Y560934D02*
Y569200D01*
G01X451573Y580624D02*
Y585714D01*
G01Y580623D02*
Y580624D01*
G01X417150Y552000D02*
X421368D01*
G01X430150D02*
X433508D01*
G01X451573Y547914D02*
Y542824D01*
G01X448226D02*
Y549559D01*
X448510Y549843D01*
G01X442508Y552000D02*
X447592D01*
X448692Y553100D01*
G01D02*
Y555348D01*
X448226Y555814D01*
Y560934D01*
G01X444008Y533100D02*
X445782D01*
X446743Y534061D01*
X448557D01*
G01X451573Y536999D02*
Y542824D01*
G01X448226D02*
Y536929D01*
G01D02*
X448432Y536723D01*
G01X441533Y580624D02*
Y585707D01*
G01X424801Y580624D02*
Y585707D01*
G01X431494Y580624D02*
Y585707D01*
G01X418108Y542824D02*
Y547907D01*
G01X431494D02*
Y542824D01*
G01X424801Y547907D02*
Y542824D01*
G01X441533Y547907D02*
Y542824D01*
G01X418108Y580624D02*
Y585599D01*
G01Y560934D02*
Y566807D01*
G01X441533Y560934D02*
Y566807D01*
G01Y574742D02*
Y580624D01*
G01X431494Y574742D02*
Y580624D01*
G01X424801Y574742D02*
Y580624D01*
G01X418108D02*
Y574742D01*
G01X441533Y555842D02*
Y560934D01*
G01X424801Y536942D02*
Y542824D01*
G01X418108D02*
Y536942D01*
G01X441533Y536957D02*
Y542824D01*
G01X431494D02*
Y537202D01*
G01X418108Y560934D02*
Y555842D01*
G01X434842Y529022D02*
X434840Y529020D01*
G01X428147Y560934D02*
Y555859D01*
G01X434840Y560934D02*
Y555859D01*
G01Y560934D02*
Y566820D01*
G01X428149Y566822D02*
X428147Y566820D01*
G01Y555859D02*
X428149Y555857D01*
G01X434840Y555859D02*
X434842Y555857D01*
G01X434840Y566820D02*
X434842Y566822D01*
G01X428147Y566820D02*
Y560934D01*
G01X448226Y580624D02*
Y587903D01*
X447735Y588394D01*
G01X454919Y598734D02*
Y591764D01*
X454569Y591414D01*
Y591314D01*
G01X478344Y598734D02*
Y591414D01*
G01X471651Y598734D02*
Y595533D01*
X469832Y593714D01*
G01X442508Y589800D02*
X444700D01*
X445800Y590900D01*
X448692D01*
G01X430150Y589800D02*
X433500D01*
G01X417150D02*
X420634D01*
G01X427324Y617756D02*
Y623541D01*
G01X448692Y590900D02*
Y593148D01*
X448226Y593614D01*
Y598734D01*
G01X434324Y617756D02*
Y615630D01*
X431494Y612800D01*
Y609864D01*
G01X420324Y617756D02*
Y615716D01*
X418108Y613500D01*
Y609864D01*
G01X434840Y598734D02*
Y607292D01*
G01X441533Y598734D02*
Y607292D01*
G01X418108Y598734D02*
Y604499D01*
G01X441533Y593642D02*
Y598734D01*
G01X428147D02*
Y607292D01*
G01X418108Y593642D02*
Y598734D01*
G01X428149Y593657D02*
X428147Y593659D01*
G01X434842Y593657D02*
X434840Y593659D01*
G01X428147D02*
Y598734D01*
G01X434840Y593659D02*
Y598734D01*
G01X485037Y22133D02*
Y14814D01*
G01Y29949D02*
Y22133D01*
G01X528155Y29949D02*
X528541Y29563D01*
Y22133D01*
G01D02*
Y15164D01*
X528191Y14814D01*
Y14714D01*
G01X534267Y17800D02*
Y15081D01*
X534534Y14814D01*
G01Y30100D02*
X535234Y29400D01*
Y22133D01*
G01X515155Y29949D02*
Y22133D01*
G01D02*
Y14814D01*
G01X521848Y22133D02*
Y14814D01*
G01Y29949D02*
Y22133D01*
G01X525195Y-1801D02*
Y4023D01*
G01D02*
Y9114D01*
G01X531888Y-1751D02*
Y4023D01*
G01D02*
Y9064D01*
X531838Y9114D01*
X531738D01*
G01X518502Y-1751D02*
Y4023D01*
G01D02*
Y9114D01*
G01X538581Y4023D02*
Y8798D01*
X538355Y9024D01*
Y9098D01*
G01X491380Y14714D02*
Y14814D01*
X491730Y15164D01*
Y22133D01*
G01D02*
Y29563D01*
X491344Y29949D01*
G01X497723Y14814D02*
X497456Y15081D01*
Y17800D01*
G01X498423Y22133D02*
Y29400D01*
X497723Y30100D01*
G01X506644Y17114D02*
X508462Y18932D01*
Y22133D01*
G01D02*
Y26131D01*
X506657Y27936D01*
G01X501770Y4023D02*
Y-1575D01*
X501544Y-1801D01*
G01Y9098D02*
Y9024D01*
X501770Y8798D01*
Y4023D01*
G01X488384Y-1801D02*
Y4023D01*
G01D02*
Y9114D01*
G01X495077Y-1751D02*
Y4023D01*
G01D02*
Y9064D01*
X495027Y9114D01*
X494927D01*
G01X481691Y-1751D02*
Y4023D01*
G01D02*
Y9114D01*
G01X511809Y-1751D02*
Y4023D01*
G01D02*
Y9114D01*
G01X491730Y59933D02*
Y67363D01*
X491344Y67749D01*
G01X491730Y59933D02*
Y52964D01*
X494927Y49767D01*
Y46914D01*
G01X495077Y36049D02*
Y41823D01*
G01X494927Y46914D02*
X495027D01*
X495077Y46864D01*
Y41823D01*
G01X481691Y46914D02*
Y41823D01*
G01D02*
Y36049D01*
G01X488384Y41823D02*
Y35999D01*
G01Y46914D02*
Y41823D01*
G01X501544Y35999D02*
X501770Y36225D01*
Y41823D01*
G01D02*
Y46598D01*
X501544Y46824D01*
Y46898D01*
G01X488384Y73799D02*
Y79623D01*
G01D02*
Y84714D01*
G01X481691Y79623D02*
Y84714D01*
G01Y73849D02*
Y79623D01*
G01X495077D02*
Y84664D01*
X495027Y84714D01*
X494927D01*
G01X495077Y73849D02*
Y79623D01*
G01X501544Y73799D02*
X501770Y74025D01*
Y79623D01*
G01D02*
Y84398D01*
X501544Y84624D01*
Y84698D01*
G01X534534Y67900D02*
X535234Y67200D01*
Y59933D01*
G01X534267Y55600D02*
Y52881D01*
X534534Y52614D01*
G01X528541Y59933D02*
Y67363D01*
X528155Y67749D01*
G01X528541Y59933D02*
Y54051D01*
X531738Y50854D01*
Y46914D01*
G01X531888Y36049D02*
Y41823D01*
G01X538355Y46898D02*
Y46824D01*
X538581Y46598D01*
Y41823D01*
G01D02*
Y36225D01*
X538355Y35999D01*
G01X518502Y84714D02*
Y79623D01*
G01D02*
Y73849D01*
G01X538355Y73799D02*
X538581Y74025D01*
Y79623D01*
G01D02*
Y84472D01*
X538355Y84698D01*
G01X515155Y90414D02*
Y97733D01*
G01X534534Y90414D02*
X534267Y90681D01*
Y93400D01*
G01X521848Y90414D02*
Y97733D01*
G01X528191Y90314D02*
Y90414D01*
X528541Y90764D01*
Y97733D01*
G01X525195Y84714D02*
Y79623D01*
G01D02*
Y73799D01*
G01X531738Y84714D02*
X531888Y84564D01*
Y79623D01*
G01D02*
Y73849D01*
G01X525195Y35999D02*
Y41823D01*
G01D02*
Y46914D01*
G01X521848Y59933D02*
Y67749D01*
G01Y52614D02*
Y59933D01*
G01X515155Y67749D02*
Y59933D01*
G01D02*
Y52614D01*
G01X531738Y46914D02*
X531838D01*
X531888Y46864D01*
Y41823D01*
G01X518502D02*
Y46914D01*
G01Y36049D02*
Y41823D01*
G01X485037Y90414D02*
Y97733D01*
G01X497723Y90414D02*
X497456Y90681D01*
Y93400D01*
G01X491380Y90314D02*
Y90414D01*
X491730Y90764D01*
Y97733D01*
G01X506644Y92714D02*
X508462Y94532D01*
Y97733D01*
G01X511809Y73849D02*
Y79623D01*
G01D02*
Y84714D01*
G01X485037Y67749D02*
Y59933D01*
G01D02*
Y52614D01*
G01X511809Y41823D02*
Y36049D01*
G01Y46914D02*
Y41823D01*
G01X506657Y65736D02*
X508462Y63931D01*
Y59933D01*
G01D02*
Y56732D01*
X506644Y54914D01*
G01X498423Y59933D02*
Y67200D01*
X497723Y67900D01*
G01Y52614D02*
X497456Y52881D01*
Y55600D01*
G01X515155Y97733D02*
Y101002D01*
X518467Y104314D01*
G01X535234Y97733D02*
Y102118D01*
X538381Y105265D01*
G01X521848Y97733D02*
Y101028D01*
X525134Y104314D01*
G01X528541Y97733D02*
Y101117D01*
X531738Y104314D01*
G01X498423Y97733D02*
Y100968D01*
X495077Y104314D01*
G01X491730Y97733D02*
Y101218D01*
X488634Y104314D01*
G01X508462Y97733D02*
Y103246D01*
X506657Y105051D01*
G01X521848Y523134D02*
Y515814D01*
G01X518502Y505024D02*
Y510114D01*
G01X515155Y523134D02*
Y515814D01*
G01X534267Y518800D02*
Y516081D01*
X534534Y515814D01*
G01X528541Y523134D02*
Y516164D01*
X528191Y515814D01*
Y515714D01*
G01X525195Y510114D02*
Y505024D01*
G01X531888D02*
Y510064D01*
X531838Y510114D01*
X531738D01*
G01X538581Y505024D02*
Y509798D01*
X538355Y510024D01*
Y510098D01*
G01X497456Y518800D02*
Y516081D01*
X497723Y515814D01*
G01X508462Y523134D02*
Y519932D01*
X506644Y518114D01*
G01X488384Y510114D02*
Y505024D01*
G01X481691D02*
Y510114D01*
G01X495077Y505024D02*
Y510064D01*
X495027Y510114D01*
X494927D01*
G01X501770Y505024D02*
Y509798D01*
X501544Y510024D01*
Y510098D01*
G01X491730Y523134D02*
Y516164D01*
X491380Y515814D01*
Y515714D01*
G01X485037Y523134D02*
Y515814D01*
G01X511809Y505024D02*
Y510114D01*
G01X518502Y542824D02*
Y547914D01*
G01X521848Y560934D02*
Y553614D01*
G01X525195Y580624D02*
Y585714D01*
G01X531888Y580624D02*
Y585564D01*
X531738Y585714D01*
G01X538581Y580624D02*
Y585398D01*
X538355Y585624D01*
Y585698D01*
G01X518502Y580624D02*
Y585714D01*
G01X525195Y542824D02*
Y547914D01*
G01X531888Y542824D02*
Y547864D01*
X531838Y547914D01*
X531738D01*
G01X515155Y560934D02*
Y553614D01*
G01X534267Y556600D02*
Y553881D01*
X534534Y553614D01*
G01X528541Y560934D02*
Y553964D01*
X528191Y553614D01*
Y553514D01*
G01X538581Y542824D02*
Y547598D01*
X538355Y547824D01*
Y547898D01*
G01X481691Y542824D02*
Y547914D01*
G01X495077Y542824D02*
Y547864D01*
X495027Y547914D01*
X494927D01*
G01X488384D02*
Y542824D01*
G01X501770D02*
Y547598D01*
X501544Y547824D01*
Y547898D01*
G01X497456Y556600D02*
Y553881D01*
X497723Y553614D01*
G01X491730Y560934D02*
Y553964D01*
X491380Y553614D01*
Y553514D01*
G01X485037Y560934D02*
Y553614D01*
G01X511809Y580624D02*
Y585714D01*
G01X495077Y580624D02*
Y585664D01*
X495027Y585714D01*
X494927D01*
G01X501770Y580624D02*
Y585398D01*
X501544Y585624D01*
Y585698D01*
G01X481691Y580624D02*
Y585714D01*
G01X488384Y580624D02*
Y585714D01*
G01X508462Y560934D02*
Y557732D01*
X506644Y555914D01*
G01X511809Y542824D02*
Y547914D01*
G01X515155Y598734D02*
Y591414D01*
G01X534267Y594400D02*
Y591681D01*
X534534Y591414D01*
G01X528541Y598734D02*
Y591764D01*
X528191Y591414D01*
Y591314D01*
G01X521848Y598734D02*
Y591414D01*
G01X497456Y594400D02*
Y591681D01*
X497723Y591414D01*
G01X491730Y598734D02*
Y591764D01*
X491380Y591414D01*
Y591314D01*
G01X485037Y598734D02*
Y592233D01*
X486250Y591020D01*
G01X508462Y598734D02*
Y595532D01*
X506644Y593714D01*
G01X562006Y-1801D02*
Y4023D01*
G01D02*
Y9114D01*
G01X545273Y22133D02*
Y18932D01*
X543455Y17114D01*
G01X543468Y27936D02*
X545273Y26131D01*
Y22133D01*
G01X588777D02*
Y29949D01*
G01Y14814D02*
Y22133D01*
G01X580266Y17114D02*
X582084Y18932D01*
Y22133D01*
G01D02*
Y26131D01*
X580279Y27936D01*
G01X602163Y-9901D02*
X600892Y-8630D01*
Y-7592D01*
X600000Y-6700D01*
G01X599000Y32000D02*
Y28082D01*
X598817Y27899D01*
G01Y36049D02*
X599000Y35866D01*
Y32000D01*
G01X595470Y22133D02*
Y14814D01*
G01Y29949D02*
Y22133D01*
G01X585431Y4023D02*
Y9114D01*
G01X592124Y4023D02*
Y9114D01*
G01X598817Y4023D02*
Y9157D01*
G01X575392Y4023D02*
Y8798D01*
X575166Y9024D01*
Y9098D01*
G01X571345Y14814D02*
X571078Y15081D01*
Y17800D01*
G01X572045Y22133D02*
Y29400D01*
X571345Y30100D01*
G01X565352Y22133D02*
Y29563D01*
X564966Y29949D01*
G01X551966Y22133D02*
Y29949D01*
G01Y14814D02*
Y22133D01*
G01X558659Y14814D02*
Y22133D01*
G01D02*
Y29949D01*
G01X548620Y-1751D02*
Y4023D01*
G01D02*
Y9114D01*
G01X568699Y-1751D02*
Y4023D01*
G01D02*
Y9064D01*
X568649Y9114D01*
X568549D01*
G01X555313Y-1751D02*
Y4023D01*
G01D02*
Y9114D01*
G01X562006Y46914D02*
Y41823D01*
G01D02*
Y35999D01*
G01X551966Y52614D02*
Y59933D01*
G01D02*
Y67749D01*
G01X565352Y59933D02*
Y67363D01*
X564966Y67749D01*
G01X585431Y46914D02*
Y41823D01*
G01D02*
Y36049D01*
G01X595470Y52614D02*
Y59933D01*
G01D02*
Y67749D01*
G01X588777Y59933D02*
Y67749D01*
G01Y52614D02*
Y59933D01*
G01X575166Y73799D02*
X575392Y74025D01*
Y79623D01*
G01D02*
Y84398D01*
X575166Y84624D01*
Y84698D01*
G01X595470Y90414D02*
Y97733D01*
G01X585431Y73849D02*
Y79623D01*
G01D02*
Y84714D01*
G01X598817Y41823D02*
Y36049D01*
G01X599000Y70000D02*
Y73666D01*
X598817Y73849D01*
G01Y84757D02*
Y79623D01*
G01X599000Y70000D02*
X598817Y69817D01*
Y65699D01*
G01Y46957D02*
Y41823D01*
G01Y73849D02*
Y79623D01*
G01X592124D02*
Y84714D01*
G01Y73849D02*
Y79623D01*
G01X588777Y90414D02*
Y97733D01*
G01X582084D02*
Y94532D01*
X580266Y92714D01*
G01X580279Y65736D02*
X582084Y63931D01*
Y59933D01*
G01D02*
Y56732D01*
X580266Y54914D01*
G01X592124Y41823D02*
Y36049D01*
G01Y46914D02*
Y41823D01*
G01X575166Y46898D02*
Y46824D01*
X575392Y46598D01*
Y41823D01*
G01D02*
Y36225D01*
X575166Y35999D01*
G01X565352Y97733D02*
Y91240D01*
X566178Y90414D01*
X571345D01*
G01D02*
X571078Y90681D01*
Y93400D01*
G01X551966Y90414D02*
Y97733D01*
G01X558659Y90414D02*
Y97733D01*
G01X543455Y92714D02*
X545273Y94532D01*
Y97733D01*
G01X555313Y84714D02*
Y79623D01*
G01D02*
Y73849D01*
G01X562006Y84714D02*
Y79623D01*
G01D02*
Y73799D01*
G01X568699Y79623D02*
Y84664D01*
X568649Y84714D01*
X568549D01*
G01X568699Y73849D02*
Y79623D01*
G01X548620Y84714D02*
Y79623D01*
G01D02*
Y73849D01*
G01X543468Y65736D02*
X545273Y63931D01*
Y59933D01*
G01D02*
Y56732D01*
X543455Y54914D01*
G01X555313Y46914D02*
Y41823D01*
G01D02*
Y36049D01*
G01X568549Y46914D02*
X568649D01*
X568699Y46864D01*
Y41823D01*
G01D02*
Y36049D01*
G01X558659Y67749D02*
Y59933D01*
G01D02*
Y52614D01*
G01X572045Y59933D02*
Y67200D01*
X571345Y67900D01*
G01Y52614D02*
X571078Y52881D01*
Y55600D01*
G01X548620Y46914D02*
Y41823D01*
G01D02*
Y36049D01*
G01X551966Y97733D02*
Y100968D01*
X548620Y104314D01*
G01X558659Y97733D02*
Y100968D01*
X557560Y102068D01*
X556628Y103000D01*
X555313Y104314D01*
G01X545273Y97733D02*
Y103246D01*
X544306Y104214D01*
X543468Y105051D01*
G01X598817Y505024D02*
Y510157D01*
G01X588777Y523134D02*
Y515814D01*
G01X595470Y523134D02*
Y515814D01*
G01X592124Y505024D02*
Y510114D01*
G01X585431Y505024D02*
Y510114D01*
G01X582084Y523134D02*
Y519932D01*
X580266Y518114D01*
G01X575392Y505024D02*
Y509798D01*
X575166Y510024D01*
Y510098D01*
G01X558659Y523134D02*
Y515814D01*
G01X562006Y510114D02*
Y505024D01*
G01X568699D02*
Y510064D01*
X568649Y510114D01*
X568549D01*
G01X555313Y505024D02*
Y510114D01*
G01X548620Y505024D02*
Y510114D01*
G01X551966Y523134D02*
Y515814D01*
G01X545273Y523134D02*
Y519932D01*
X543455Y518114D01*
G01X565352Y523134D02*
Y516640D01*
X566178Y515814D01*
X571345D01*
G01D02*
X571078Y516081D01*
Y518800D01*
G01Y556600D02*
Y553881D01*
X571345Y553614D01*
G01X592124Y542824D02*
Y547914D01*
G01X585431Y542824D02*
Y547914D01*
G01X598817Y542824D02*
Y547957D01*
G01X588777Y560934D02*
Y553614D01*
G01X595470Y560934D02*
Y553614D01*
G01X600892Y532978D02*
X598817Y530903D01*
Y528899D01*
G01X575392Y580624D02*
Y585398D01*
X575166Y585624D01*
Y585698D01*
G01X592124Y580624D02*
Y585714D01*
G01X585431Y580624D02*
Y585714D01*
G01X598817Y568703D02*
X600892Y570778D01*
G01X598817Y580624D02*
Y585757D01*
G01X582084Y560934D02*
Y557732D01*
X580266Y555914D01*
G01X575392Y542824D02*
Y547598D01*
X575166Y547824D01*
Y547898D01*
G01X555313Y542824D02*
Y547914D01*
G01X562006D02*
Y542824D01*
G01X568699D02*
Y547864D01*
X568649Y547914D01*
X568549D01*
G01X558659Y560934D02*
Y553614D01*
G01X551966Y560934D02*
Y553614D01*
G01X548620Y542824D02*
Y547914D01*
G01X545273Y560934D02*
Y557732D01*
X543455Y555914D01*
G01X562006Y585714D02*
Y580624D01*
G01X568699D02*
Y585664D01*
X568649Y585714D01*
X568549D01*
G01X555313Y580624D02*
Y585714D01*
G01X548620Y580624D02*
Y585714D01*
G01X571345Y553614D02*
X566178D01*
X565352Y554440D01*
Y560934D01*
G01X588777Y598734D02*
Y591414D01*
G01X595470Y598734D02*
Y591414D01*
G01X582084Y598734D02*
Y595532D01*
X580266Y593714D01*
G01X599992Y609378D02*
X598817Y610553D01*
Y612649D01*
G01X565352Y598734D02*
Y592240D01*
X566178Y591414D01*
X571345D01*
G01X545273Y598734D02*
Y595532D01*
X543455Y593714D01*
G01X558659Y598734D02*
Y591414D01*
G01X551966Y598734D02*
Y591414D01*
G01X571345D02*
X571078Y591681D01*
Y594400D01*
G01X658300Y-4800D02*
X660400Y-2700D01*
Y-2600D01*
X660676D01*
G01X620192Y-5822D02*
X617378D01*
X616500Y-6700D01*
G01X616892Y31978D02*
X620192D01*
G01X602163Y22133D02*
Y16999D01*
G01X654800Y-4800D02*
Y-3650D01*
X656400Y-2050D01*
X657250D01*
G01X645430Y31067D02*
Y7670D01*
X650140Y2960D01*
X654790D01*
X656300Y1450D01*
Y-1100D01*
X657250Y-2050D01*
G01X656500Y-17500D02*
X653150D01*
G01X660000D02*
X656500D01*
G01X650050Y-17800D02*
X615300D01*
X612203Y-14703D01*
Y-9901D01*
G01X650050Y-17800D02*
X651440D01*
X651740Y-17500D01*
X653150D01*
G01X616500Y70000D02*
X616722Y69778D01*
X620192D01*
G01X602163Y92599D02*
Y97733D01*
G01X644400Y316300D02*
Y317800D01*
X642700Y319500D01*
G01X644000Y322000D02*
Y320800D01*
X642700Y319500D01*
G01X644000Y327000D02*
Y328200D01*
G01X644890Y337000D02*
Y338379D01*
X643289Y339980D01*
X639350D01*
G01X653000Y320500D02*
X655900D01*
G01X654000Y342000D02*
X655200D01*
X656500Y343300D01*
G01X659000Y342000D02*
X657800D01*
X656500Y343300D01*
G01X648800Y348000D02*
X647600D01*
X646500Y346900D01*
Y343300D01*
X647800Y342000D01*
X649000D01*
G01X653000Y316500D02*
X655900D01*
G01X642700Y319500D02*
X639100D01*
G01X649500Y316500D02*
X647700D01*
X646900Y317300D01*
G01X649500Y320500D02*
X647300D01*
X646900Y320100D01*
G01X656500Y343300D02*
Y346900D01*
X657600Y348000D01*
X658900D01*
G01X660500Y494500D02*
Y492000D01*
G01X602163Y523134D02*
Y517999D01*
G01X620192Y532978D02*
X616892D01*
G01X618292Y574300D02*
Y572178D01*
X616892Y570778D01*
G01X615992Y609378D02*
X619533D01*
X620033Y608878D01*
G01X602163Y598734D02*
Y593599D01*
G01X710263Y-14500D02*
X710993D01*
X713937Y-11556D01*
Y-9548D01*
G01X723715Y23462D02*
X722937Y22684D01*
Y20952D01*
G01X687450Y14500D02*
X689334Y12616D01*
X693416D01*
X693500Y12700D01*
X693578D01*
X695100Y14222D01*
Y21550D01*
X693600Y23050D01*
G01D02*
X691400D01*
X689900Y21550D01*
Y20800D01*
G01X692500Y15300D02*
Y16414D01*
X690899Y18015D01*
X688226D01*
G01X719600Y279400D02*
X722500Y282300D01*
Y283300D01*
G01X909040Y217400D02*
X885099D01*
X869046Y201347D01*
X829576D01*
X820629Y192400D01*
X796800D01*
X788886Y200314D01*
X768254D01*
X761434Y207134D01*
Y213757D01*
X756126Y219065D01*
Y225674D01*
X752700Y229100D01*
Y234900D01*
X752729Y234929D01*
Y245295D01*
X747564Y250460D01*
X737999D01*
X732573Y245034D01*
X727325D01*
X725725Y243434D01*
Y241560D01*
G01X679000Y342000D02*
X677704D01*
X676586Y343118D01*
G01X674000Y342000D02*
X675468D01*
X676586Y343118D01*
G01X684900Y348000D02*
X685400D01*
X686500Y346900D01*
Y343200D01*
X685300Y342000D01*
X684000D01*
G01X691800Y318000D02*
X695400D01*
G01Y328000D02*
X691093D01*
X690251Y328842D01*
Y330500D01*
G01Y335500D02*
Y337362D01*
X690989Y338100D01*
X695300D01*
G01X669000Y342000D02*
X667800D01*
X666500Y343300D01*
G01X695800Y308000D02*
X691100D01*
G01X692331Y297069D02*
X696088D01*
G01X666500Y343300D02*
X665200Y342000D01*
X664000D01*
G01X724000Y291700D02*
Y288300D01*
X722500Y286800D01*
G01X667900Y339000D02*
Y336600D01*
X668500Y336000D01*
G01X684000Y342000D02*
X679000D01*
G01X664100Y348000D02*
X665300D01*
X666500Y346800D01*
Y343300D01*
G01X676586Y343118D02*
Y346886D01*
X677700Y348000D01*
X679000D01*
G01X688300Y532900D02*
X687300Y533900D01*
X685271D01*
X684500Y533129D01*
Y532900D01*
G01X786616Y4023D02*
X786614D01*
G01X779771Y9114D02*
X779871D01*
X779921Y9064D01*
Y4023D01*
G01X779923D02*
X779921D01*
G01X769883Y22133D02*
X769881D01*
G01Y16839D02*
Y22133D01*
G01X776576D02*
X776574D01*
G01X776188Y29949D02*
X776574Y29563D01*
Y22133D01*
G01X783269D02*
X783267D01*
G01X773230Y4023D02*
X773228D01*
G01Y9114D02*
Y4023D01*
G01X786388Y-1801D02*
X786614Y-1575D01*
Y4023D01*
G01X773228D02*
Y-1801D01*
G01X776574Y22133D02*
Y17773D01*
X776224Y17423D01*
Y14714D01*
G01X769881Y22133D02*
Y27899D01*
G01X783267Y22133D02*
Y29400D01*
X782567Y30100D01*
G01X779921Y4023D02*
Y-1751D01*
G01X786614Y4023D02*
Y8798D01*
X786388Y9024D01*
Y9098D01*
G01X786616Y41823D02*
X786614D01*
G01X779771Y46914D02*
X779871D01*
X779921Y46864D01*
Y41823D01*
G01X779923D02*
X779921D01*
G01X779771Y84714D02*
X779871D01*
X779921Y84664D01*
Y79623D01*
G01X779923D02*
X779921D01*
G01X773230D02*
X773228D01*
G01X776576Y97733D02*
X776574D01*
Y93373D01*
X776224Y93023D01*
Y90314D01*
G01X769883Y97733D02*
X769881D01*
Y92500D01*
G01X782300Y93400D02*
Y90681D01*
X782567Y90414D01*
G01X786616Y79623D02*
X786614D01*
G01X786388Y84698D02*
Y84624D01*
X786614Y84398D01*
Y79623D01*
G01X769883Y59933D02*
X769881D01*
G01Y66000D02*
Y59933D01*
G01X783269D02*
X783267D01*
G01X776576D02*
X776574D01*
G01X776188Y67749D02*
X776574Y67363D01*
Y59933D01*
G01X773230Y41823D02*
X773228D01*
G01X753208Y69778D02*
Y72300D01*
X751708Y73800D01*
G01X773228Y73799D02*
Y79623D01*
G01Y35983D02*
Y41823D01*
G01X786388Y46898D02*
Y46824D01*
X786614Y46598D01*
Y41823D01*
G01X773228D02*
Y46914D01*
G01X776574Y59933D02*
Y55573D01*
X776224Y55223D01*
Y52514D01*
G01X769881Y59933D02*
Y54839D01*
G01X773228Y79623D02*
Y84714D01*
G01X779921Y41823D02*
Y35983D01*
G01X786614Y41823D02*
Y36225D01*
X786388Y35999D01*
G01X783267Y59933D02*
Y67200D01*
X782567Y67900D01*
G01X786614Y79623D02*
Y74025D01*
X786388Y73799D01*
G01X779921Y79623D02*
Y73849D01*
G01X780202Y209163D02*
X780232Y209193D01*
Y211733D01*
X779932Y212033D01*
G01X780032Y214689D02*
Y212133D01*
X779932Y212033D01*
G01X777182D02*
Y212669D01*
X776532Y213319D01*
Y214689D01*
G01X731100Y279300D02*
X728500Y281900D01*
Y283500D01*
G01X780032Y278689D02*
Y277141D01*
X779400Y276509D01*
Y276200D01*
G01X780232Y241283D02*
Y243733D01*
X779932Y244033D01*
G01X780032Y246689D02*
Y244133D01*
X779932Y244033D01*
G01X779400Y276200D02*
Y275757D01*
X780232Y274925D01*
Y273533D01*
G01X776532Y246689D02*
Y243968D01*
X777000Y243500D01*
G01X776532Y278689D02*
Y275668D01*
X776700Y275500D01*
G01X780942Y305563D02*
X779100Y307405D01*
Y307900D01*
G01X779932Y340033D02*
X780772Y339193D01*
Y337353D01*
G01X779932Y340033D02*
X780032Y340133D01*
Y342689D01*
G01X779100Y307900D02*
Y308290D01*
X780032Y309222D01*
Y310689D01*
G01X777182Y340033D02*
Y340719D01*
X776532Y341369D01*
Y342689D01*
G01X729405Y290725D02*
X728500Y289820D01*
Y287000D01*
G01X776532Y310689D02*
Y310335D01*
X775925Y309728D01*
Y307445D01*
X776270Y307100D01*
G01X780162Y369433D02*
X780182Y369453D01*
Y371733D01*
X779882Y372033D01*
G01X779982Y374689D02*
Y372133D01*
X779882Y372033D01*
G01X777100Y372000D02*
X776482Y372618D01*
Y374689D01*
G01X782300Y518800D02*
Y516081D01*
X782567Y515814D01*
G01X769883Y523134D02*
X769881Y523133D01*
Y517900D01*
G01X779923Y505024D02*
X779921D01*
Y510064D01*
X779871Y510114D01*
X779771D01*
G01X786616Y505024D02*
X786614D01*
Y509798D01*
X786388Y510024D01*
Y510098D01*
G01X773230Y505024D02*
X773228D01*
Y510114D01*
G01X776224Y515714D02*
X776574Y516064D01*
Y523133D01*
X776576Y523134D01*
G01X773000Y570778D02*
Y574571D01*
X773228Y574799D01*
G01X786616Y580624D02*
X786614D01*
Y585398D01*
X786388Y585624D01*
Y585698D01*
G01X773230Y580624D02*
X773228D01*
Y585714D01*
G01X779923Y580624D02*
X779921D01*
Y585664D01*
X779871Y585714D01*
X779771D01*
G01X769883Y560934D02*
X769881D01*
G01Y555700D02*
Y560934D01*
G01X756000Y534500D02*
Y537000D01*
G01X782300Y556600D02*
Y553881D01*
X782567Y553614D01*
G01X779923Y542824D02*
X779921D01*
Y547864D01*
X779871Y547914D01*
X779771D01*
G01X786616Y542824D02*
X786614D01*
Y547598D01*
X786388Y547824D01*
Y547898D01*
G01X773230Y542824D02*
X773228D01*
Y547914D01*
G01X773400Y532800D02*
Y536827D01*
X773228Y536999D01*
G01X769818Y529200D02*
X768300D01*
X766500Y531000D01*
G01X776576Y560934D02*
X776574Y560933D01*
Y556573D01*
X776224Y556223D01*
Y553514D01*
G01X755000Y572300D02*
Y574800D01*
G01X769700Y566900D02*
X768195Y568405D01*
X765895D01*
X765500Y568800D01*
G01X769881Y560934D02*
Y566719D01*
X769700Y566900D01*
G01X763300Y566000D02*
X762000Y567300D01*
Y568800D01*
G01X763000Y531000D02*
Y530000D01*
X764400Y528600D01*
G01X769900Y532800D02*
X769500Y533200D01*
Y536983D01*
G01X763000Y534500D02*
X766500D01*
G01X759500D02*
X763000D01*
G01X769500Y536983D02*
X767017Y534500D01*
X766500D01*
G01X769500Y570778D02*
Y574700D01*
G01X765500Y572300D02*
X766418D01*
X768818Y574700D01*
X769500D01*
G01X762000Y572300D02*
X765500D01*
G01X758500D02*
X762000D01*
G01X769883Y580624D02*
X769881D01*
Y585319D01*
X769500Y585700D01*
G01X776576Y598734D02*
X776574Y598733D01*
Y594373D01*
X776224Y594023D01*
Y591314D01*
G01X782300Y594400D02*
Y591681D01*
X782567Y591414D01*
G01X769883Y598734D02*
X769881Y598733D01*
Y593081D01*
X767500Y590700D01*
X766600D01*
G01X773000Y608800D02*
Y612371D01*
X773228Y612599D01*
G01X766000Y608500D02*
X766500Y607000D01*
X768600Y604900D01*
X769700D01*
G01X762500Y608500D02*
Y606500D01*
X764400Y604600D01*
G01X769500Y608800D02*
Y612583D01*
G01X762500Y612000D02*
X759000D01*
G01X766000D02*
X762500D01*
G01X769500Y612583D02*
X768917Y612000D01*
G01X813387Y22133D02*
X813385D01*
G01X810041Y4023D02*
X810039D01*
G01X796655D02*
X796653D01*
G01X820080Y22133D02*
X820078D01*
G01X819378Y30100D02*
X820078Y29400D01*
Y22133D01*
G01X830120D02*
X830118D01*
G01X828299Y17114D02*
X830118Y18933D01*
Y22133D01*
G01X843506D02*
X843504D01*
G01X843503Y29949D02*
X843504Y29948D01*
Y22133D01*
G01X836813D02*
X836811D01*
G01X836810Y14814D02*
Y20974D01*
X836811Y20975D01*
Y22133D01*
G01X833466Y4023D02*
X833464D01*
G01Y-1751D02*
Y4023D01*
G01X840159D02*
X840157D01*
G01Y-1751D02*
Y4023D01*
G01X846852D02*
X846850D01*
G01Y-1801D02*
Y4023D01*
G01X816734D02*
X816732D01*
G01Y-1751D02*
Y4023D01*
G01X823427D02*
X823425D01*
G01X823199Y9098D02*
Y9024D01*
X823425Y8798D01*
Y4023D01*
G01X800002Y22133D02*
X800000D01*
G01X799999Y14814D02*
X800000Y14815D01*
Y22133D01*
G01X793309D02*
X793307D01*
G01X791488Y17114D02*
X793307Y18933D01*
Y22133D01*
G01X806694D02*
X806692D01*
G01Y29949D02*
Y22133D01*
G01X803348Y4023D02*
X803346D01*
G01Y9114D02*
Y4023D01*
G01X812999Y29949D02*
X813385Y29563D01*
Y22133D01*
G01X810039Y9114D02*
Y4023D01*
G01X796653Y9114D02*
Y4023D01*
G01X803346D02*
Y-1751D01*
G01X806692Y22133D02*
Y14814D01*
G01X793307Y22133D02*
Y26130D01*
X791501Y27936D01*
G01X800000Y22133D02*
Y29948D01*
X799999Y29949D01*
G01X823425Y4023D02*
Y-1575D01*
X823199Y-1801D01*
G01X816732Y4023D02*
Y9064D01*
X816682Y9114D01*
X816582D01*
G01X833464Y4023D02*
Y9114D01*
G01X836811Y22133D02*
Y29948D01*
X836810Y29949D01*
G01X830118Y22133D02*
Y26130D01*
X828312Y27936D01*
G01X819100Y18288D02*
Y15092D01*
X819378Y14814D01*
G01X796653Y4023D02*
Y-1751D01*
G01X810039Y4023D02*
Y-1801D01*
G01X813385Y22133D02*
Y15064D01*
X813035Y14714D01*
G01X846850Y4023D02*
Y9114D01*
G01X840157Y4023D02*
Y9114D01*
G01X843504Y22133D02*
Y20775D01*
X843503Y20774D01*
Y14814D01*
G01X796655Y41823D02*
X796653D01*
G01X803348D02*
X803346D01*
G01X843506Y59933D02*
X843504D01*
G01X840159Y41823D02*
X840157D01*
G01X833466D02*
X833464D01*
G01X816734Y79623D02*
X816732D01*
G01X823427D02*
X823425D01*
G01X823199Y84698D02*
Y84624D01*
X823425Y84398D01*
Y79623D01*
G01X819100Y93888D02*
Y90642D01*
G01X836813Y97733D02*
X836811D01*
Y96575D01*
X836810Y96574D01*
Y90414D01*
G01X830120Y97733D02*
X830118D01*
Y94533D01*
X828299Y92714D01*
G01X833466Y79623D02*
X833464D01*
G01Y73849D02*
Y79623D01*
G01X840159D02*
X840157D01*
G01Y84714D02*
Y79623D01*
G01X843506Y97733D02*
X843504D01*
Y96375D01*
X843503Y96374D01*
Y90414D01*
G01X846852Y79623D02*
X846850D01*
G01Y84714D02*
Y79623D01*
G01X816734Y41823D02*
X816732D01*
G01X816582Y46914D02*
X816682D01*
X816732Y46864D01*
Y41823D01*
G01X820080Y59933D02*
X820078D01*
G01X819378Y67900D02*
X820078Y67200D01*
Y59933D01*
G01X846852Y41823D02*
X846850D01*
G01Y35999D02*
Y41823D01*
G01X836813Y59933D02*
X836811D01*
G01X836810Y67749D02*
X836811Y67748D01*
Y59933D01*
G01X830120D02*
X830118D01*
G01X828312Y65736D02*
X830118Y63930D01*
Y59933D01*
G01X823427Y41823D02*
X823425D01*
G01X823199Y46898D02*
Y46824D01*
X823425Y46598D01*
Y41823D01*
G01X813387Y97733D02*
X813385D01*
Y90664D01*
X813035Y90314D01*
G01X806694Y97733D02*
X806692D01*
Y90414D01*
G01X800002Y97733D02*
X800000D01*
Y90415D01*
X799999Y90414D01*
G01X793309Y97733D02*
X793307D01*
Y94533D01*
X791488Y92714D01*
G01X796655Y79623D02*
X796653D01*
G01Y84714D02*
Y79623D01*
G01X803348D02*
X803346D01*
G01Y73849D02*
Y79623D01*
G01X810041D02*
X810039D01*
G01Y73799D02*
Y79623D01*
G01X816582Y73849D02*
X816732Y73999D01*
Y79623D01*
G01X806694Y59933D02*
X806692D01*
G01Y67749D02*
Y59933D01*
G01X800002D02*
X800000D01*
G01X799999Y67749D02*
X800000Y67748D01*
Y59933D01*
G01X813387D02*
X813385D01*
G01X812999Y67749D02*
X813385Y67363D01*
Y59933D01*
G01X793309D02*
X793307D01*
G01X791501Y65736D02*
X793307Y63930D01*
Y59933D01*
G01X810041Y41823D02*
X810039D01*
G01Y46914D02*
Y41823D01*
G01X796653Y36049D02*
Y41823D01*
G01X803346Y36049D02*
Y41823D01*
G01X833464Y46914D02*
Y41823D01*
G01X840157Y46914D02*
Y41823D01*
G01X843503Y67749D02*
X843504Y67748D01*
Y59933D01*
G01X810039Y41823D02*
Y35999D01*
G01X823425Y41823D02*
Y36225D01*
X823199Y35999D01*
G01X816732Y41823D02*
Y36049D01*
G01X833464Y41823D02*
Y36049D01*
G01X803346Y41823D02*
Y46914D01*
G01X796653Y41823D02*
Y46914D01*
G01X793307Y59933D02*
Y56733D01*
X791488Y54914D01*
G01X813385Y59933D02*
Y52864D01*
X813035Y52514D01*
G01X800000Y59933D02*
Y52615D01*
X799999Y52614D01*
G01X806692Y59933D02*
Y52614D01*
G01X810039Y79623D02*
Y84714D01*
G01X803346Y79623D02*
Y84714D01*
G01X796653Y79623D02*
Y73849D01*
G01X830118Y59933D02*
Y56733D01*
X828299Y54914D01*
G01X836811Y59933D02*
Y58775D01*
X836810Y58774D01*
Y52614D01*
G01X819100Y56088D02*
Y52892D01*
X819378Y52614D01*
G01X833464Y79623D02*
Y84714D01*
G01X823425Y79623D02*
Y74025D01*
X823199Y73799D01*
G01X816732Y79623D02*
Y84664D01*
X816682Y84714D01*
X816582D01*
G01X846850Y41823D02*
Y46914D01*
G01X840157Y41823D02*
Y36049D01*
G01X846850Y79623D02*
Y73799D01*
G01X840157Y79623D02*
Y73849D01*
G01X843504Y59933D02*
Y58575D01*
X843503Y58574D01*
Y52614D01*
G01X816734Y505024D02*
X816732D01*
Y510064D01*
X816682Y510114D01*
X816582D01*
G01X819100Y519288D02*
Y516042D01*
G01X830120Y523134D02*
X830118Y523133D01*
Y519933D01*
X828299Y518114D01*
G01X836813Y523134D02*
X836811Y523133D01*
Y521975D01*
X836810Y521974D01*
Y515814D01*
G01X843506Y523134D02*
X843504Y523133D01*
Y521775D01*
X843503Y521774D01*
Y515814D01*
G01X840159Y505024D02*
X840157D01*
Y510114D01*
G01X833466Y505024D02*
X833464D01*
Y510114D01*
G01X846852Y505024D02*
X846850D01*
Y510114D01*
G01X823427Y505024D02*
X823425D01*
Y509798D01*
X823199Y510024D01*
Y510098D01*
G01X810041Y505024D02*
X810039D01*
Y510114D01*
G01X796655Y505024D02*
X796653D01*
Y510114D01*
G01X803348Y505024D02*
X803346D01*
Y510114D01*
G01X806694Y523134D02*
X806692Y523133D01*
Y515814D01*
G01X813387Y523134D02*
X813385Y523133D01*
Y516064D01*
X813035Y515714D01*
G01X793309Y523134D02*
X793307Y523133D01*
Y519933D01*
X791488Y518114D01*
G01X800002Y523134D02*
X800000Y523133D01*
Y515815D01*
X799999Y515814D01*
G01X816734Y580624D02*
X816732D01*
Y585664D01*
X816682Y585714D01*
X816582D01*
G01X830120Y560934D02*
X830118Y560933D01*
Y557733D01*
X828299Y555914D01*
G01X823427Y580624D02*
X823425D01*
Y585398D01*
X823199Y585624D01*
Y585698D01*
G01X840159Y580624D02*
X840157D01*
Y585714D01*
G01X833466Y580624D02*
X833464D01*
Y585714D01*
G01X816734Y542824D02*
X816732D01*
Y547864D01*
X816682Y547914D01*
X816582D01*
G01X823427Y542824D02*
X823425D01*
Y547598D01*
X823199Y547824D01*
Y547898D01*
G01X819100Y557088D02*
Y553842D01*
G01X846852Y580624D02*
X846850D01*
Y585714D01*
G01X846852Y542824D02*
X846850D01*
Y547914D01*
G01X843506Y560934D02*
X843504Y560933D01*
Y559575D01*
X843503Y559574D01*
Y553614D01*
G01X836813Y560934D02*
X836811Y560933D01*
Y559775D01*
X836810Y559774D01*
Y553614D01*
G01X840159Y542824D02*
X840157D01*
Y547914D01*
G01X833466Y542824D02*
X833464D01*
Y547914D01*
G01X793309Y560934D02*
X793307Y560933D01*
Y557733D01*
X791488Y555914D01*
G01X810041Y580624D02*
X810039D01*
Y585714D01*
G01X796655Y580624D02*
X796653D01*
Y585714D01*
G01X803348Y580624D02*
X803346D01*
Y585714D01*
G01X806694Y560934D02*
X806692Y560933D01*
Y553614D01*
G01X813387Y560934D02*
X813385Y560933D01*
Y553864D01*
X813035Y553514D01*
G01X800002Y560934D02*
X800000Y560933D01*
Y553615D01*
X799999Y553614D01*
G01X796655Y542824D02*
X796653D01*
Y547914D01*
G01X803348Y542824D02*
X803346D01*
Y547914D01*
G01X810041Y542824D02*
X810039D01*
Y547914D01*
G01X819100Y594888D02*
Y591642D01*
G01X830120Y598734D02*
X830118Y598733D01*
Y595533D01*
X828299Y593714D01*
G01X836813Y598734D02*
X836811Y598733D01*
Y597575D01*
X836810Y597574D01*
Y591414D01*
G01X843506Y598734D02*
X843504Y598733D01*
Y597375D01*
X843503Y597374D01*
Y591414D01*
G01X806694Y598734D02*
X806692Y598733D01*
Y591414D01*
G01X813387Y598734D02*
X813385Y598733D01*
Y591664D01*
X813035Y591314D01*
G01X793309Y598734D02*
X793307Y598733D01*
Y595533D01*
X791488Y593714D01*
G01X800002Y598734D02*
X800000Y598733D01*
Y591415D01*
X799999Y591414D01*
G01X866931Y22133D02*
X866929D01*
G01X876970Y4023D02*
X876968D01*
G01X907088D02*
X907086D01*
G01X893000Y30100D02*
X893700Y29400D01*
Y22133D01*
G01X903742D02*
X903740D01*
G01X901934Y27936D02*
X903740Y26130D01*
Y22133D01*
G01X880317D02*
X880315D01*
G01X880314Y29949D02*
X880315Y29948D01*
Y22133D01*
G01X887009D02*
X887007D01*
G01X886621Y29949D02*
X887007Y29563D01*
Y22133D01*
G01X910435D02*
X910433D01*
G01X910432Y29949D02*
X910433Y29948D01*
Y22133D01*
G01X883663Y4023D02*
X883661D01*
G01Y-1801D02*
Y4023D01*
G01X890356D02*
X890354D01*
G01Y-1751D02*
Y4023D01*
G01X897049D02*
X897047D01*
G01X896821Y9098D02*
Y9024D01*
X897047Y8798D01*
Y4023D01*
G01X850198Y22133D02*
X850196D01*
G01X849810Y29949D02*
X850196Y29563D01*
Y22133D01*
G01X856891D02*
X856889D01*
G01X856189Y30100D02*
X856889Y29400D01*
Y22133D01*
G01X873624D02*
X873622D01*
G01X873621Y29949D02*
X873622Y29948D01*
Y22133D01*
G01X870277Y4023D02*
X870275D01*
G01Y-1751D02*
Y4023D01*
G01X853545D02*
X853543D01*
G01Y-1751D02*
Y4023D01*
G01X860238D02*
X860236D01*
G01X860010Y-1801D02*
X860236Y-1575D01*
Y4023D01*
G01X865123Y27936D02*
X866929Y26130D01*
Y22133D01*
G01X876968Y9114D02*
Y4023D01*
G01X907086Y9114D02*
Y4023D01*
G01X860236D02*
Y8798D01*
X860010Y9024D01*
Y9098D01*
G01X853543Y4023D02*
Y9064D01*
X853493Y9114D01*
X853393D01*
G01X870275Y4023D02*
Y9114D01*
G01X873622Y22133D02*
Y20775D01*
X873621Y20774D01*
Y14814D01*
G01X855900Y17800D02*
Y15103D01*
X856189Y14814D01*
G01X850196Y22133D02*
Y15164D01*
X849846Y14814D01*
Y14714D01*
G01X897047Y4023D02*
Y-1575D01*
X896821Y-1801D01*
G01X890354Y4023D02*
Y9064D01*
X890304Y9114D01*
X890204D01*
G01X883661Y4023D02*
Y9114D01*
G01X887007Y22133D02*
Y15164D01*
X886657Y14814D01*
Y14714D01*
G01X880315Y22133D02*
Y21175D01*
X880314Y21174D01*
Y14814D01*
G01X892700Y17700D02*
Y15114D01*
X893000Y14814D01*
G01X876968Y4023D02*
Y-1751D01*
G01X866929Y22133D02*
Y18933D01*
X865110Y17114D01*
G01X910433Y22133D02*
Y20675D01*
X910432Y20674D01*
Y14814D01*
G01X903740Y22133D02*
Y18933D01*
X901921Y17114D01*
G01X907086Y4023D02*
Y-1751D01*
G01X850198Y59933D02*
X850196D01*
G01X870277Y41823D02*
X870275D01*
G01X853545D02*
X853543D01*
G01X860238D02*
X860236D01*
G01X866931Y59933D02*
X866929D01*
G01X890356Y79623D02*
X890354D01*
G01X876970D02*
X876968D01*
G01Y84714D02*
Y79623D01*
G01X907088D02*
X907086D01*
G01Y73849D02*
Y79623D01*
G01X883663D02*
X883661D01*
G01Y73799D02*
Y79623D01*
G01X897049D02*
X897047D01*
G01X896821Y73799D02*
X897047Y74025D01*
Y79623D01*
G01X876970Y41823D02*
X876968D01*
G01Y36049D02*
Y41823D01*
G01X897049D02*
X897047D01*
G01X896821Y46898D02*
Y46824D01*
X897047Y46598D01*
Y41823D01*
G01X890356D02*
X890354D01*
G01X890204Y46914D02*
X890304D01*
X890354Y46864D01*
Y41823D01*
G01X910435Y59933D02*
X910433D01*
G01X910432Y67749D02*
X910433Y67748D01*
Y59933D01*
G01X883663Y41823D02*
X883661D01*
G01Y46914D02*
Y41823D01*
G01X887009Y59933D02*
X887007D01*
G01X886621Y67749D02*
X887007Y67363D01*
Y59933D01*
G01X880317D02*
X880315D01*
G01X880314Y67749D02*
X880315Y67748D01*
Y59933D01*
G01X903742D02*
X903740D01*
G01X901934Y65736D02*
X903740Y63930D01*
Y59933D01*
G01X893702D02*
X893700D01*
G01X893000Y67900D02*
X893700Y67200D01*
Y59933D01*
G01X907088Y41823D02*
X907086D01*
G01Y46914D02*
Y41823D01*
G01X866931Y97733D02*
X866929D01*
Y94533D01*
X865110Y92714D01*
G01X873624Y97733D02*
X873622D01*
Y96375D01*
X873621Y96374D01*
Y90414D01*
G01X855900Y93400D02*
Y90703D01*
X856189Y90414D01*
G01X850198Y97733D02*
X850196D01*
Y90764D01*
X849846Y90414D01*
Y90314D01*
G01X853545Y79623D02*
X853543D01*
G01Y73849D02*
Y79623D01*
G01X860238D02*
X860236D01*
G01X860010Y73799D02*
X860236Y74025D01*
Y79623D01*
G01X870277D02*
X870275D01*
G01Y84714D02*
Y79623D01*
G01X873624Y59933D02*
X873622D01*
G01X873621Y67749D02*
X873622Y67748D01*
Y59933D01*
G01X856189Y67900D02*
X856889Y67200D01*
Y59933D01*
G01X870275Y36049D02*
Y41823D01*
G01X853543Y36049D02*
Y41823D01*
G01X860010Y35999D02*
X860236Y36225D01*
Y41823D01*
G01X849810Y67749D02*
X850196Y67363D01*
Y59933D01*
G01X865123Y65736D02*
X866929Y63930D01*
Y59933D01*
G01X890204Y84714D02*
X890304D01*
X890354Y84664D01*
Y79623D01*
G01X883661Y41823D02*
Y35999D01*
G01X890354Y41823D02*
Y36049D01*
G01X897047Y41823D02*
Y36225D01*
X896821Y35999D01*
G01X876968Y41823D02*
Y46914D01*
G01X860236Y41823D02*
Y46598D01*
X860010Y46824D01*
Y46898D01*
G01X853543Y41823D02*
Y46864D01*
X853493Y46914D01*
X853393D01*
G01X870275Y41823D02*
Y46914D01*
G01X855900Y55600D02*
Y52903D01*
X856189Y52614D01*
G01X873622Y59933D02*
Y58575D01*
X873621Y58574D01*
Y52614D01*
G01X870275Y79623D02*
Y73849D01*
G01X860236Y79623D02*
Y84398D01*
X860010Y84624D01*
Y84698D01*
G01X853543Y79623D02*
Y84664D01*
X853493Y84714D01*
X853393D01*
G01X892700Y55500D02*
Y52914D01*
X893000Y52614D01*
G01X880315Y59933D02*
Y58975D01*
X880314Y58974D01*
Y52614D01*
G01X887007Y59933D02*
Y52964D01*
X886657Y52614D01*
Y52514D01*
G01X897047Y79623D02*
Y84398D01*
X896821Y84624D01*
Y84698D01*
G01X880315Y97733D02*
Y96775D01*
X880314Y96774D01*
Y90414D01*
G01X883661Y79623D02*
Y84714D01*
G01X892700Y93300D02*
Y90714D01*
X893000Y90414D01*
G01X876968Y79623D02*
Y73849D01*
G01X890354Y79623D02*
Y73849D01*
G01X887007Y97733D02*
Y90764D01*
X886657Y90414D01*
Y90314D01*
G01X866929Y59933D02*
Y56733D01*
X865110Y54914D01*
G01X850196Y59933D02*
Y52964D01*
X849846Y52614D01*
Y52514D01*
G01X907086Y41823D02*
Y36049D01*
G01X903740Y59933D02*
Y56733D01*
X901921Y54914D01*
G01X910433Y59933D02*
Y58475D01*
X910432Y58474D01*
Y52614D01*
G01X907086Y79623D02*
Y84714D01*
G01X903740Y97733D02*
Y94533D01*
X901921Y92714D01*
G01X910433Y97733D02*
Y96275D01*
X910432Y96274D01*
Y90414D01*
G01X910435Y97733D02*
X910433D01*
G01X887009D02*
X887007D01*
G01X903742D02*
X903740D01*
G01X901934Y105051D02*
X903740Y103245D01*
Y97733D01*
G01X896847Y105265D02*
X893700Y102118D01*
Y97733D01*
G01X880317D02*
X880315D01*
G01X883661Y104284D02*
X880315Y100938D01*
Y97733D01*
G01X890204Y104284D02*
X887007Y101087D01*
Y97733D01*
G01X913779Y104284D02*
X910433Y100938D01*
Y97733D01*
G01X876968Y510114D02*
Y505024D01*
X876970D01*
G01X892700Y518700D02*
Y516114D01*
X893000Y515814D01*
G01X903742Y523134D02*
X903740Y523133D01*
Y519933D01*
X901921Y518114D01*
G01X907088Y505024D02*
X907086D01*
Y510114D01*
G01X890356Y505024D02*
X890354D01*
Y510064D01*
X890304Y510114D01*
X890204D01*
G01X897049Y505024D02*
X897047D01*
Y509798D01*
X896821Y510024D01*
Y510098D01*
G01X883663Y505024D02*
X883661D01*
Y510114D01*
G01X910435Y523134D02*
X910433Y523133D01*
Y521675D01*
X910432Y521674D01*
Y515814D01*
G01X880317Y523134D02*
X880315Y523133D01*
Y522175D01*
X880314Y522174D01*
Y515814D01*
G01X887009Y523134D02*
X887007Y523133D01*
Y516164D01*
X886657Y515814D01*
Y515714D01*
G01X873624Y523134D02*
X873622Y523133D01*
Y521775D01*
X873621Y521774D01*
Y515814D01*
G01X870277Y505024D02*
X870275D01*
Y510114D01*
G01X866931Y523134D02*
X866929Y523133D01*
Y519933D01*
X865110Y518114D01*
G01X850198Y523134D02*
X850196Y523133D01*
Y516164D01*
X849846Y515814D01*
Y515714D01*
G01X855900Y518800D02*
Y516103D01*
X856189Y515814D01*
G01X853545Y505024D02*
X853543D01*
Y510064D01*
X853493Y510114D01*
X853393D01*
G01X860238Y505024D02*
X860236D01*
Y509798D01*
X860010Y510024D01*
Y510098D01*
G01X876970Y580624D02*
X876968D01*
Y585714D01*
G01X903742Y560934D02*
X903740Y560933D01*
Y557733D01*
X901921Y555914D01*
G01X897049Y580624D02*
X897047D01*
Y585398D01*
X896821Y585624D01*
Y585698D01*
G01X890356Y580624D02*
X890354D01*
Y585664D01*
X890304Y585714D01*
X890204D01*
G01X907088Y580624D02*
X907086D01*
Y585714D01*
G01X883663Y580624D02*
X883661D01*
Y585714D01*
G01X876970Y542824D02*
X876968D01*
Y547914D01*
G01X880317Y560934D02*
X880315Y560933D01*
Y559975D01*
X880314Y559974D01*
Y553614D01*
G01X883663Y542824D02*
X883661D01*
Y547914D01*
G01X907086D02*
Y542824D01*
X907088D01*
G01X890356D02*
X890354D01*
Y547864D01*
X890304Y547914D01*
X890204D01*
G01X897049Y542824D02*
X897047D01*
Y547598D01*
X896821Y547824D01*
Y547898D01*
G01X910435Y560934D02*
X910433Y560933D01*
Y559475D01*
X910432Y559474D01*
Y553614D01*
G01X892700Y556500D02*
Y553914D01*
X893000Y553614D01*
G01X887009Y560934D02*
X887007Y560933D01*
Y553964D01*
X886657Y553614D01*
Y553514D01*
G01X866931Y560934D02*
X866929Y560933D01*
Y557733D01*
X865110Y555914D01*
G01X870277Y580624D02*
X870275D01*
Y585714D01*
G01X860238Y580624D02*
X860236D01*
Y585398D01*
X860010Y585624D01*
Y585698D01*
G01X853545Y542824D02*
X853543D01*
Y547864D01*
X853493Y547914D01*
X853393D01*
G01X873624Y560934D02*
X873622Y560933D01*
Y559575D01*
X873621Y559574D01*
Y553614D01*
G01X853545Y580624D02*
X853543D01*
Y585664D01*
X853493Y585714D01*
X853393D01*
G01X850198Y560934D02*
X850196Y560933D01*
Y553964D01*
X849846Y553614D01*
Y553514D01*
G01X855900Y556600D02*
Y553903D01*
X856189Y553614D01*
G01X870277Y542824D02*
X870275D01*
Y547914D01*
G01X860238Y542824D02*
X860236D01*
Y547598D01*
X860010Y547824D01*
Y547898D01*
G01X910435Y598734D02*
X910433Y598733D01*
Y597275D01*
X910432Y597274D01*
Y591414D01*
G01X892700Y594300D02*
Y591714D01*
X893000Y591414D01*
G01X903742Y598734D02*
X903740Y598733D01*
Y595533D01*
X901921Y593714D01*
G01X880317Y598734D02*
X880315Y598733D01*
Y597775D01*
X880314Y597774D01*
Y591414D01*
G01X887009Y598734D02*
X887007Y598733D01*
Y591764D01*
X886657Y591414D01*
Y591314D01*
G01X873624Y598734D02*
X873622Y598733D01*
Y597375D01*
X873621Y597374D01*
Y591414D01*
G01X866931Y598734D02*
X866929Y598733D01*
Y595533D01*
X865110Y593714D01*
G01X850198Y598734D02*
X850196Y598733D01*
Y591764D01*
X849846Y591414D01*
Y591314D01*
G01X855900Y594400D02*
Y591703D01*
X856189Y591414D01*
G01X913781Y4023D02*
X913779D01*
G01X940553Y22133D02*
X940551D01*
G01X938745Y27936D02*
X940551Y26130D01*
Y22133D01*
G01X953939D02*
X953937D01*
G01X947246D02*
X947244D01*
G01X947243Y29949D02*
X947244Y29948D01*
Y22133D01*
G01X950592Y4023D02*
X950590D01*
G01Y-1751D02*
Y4023D01*
G01X957285D02*
X957283D01*
G01Y9300D02*
Y4023D01*
G01X943899D02*
X943897D01*
G01Y9114D02*
Y4023D01*
G01X917128Y22133D02*
X917126D01*
G01X917125Y29949D02*
X917126Y29948D01*
Y22133D01*
G01X923820D02*
X923818D01*
G01X923432Y29949D02*
X923818Y29563D01*
Y22133D01*
G01X920474Y4023D02*
X920472D01*
G01Y9114D02*
Y4023D01*
G01X927167D02*
X927165D01*
G01X927015Y9114D02*
X927165Y8964D01*
Y4023D01*
G01X933860D02*
X933858D01*
G01X933632Y9098D02*
Y9024D01*
X933858Y8798D01*
Y4023D01*
G01X929811Y30100D02*
X930511Y29400D01*
Y22133D01*
G01X927165Y36049D02*
Y32746D01*
X929811Y30100D01*
G01X913779Y9114D02*
Y4023D01*
G01X933858D02*
Y-1575D01*
X933632Y-1801D01*
G01X927165Y4023D02*
Y-1751D01*
G01X920472Y4023D02*
Y-1801D01*
G01X929511Y17700D02*
Y15114D01*
X929811Y14814D01*
G01X923818Y22133D02*
Y15164D01*
X923468Y14814D01*
Y14714D01*
G01X917126Y22133D02*
Y20975D01*
X917125Y20974D01*
Y14814D01*
G01X943897Y4023D02*
Y-1751D01*
G01X957283Y4023D02*
Y-1843D01*
G01X950590Y4023D02*
Y9114D01*
G01X947244Y22133D02*
Y20675D01*
X947243Y20674D01*
Y14814D01*
G01X953937Y22133D02*
Y14815D01*
X953936Y14814D01*
G01X940551Y22133D02*
Y18933D01*
X938732Y17114D01*
G01X913779Y4023D02*
Y-1751D01*
G01X953937Y22133D02*
Y29948D01*
G01D02*
X953936Y29949D01*
G01X967324Y22133D02*
X967322D01*
Y17057D01*
G01X960631Y22133D02*
X960629D01*
Y17057D01*
G01X970669Y9114D02*
Y4023D01*
G01X963976Y9114D02*
Y4023D01*
G01X960631Y22133D02*
X960629Y22135D01*
Y28014D01*
G01X967324Y22133D02*
X967322Y22135D01*
Y28014D01*
G01X963976Y4023D02*
Y-1843D01*
G01X970669Y4023D02*
Y-1743D01*
G01X963976Y4023D02*
X963978D01*
G01X970669D02*
X970671D01*
G01X917128Y59933D02*
X917126D01*
G01X913781Y41823D02*
X913779D01*
G01X913781Y79623D02*
X913779D01*
G01X938732Y92714D02*
X940551Y94533D01*
Y97733D01*
G01X957285Y79623D02*
X957283D01*
G01X953886Y90414D02*
X953936Y90464D01*
Y96074D01*
X953937Y96075D01*
Y97733D01*
G01X947246D02*
X947244D01*
Y96275D01*
X947243Y96274D01*
Y90414D01*
G01X943899Y79623D02*
X943897D01*
G01Y73849D02*
Y79623D01*
G01X950592D02*
X950590D01*
G01Y73849D02*
Y79623D01*
G01X974250Y51000D02*
X970940D01*
X970800Y50860D01*
G01X940553Y59933D02*
X940551D01*
Y56733D01*
X938732Y54914D01*
G01X953939Y59933D02*
X953937D01*
G01X947246D02*
X947244D01*
G01X947243Y67749D02*
X947244Y67748D01*
Y59933D01*
G01X943899Y41823D02*
X943897D01*
G01Y46914D02*
Y41823D01*
G01X950592D02*
X950590D01*
G01Y36049D02*
Y41823D01*
G01X957285D02*
X957283D01*
G01X920474Y79623D02*
X920472D01*
G01Y84714D02*
Y79623D01*
G01X927167D02*
X927165D01*
G01X927015Y73849D02*
X927165Y73999D01*
Y79623D01*
G01X933860D02*
X933858D01*
G01X933632Y73799D02*
X933858Y74025D01*
Y79623D01*
G01X920474Y41823D02*
X920472D01*
G01Y46914D02*
Y41823D01*
G01X929811Y67900D02*
X930511Y67200D01*
Y59933D01*
G01X923820D02*
X923818D01*
Y67363D01*
X923432Y67749D01*
G01X927167Y41823D02*
X927165D01*
G01X933860D02*
X933858D01*
G01X933632Y46898D02*
Y46824D01*
X933858Y46598D01*
Y41823D01*
G01X927165Y36049D02*
Y41823D01*
G01X913779Y36049D02*
Y41823D01*
G01X957283Y35957D02*
Y41823D01*
G01X917125Y67749D02*
X917126Y67748D01*
Y59933D01*
G01X913779Y73849D02*
Y79623D01*
G01X933858Y41823D02*
Y36225D01*
X933632Y35999D01*
G01X927165Y41823D02*
Y46764D01*
X927015Y46914D01*
G01X920472Y41823D02*
Y35999D01*
G01X957283Y41823D02*
Y50454D01*
X957558Y50729D01*
G01X950590Y41823D02*
Y46914D01*
G01X943897Y41823D02*
Y36049D01*
G01X913779Y41823D02*
Y46914D01*
G01X929511Y55500D02*
Y52914D01*
X929811Y52614D01*
G01X933858Y79623D02*
Y84398D01*
X933632Y84624D01*
Y84698D01*
G01X927165Y79623D02*
Y84564D01*
X927015Y84714D01*
G01X920472Y79623D02*
Y73799D01*
G01X929511Y93300D02*
Y90714D01*
X929811Y90414D01*
G01X923818Y97733D02*
Y90764D01*
X923468Y90414D01*
Y90314D01*
G01X917126Y97733D02*
Y96575D01*
X917125Y96574D01*
Y90414D01*
G01X947244Y59933D02*
Y58475D01*
X947243Y58474D01*
Y52614D01*
G01X953937Y59933D02*
Y52615D01*
X953936Y52614D01*
G01X950590Y79623D02*
Y84714D01*
G01X943897Y79623D02*
Y84714D01*
G01X957283Y79623D02*
Y86903D01*
X957774Y87394D01*
G01X913779Y79623D02*
Y84714D01*
G01X917126Y59933D02*
Y58775D01*
X917125Y58774D01*
Y52614D01*
G01X957283Y79623D02*
Y73883D01*
G01X953937Y59933D02*
Y67748D01*
G01X957283Y73883D02*
X957200Y73800D01*
G01X953937Y67748D02*
X953936Y67749D01*
G01X963976Y73757D02*
Y79623D01*
G01X970669Y73757D02*
Y79623D01*
G01Y46914D02*
Y41823D01*
G01X967322Y65814D02*
Y59933D01*
G01X963976Y46914D02*
Y41823D01*
G01X960629Y65814D02*
Y59933D01*
G01D02*
Y54857D01*
G01X970669Y41823D02*
Y35957D01*
G01X967322Y59933D02*
Y54857D01*
G01X970669Y79623D02*
Y87392D01*
G01X963976Y79623D02*
Y87392D01*
G01X970669Y79623D02*
X970671D01*
G01X963976D02*
X963978D01*
G01X960629Y59933D02*
X960631D01*
G01X967322D02*
X967324D01*
G01X963976Y41823D02*
X963978D01*
G01X963976D02*
Y35957D01*
G01X970669Y41823D02*
X970671D01*
G01X960629Y89964D02*
X960631Y89966D01*
G01X967322Y89964D02*
X967324Y89966D01*
G01X960631D02*
Y97733D01*
G01X967324Y89966D02*
Y97733D01*
G01X940553D02*
X940551D01*
G01X953939D02*
X953937D01*
G01X957100Y109500D02*
X950654Y112171D01*
X950600Y112300D01*
G01X917128Y97733D02*
X917126D01*
G01X923820D02*
X923818D01*
G01X927015Y104284D02*
X923818Y101087D01*
Y97733D01*
G01X933658Y105265D02*
X930511Y102118D01*
Y97733D01*
G01X920472Y104284D02*
X917126Y100938D01*
Y97733D01*
G01X953800Y105000D02*
X954900D01*
X957100Y107200D01*
Y109500D01*
G01X953937Y97733D02*
Y104863D01*
X953800Y105000D01*
G01X940551Y97733D02*
Y103245D01*
X938745Y105051D01*
G01X940553Y523134D02*
X940551Y523133D01*
Y519933D01*
X938732Y518114D01*
G01X950592Y505024D02*
X950590D01*
Y510114D01*
G01X943899Y505024D02*
X943897D01*
Y510114D01*
G01X933860Y505024D02*
X933858D01*
Y509798D01*
X933632Y510024D01*
Y510098D01*
G01X920474Y505024D02*
X920472D01*
Y510114D01*
G01X929511Y518700D02*
Y516114D01*
X929811Y515814D01*
G01X913781Y505024D02*
X913779D01*
Y510114D01*
G01X917128Y523134D02*
X917126Y523133D01*
Y521975D01*
X917125Y521974D01*
Y515814D01*
G01X923820Y523134D02*
X923818Y523133D01*
Y516164D01*
X923468Y515814D01*
Y515714D01*
G01X927167Y505024D02*
X927165D01*
Y509964D01*
X927015Y510114D01*
G01X953939Y523134D02*
Y515867D01*
X953886Y515814D01*
G01X947243D02*
X947244Y515815D01*
Y523133D01*
X947246Y523134D01*
G01X953939D02*
Y530946D01*
G01X960631Y523134D02*
X960629D01*
G01X967324D02*
X967322D01*
G01X960629Y515364D02*
Y523134D01*
G01X963978Y505024D02*
X963976D01*
G01X960629Y515364D02*
X963201Y512792D01*
X963976D01*
G01X967322Y515364D02*
X969894Y512792D01*
X970669D01*
G01D02*
Y505024D01*
G01X962800Y494315D02*
Y496959D01*
X961309Y498450D01*
Y499136D01*
G01X967322Y529014D02*
Y523134D01*
G01X970669Y505024D02*
X970671D01*
G01X963976D02*
Y512792D01*
G01X967322Y523134D02*
Y515364D01*
G01X960629Y523134D02*
Y529014D01*
G01X963976Y505024D02*
Y501266D01*
X961846Y499136D01*
G01X970669Y505024D02*
Y500951D01*
X967778Y498060D01*
G01X961846Y499136D02*
X961309D01*
G01X967778Y498060D02*
Y494315D01*
G01X957285Y542824D02*
X957283D01*
G01X940553Y560934D02*
X940551Y560933D01*
Y557733D01*
X938732Y555914D01*
G01X943899Y580624D02*
X943897D01*
Y585714D01*
G01X950592Y580624D02*
X950590D01*
Y585714D01*
G01X957285Y580624D02*
X957283D01*
G01Y580623D02*
Y580624D01*
G01X950592Y542824D02*
X950590D01*
Y547914D01*
G01X943899Y542824D02*
X943897D01*
Y547914D01*
G01X953886Y553614D02*
X953936Y553664D01*
Y559274D01*
X953937Y559275D01*
Y560933D01*
G01X947246Y560934D02*
X947244Y560933D01*
Y559475D01*
X947243Y559474D01*
Y553614D01*
G01X913781Y580624D02*
X913779D01*
Y585714D01*
G01X920474Y580624D02*
X920472D01*
Y585714D01*
G01X933860Y580624D02*
X933858D01*
Y585398D01*
X933632Y585624D01*
Y585698D01*
G01X927167Y580624D02*
X927165D01*
Y585564D01*
X927015Y585714D01*
G01X929511Y556500D02*
Y553914D01*
X929811Y553614D01*
G01X920474Y542824D02*
X920472D01*
Y547914D01*
G01X933860Y542824D02*
X933858D01*
Y547598D01*
X933632Y547824D01*
Y547898D01*
G01X917128Y560934D02*
X917126Y560933D01*
Y559775D01*
X917125Y559774D01*
Y553614D01*
G01X923820Y560934D02*
X923818Y560933D01*
Y553964D01*
X923468Y553614D01*
Y553514D01*
G01X927167Y542824D02*
X927165D01*
Y547764D01*
X927015Y547914D01*
G01X913781Y542824D02*
X913779D01*
Y547914D01*
G01X957283Y548200D02*
Y542824D01*
G01Y580624D02*
Y587903D01*
X957456Y588076D01*
Y588334D01*
G01X957283Y542824D02*
Y542823D01*
G01X953939Y530946D02*
X953936Y530949D01*
G01X967324Y560934D02*
X967322D01*
G01X960631D02*
X960629D01*
G01X963978Y580624D02*
X963976D01*
G01Y574757D02*
Y580624D01*
G01Y547914D02*
Y542824D01*
G01X970669Y547914D02*
Y542824D01*
X970671D01*
G01X963976Y580624D02*
Y585714D01*
G01X970669D02*
Y580624D01*
G01X960629Y560934D02*
Y555857D01*
G01X967322D02*
Y560934D01*
G01X963976Y536957D02*
Y542824D01*
G01X970669Y580624D02*
Y574757D01*
G01X960629Y560934D02*
Y566814D01*
G01X967322Y560934D02*
Y566814D01*
G01X963976Y542824D02*
X963978D01*
G01X970669Y580624D02*
X970671D01*
G01X970669Y536957D02*
X970671Y536959D01*
G01D02*
Y542824D01*
G01X940553Y598734D02*
X940551Y598733D01*
Y595533D01*
X938732Y593714D01*
G01X947246Y598734D02*
X947244Y598733D01*
Y597275D01*
X947243Y597274D01*
Y591414D01*
G01X974250Y589800D02*
X970731D01*
G01X953939Y598734D02*
X953937Y598733D01*
Y597075D01*
X953936Y597074D01*
Y591464D01*
X953886Y591414D01*
G01X929511Y594300D02*
Y591714D01*
X929811Y591414D01*
G01X917128Y598734D02*
X917126Y598733D01*
Y597575D01*
X917125Y597574D01*
Y591414D01*
G01X923820Y598734D02*
X923818Y598733D01*
Y591764D01*
X923468Y591414D01*
Y591314D01*
G01X967322Y604614D02*
Y598734D01*
G01X960629Y604614D02*
Y598734D01*
G01X967322D02*
Y593657D01*
G01X960629Y598734D02*
Y593657D01*
G01X967322Y598734D02*
X967324D01*
G01X960629D02*
X960631D01*
G01X1003108Y13200D02*
X1004222Y14314D01*
X1007100D01*
G01X1029300Y31978D02*
X1030400Y30878D01*
Y26150D01*
G01X1007100Y14314D02*
Y11714D01*
G01X1008227Y33342D02*
X1010458D01*
X1012000Y31800D01*
G01X1007100Y11714D02*
X1009536D01*
X1010900Y13078D01*
G01X1008200Y30736D02*
X1008227Y30763D01*
Y33342D01*
G01X1017521Y4023D02*
X1017519D01*
G01X1007482Y22133D02*
X1007480D01*
Y17014D01*
G01X1017521Y22133D02*
X1017519D01*
G01Y28014D02*
Y22133D01*
G01X1000787Y9122D02*
Y4023D01*
G01X1007480Y-1858D02*
Y4023D01*
X1007482D01*
G01X987403Y22133D02*
X987401D01*
Y17057D01*
G01X977364Y22133D02*
X977362D01*
Y17057D01*
G01X997443Y22133D02*
X997441D01*
Y17057D01*
G01X980708Y9114D02*
Y4023D01*
G01X990748Y9122D02*
Y4023D01*
G01X977364Y22133D02*
X977362Y22135D01*
Y28014D01*
G01X987403Y22133D02*
X987401Y22135D01*
Y28014D01*
G01X997443Y22133D02*
X997441Y22135D01*
Y28022D01*
G01X1007482Y22133D02*
X1007480Y22135D01*
Y28014D01*
G01X1017519Y9114D02*
Y4023D01*
G01X990748D02*
Y-1743D01*
G01X980708Y4023D02*
Y-4536D01*
G01X1000787Y4023D02*
Y-4536D01*
G01X1017519Y22133D02*
Y17042D01*
G01Y4023D02*
Y-1858D01*
G01X980708Y4023D02*
X980710D01*
G01X990748D02*
X990750D01*
G01X1000787D02*
X1000789D01*
G01X1007280Y9114D02*
X1007482Y8912D01*
G01D02*
Y4023D01*
G01X1023900Y77200D02*
Y74100D01*
G01X983900Y69900D02*
X987250D01*
G01Y51000D02*
X983900D01*
G01X1007380Y68335D02*
Y70935D01*
G01X1012000Y69400D02*
Y70900D01*
X1014100Y73000D01*
X1014350D01*
G01X1000787Y35957D02*
Y41823D01*
G01X1007482D02*
X1007480D01*
G01X977364Y97733D02*
X977362D01*
Y92757D01*
G01X997443Y97733D02*
X997441D01*
Y92757D01*
G01X990748Y73757D02*
Y79623D01*
G01X997443Y59933D02*
X997441D01*
Y65822D01*
G01X990748Y35957D02*
Y41823D01*
G01X980708Y35957D02*
Y41823D01*
G01X987403Y59933D02*
X987401D01*
Y65814D01*
G01X977364Y59933D02*
X977362D01*
Y65814D01*
G01X987401Y89964D02*
Y97733D01*
X987403D01*
G01X977364Y59933D02*
X977362Y59931D01*
Y54857D01*
G01X987403Y59933D02*
X987401Y59931D01*
Y54857D01*
G01X997443Y59933D02*
X997441Y59931D01*
Y54857D01*
G01X980708Y73757D02*
Y79623D01*
G01X1000787Y84599D02*
Y79623D01*
G01X1007480Y65736D02*
Y59933D01*
G01X980708Y41823D02*
Y46914D01*
G01X990748Y41823D02*
Y46922D01*
G01X1000787Y41823D02*
Y46922D01*
G01X1007480Y41823D02*
Y46914D01*
G01X990748Y79623D02*
Y87392D01*
G01X1000787Y79623D02*
Y73757D01*
G01X980708Y79623D02*
Y84714D01*
G01X1007482Y79623D02*
X1007480D01*
G01D02*
Y87500D01*
G01X1000787Y79623D02*
X1000789D01*
G01X990748D02*
X990750D01*
G01X980708D02*
X980710D01*
G01X1007480Y59933D02*
X1007482D01*
G01X980708Y41823D02*
X980710D01*
G01X990748D02*
X990750D01*
G01X1000787D02*
X1000789D01*
G01X1007480D02*
Y36679D01*
G01X1008099Y73479D02*
X1007480Y74098D01*
G01X1008226Y54842D02*
X1007480Y55588D01*
G01X1007482Y97733D02*
X1007480D01*
Y92704D01*
G01Y36679D02*
X1008217Y35942D01*
G01X1007480Y74098D02*
Y79623D01*
G01Y55588D02*
Y59933D01*
G01Y92704D02*
X1007495Y92689D01*
Y92578D01*
X1007573Y92500D01*
G01X1030300Y63200D02*
X1027033Y59933D01*
X1020868D01*
G01X974100Y103500D02*
Y103700D01*
X972900Y104900D01*
Y107100D01*
G01X977364Y523134D02*
X977362D01*
G01X1007482Y505024D02*
X1007480D01*
Y509068D01*
X1008526Y510114D01*
G01X1017521Y523134D02*
X1017519D01*
G01X997443D02*
X997441D01*
Y518157D01*
G01X980710Y505024D02*
X980708D01*
Y510114D01*
G01X987403Y523134D02*
X987401D01*
Y515364D01*
G01X1008526Y510114D02*
X1008650Y510238D01*
Y515200D01*
G01X1016473Y510114D02*
X1017521Y509066D01*
Y505024D01*
G01X1016473Y515152D02*
Y510114D01*
G01X990748Y512792D02*
Y505024D01*
X990750D01*
G01X987401Y515364D02*
X988176D01*
X990748Y512792D01*
G01X977362Y529014D02*
Y523134D01*
G01X1017519D02*
Y529057D01*
G01X977362Y523134D02*
Y518157D01*
G01X1000789Y505024D02*
X1000787D01*
Y509702D01*
G01X1008650Y515200D02*
X1007480Y516370D01*
G01X1016473Y515152D02*
X1017521Y516200D01*
G01X987403Y529012D02*
Y523134D01*
G01X997443Y529020D02*
Y523134D01*
G01X1007482Y528940D02*
Y523134D01*
G01X1000787Y509702D02*
X1000490Y509999D01*
G01X1007480Y516370D02*
Y523134D01*
X1007482D01*
G01X1017521Y516200D02*
Y523131D01*
X1017519Y523133D01*
Y523134D01*
G01X1007207Y531537D02*
Y534137D01*
G01X1011050Y570400D02*
X1009440Y572010D01*
X1007332D01*
G01X1011500Y532800D02*
Y531400D01*
X1013500Y529400D01*
Y529200D01*
G01X1007147Y550511D02*
X1005989D01*
X1005400Y551100D01*
X1004008D01*
X1003108Y552000D01*
G01X1028800Y532978D02*
Y536200D01*
X1026500Y538500D01*
G01X1007332Y572010D02*
Y569410D01*
G01X1026500Y538500D02*
Y541000D01*
G01X1028900Y551500D02*
Y548800D01*
X1026500Y546400D01*
G01X1007147Y553111D02*
Y550511D01*
G01X1011100Y551900D02*
X1009889Y553111D01*
X1007147D01*
G01X1017521Y542824D02*
X1017519D01*
G01X1017521Y560934D02*
X1017519D01*
G01X997443D02*
X997441D01*
G01X977364D02*
X977362D01*
G01X987403D02*
X987401D01*
G01X980708Y585714D02*
Y580624D01*
G01X990748Y585722D02*
Y580624D01*
G01X1000787Y585722D02*
Y580624D01*
G01X990748Y547922D02*
Y542824D01*
X990750D01*
G01X980708Y547914D02*
Y542824D01*
X980710D01*
G01X1000787Y547922D02*
Y542824D01*
X1000789D01*
G01X990748Y574757D02*
Y580624D01*
G01X987401Y555857D02*
Y560934D01*
G01X977362Y555857D02*
Y560934D01*
G01X997441Y555857D02*
Y560934D01*
G01X1000787Y574757D02*
Y580624D01*
G01X980708Y574757D02*
Y580624D01*
G01X1007480D02*
Y574742D01*
G01Y542824D02*
X1007482D01*
G01X1007480Y560934D02*
X1007482D01*
G01X990748Y580624D02*
X990750D01*
G01X987401Y560934D02*
Y566814D01*
G01X977362Y560934D02*
Y566814D01*
G01X997441Y560934D02*
Y566822D01*
G01X1000787Y580624D02*
X1000789D01*
G01X980708D02*
X980710D01*
G01X1007480D02*
X1007482D01*
G01X1007518Y566814D02*
X1007480Y566776D01*
G01X1017519Y560934D02*
Y566138D01*
G01X1000787Y536957D02*
X1000789Y536959D01*
G01X990748Y536957D02*
X990750Y536959D01*
G01X987401Y529014D02*
X987403Y529012D01*
G01X997441Y529022D02*
X997443Y529020D01*
G01X980708Y536957D02*
X980710Y536959D01*
G01X1017300Y536200D02*
X1017519Y536419D01*
G01X1007480Y542824D02*
Y536765D01*
G01Y528942D02*
X1007482Y528940D01*
G01X1006633Y585714D02*
X1007480Y584867D01*
G01X1016819Y555842D02*
X1017519Y556542D01*
G01X1017300Y547914D02*
X1017519Y547695D01*
G01X1007480Y542824D02*
Y547714D01*
G01Y560934D02*
Y555855D01*
G01Y566776D02*
Y560934D01*
G01X1017519Y566138D02*
X1016843Y566814D01*
X1016800D01*
G01X1000789Y536959D02*
Y542824D01*
G01X990750Y536959D02*
Y542824D01*
G01X980710Y536959D02*
Y542824D01*
G01X1017519Y536419D02*
Y542824D01*
G01X1007480Y536765D02*
X1007518Y536727D01*
G01X1007480Y584867D02*
Y580624D01*
G01X1017519Y556542D02*
Y560934D01*
G01Y547695D02*
Y542824D01*
G01X1007480Y547714D02*
X1007280Y547914D01*
G01X1007480Y555855D02*
X1007505D01*
X1007518Y555842D01*
G01X987250Y589800D02*
X983900D01*
G01X1023200Y610700D02*
X1023700Y611200D01*
Y618200D01*
G01D02*
X1018757D01*
X1018734Y618177D01*
X1018234D01*
G01X997443Y598734D02*
X997441D01*
G01X1017521D02*
X1017519D01*
G01X1007482D02*
X1007480D01*
G01X1006634Y593642D02*
X1007480Y594488D01*
Y598734D01*
G01X987403D02*
X987401D01*
G01Y593657D02*
Y598734D01*
G01X977362Y593657D02*
Y598734D01*
G01X997441Y607292D02*
Y598734D01*
G01X1017519Y604614D02*
Y598734D01*
G01X977362D02*
Y607292D01*
G01X987401Y598734D02*
Y604499D01*
G01X1007480Y598734D02*
Y604614D01*
G01X1017519Y598734D02*
Y593642D01*
G01X997441Y598734D02*
Y593657D01*
G01X977362Y598734D02*
X977364D01*
G01X1067716Y28007D02*
Y22133D01*
G01Y9107D02*
Y4023D01*
G01X1081102Y-4536D02*
Y4023D01*
G01X1074409Y9107D02*
Y4023D01*
G01X1091141Y9107D02*
Y4023D01*
G01X1047639D02*
X1047637D01*
G01X1057677Y9107D02*
Y4023D01*
G01D02*
Y-1742D01*
X1057676Y-1743D01*
G01X1074409Y4023D02*
Y-4536D01*
G01X1067716Y4023D02*
Y-4536D01*
G01Y22133D02*
Y17042D01*
G01X1091141Y4023D02*
Y-1843D01*
G01X1081102Y4023D02*
Y9107D01*
G01X1091141Y28007D02*
Y22133D01*
G01X1047637Y4023D02*
Y-4536D01*
G01Y4023D02*
Y9107D01*
G01X1057677Y4023D02*
X1057679D01*
G01X1067716D02*
X1067718D01*
G01X1074409D02*
X1074411D01*
G01X1081102D02*
X1081104D01*
G01X1091141D02*
X1091143D01*
G01X1067716Y22133D02*
X1067718D01*
G01X1077755D02*
Y28020D01*
G01Y22133D02*
X1077757D01*
G01X1084448D02*
X1084450D01*
G01X1091141D02*
X1091143D01*
G01X1050985Y28022D02*
X1050984Y28021D01*
G01X1050986Y22133D02*
X1050984D01*
G01X1077755D02*
Y17059D01*
G01X1084448Y22133D02*
Y17059D01*
G01X1061025Y22133D02*
Y17058D01*
G01X1091141Y22133D02*
Y17059D01*
G01X1084448Y22133D02*
Y28096D01*
G01X1061024Y28022D02*
X1061025Y28021D01*
G01X1077755Y17059D02*
X1077757Y17057D01*
G01X1084448Y17059D02*
X1084450Y17057D01*
G01X1061025Y17058D02*
X1061024Y17057D01*
G01X1084448Y28096D02*
X1084450Y28098D01*
G01X1061025Y28021D02*
Y22133D01*
G01X1050984Y28021D02*
Y22133D01*
G01X1067716Y35942D02*
Y41823D01*
G01X1074409Y46907D02*
Y41823D01*
G01X1081102Y46907D02*
Y41823D01*
G01X1047637Y35942D02*
Y41823D01*
G01X1057677Y36058D02*
Y41823D01*
G01X1047637D02*
Y46907D01*
G01X1050986Y59933D02*
X1050984D01*
G01X1091141Y41823D02*
Y46907D01*
G01Y59933D02*
Y65807D01*
G01X1047637Y41823D02*
X1047639D01*
G01X1057677D02*
X1057679D01*
G01X1067716D02*
X1067718D01*
G01X1074409D02*
X1074411D01*
G01X1081102D02*
X1081104D01*
G01X1091141D02*
X1091143D01*
G01X1091141Y59933D02*
X1091143D01*
G01X1084448D02*
X1084450D01*
G01X1050984D02*
Y54842D01*
G01X1061025Y59933D02*
Y54858D01*
X1061024Y54857D01*
G01X1057677Y41823D02*
Y46907D01*
G01X1067716Y41823D02*
Y46907D01*
G01X1074409Y41823D02*
Y35942D01*
G01X1081102Y41823D02*
Y35942D01*
G01X1077755Y59933D02*
X1077757D01*
G01X1077755Y65820D02*
Y59933D01*
G01X1084450Y65822D02*
X1084448Y65820D01*
G01X1050985Y65822D02*
X1050984Y65821D01*
G01X1084448Y59933D02*
Y54859D01*
G01X1077755Y59933D02*
Y54859D01*
G01X1067718Y59933D02*
Y54844D01*
G01X1091260Y36076D02*
Y41704D01*
X1091141Y41823D01*
G01X1084448Y65820D02*
Y59933D01*
G01X1067718Y65805D02*
Y59933D01*
G01X1061025Y65821D02*
Y59933D01*
G01X1050984Y65821D02*
Y59933D01*
G01X1084448Y54859D02*
X1084450Y54857D01*
G01X1077755Y54859D02*
X1077757Y54857D01*
G01X1091141Y54859D02*
Y59933D01*
G01X1092000Y270000D02*
X1093510D01*
X1096756Y273246D01*
G01X1095788Y494860D02*
Y499292D01*
X1097834Y501338D01*
Y505024D01*
G01X1095788Y494860D02*
X1101181Y500253D01*
Y505024D01*
G01X1091141Y518057D02*
Y523134D01*
X1091143D01*
G01X1061025D02*
X1061023D01*
G01X1067718D02*
X1067716D01*
G01X1090288Y494860D02*
X1085590D01*
X1082800Y497650D01*
G01X1077757Y523134D02*
X1077755D01*
G01Y528955D02*
Y523134D01*
G01X1061023Y529014D02*
Y523134D01*
G01X1067716Y528899D02*
Y523134D01*
G01X1050986D02*
X1050984D01*
G01Y518158D02*
Y523134D01*
G01X1091141Y518057D02*
Y512792D01*
G01X1050984Y523134D02*
Y528684D01*
G01X1077755Y523134D02*
Y518157D01*
G01X1067716Y523134D02*
Y515364D01*
G01X1061023Y523134D02*
Y515364D01*
G01X1079880Y498722D02*
X1081102Y499944D01*
G01X1091143Y505024D02*
X1091141D01*
G01X1081104D02*
X1081102D01*
G01X1090288Y494860D02*
X1091141Y495713D01*
G01Y505024D02*
Y495713D01*
G01X1081102Y505024D02*
Y499944D01*
G01X1091143Y560934D02*
X1091141D01*
G01X1067716Y566807D02*
Y560934D01*
G01X1067718Y580624D02*
Y585597D01*
X1067716Y585599D01*
G01X1074409Y547907D02*
Y542824D01*
G01X1047639D02*
X1047637D01*
G01X1091141Y555842D02*
Y560934D01*
G01X1047637Y585707D02*
Y580624D01*
G01X1057677Y547907D02*
Y542824D01*
G01Y585707D02*
Y580624D01*
G01X1067716Y547907D02*
Y542824D01*
G01X1074409Y585707D02*
Y580624D01*
G01X1050984Y560934D02*
X1050986D01*
G01X1091141Y547907D02*
Y542824D01*
G01X1081102Y547907D02*
Y542824D01*
G01Y585707D02*
Y580624D01*
G01X1091141Y585707D02*
Y580624D01*
G01X1077755Y560934D02*
X1077757D01*
G01X1050984D02*
Y555842D01*
G01X1067716Y542824D02*
Y536942D01*
G01X1091141Y542824D02*
Y536957D01*
G01X1081102Y542824D02*
Y537202D01*
G01X1057677Y542824D02*
Y537058D01*
G01X1047637Y574742D02*
Y580624D01*
G01X1057677Y574858D02*
Y580624D01*
G01X1074409Y574809D02*
Y580624D01*
G01X1091141Y574757D02*
Y580624D01*
G01X1081102Y574902D02*
Y580624D01*
G01X1074409Y536942D02*
Y542824D01*
G01X1067716Y555842D02*
Y560934D01*
G01X1047637Y536942D02*
Y542824D01*
G01X1067716D02*
X1067718D01*
G01X1091141D02*
X1091143D01*
G01X1081102D02*
X1081104D01*
G01X1057677D02*
X1057679D01*
G01X1047637Y580624D02*
X1047639D01*
G01X1057677D02*
X1057679D01*
G01X1074409D02*
X1074411D01*
G01X1091141D02*
X1091143D01*
G01X1091141Y560934D02*
Y566807D01*
G01X1081102Y580624D02*
X1081104D01*
G01X1061023Y560934D02*
X1061025D01*
G01X1074409Y542824D02*
X1074411D01*
G01X1067716Y560934D02*
X1067718D01*
G01X1084448D02*
X1084450D01*
G01X1047637Y542824D02*
Y547907D01*
G01X1077757Y555857D02*
X1077755Y555859D01*
G01X1061024Y555857D02*
X1061023Y555858D01*
G01X1084450Y555857D02*
X1084448Y555859D01*
G01X1084450Y566822D02*
X1084448Y566820D01*
G01X1077755Y560934D02*
Y566820D01*
G01X1067718Y580624D02*
Y574744D01*
G01X1061024Y566822D02*
X1061023Y566821D01*
G01X1050985Y566822D02*
X1050984Y566821D01*
G01X1077755Y555859D02*
Y560934D01*
G01X1061023Y555858D02*
Y560934D01*
G01X1084448Y555859D02*
Y560934D01*
G01Y566820D02*
Y560934D01*
G01X1077755Y566820D02*
X1077757Y566822D01*
G01X1067718Y574744D02*
X1067716Y574742D01*
G01X1061023Y566821D02*
Y560934D01*
G01X1050984Y566821D02*
Y560934D01*
G01X1092116Y589800D02*
X1094200D01*
X1095300Y590900D01*
X1098300D01*
G01X1061023Y604614D02*
Y604621D01*
G01X1084450Y598734D02*
X1084448D01*
G01X1091143D02*
X1091141D01*
G01X1067718D02*
X1067716D01*
G01X1091141Y593642D02*
Y598734D01*
G01X1077755Y593758D02*
Y598734D01*
X1077757D01*
G01X1061023D02*
Y604614D01*
G01Y598734D02*
X1061025D01*
G01X1067716D02*
Y593642D01*
G01X1050984Y598734D02*
Y593642D01*
G01X1067716Y598734D02*
Y604499D01*
G01X1091141Y598734D02*
Y607292D01*
G01X1084448Y598734D02*
Y607292D01*
G01X1050984Y598734D02*
X1050986D01*
G01X1061024Y593657D02*
Y593757D01*
X1061023Y593758D01*
G01X1084448Y598734D02*
Y593659D01*
G01X1050984Y598734D02*
Y607291D01*
G01X1077757Y598734D02*
Y607290D01*
G01X1061023Y593758D02*
Y598734D01*
G01X1084448Y593659D02*
X1084450Y593657D01*
G01X1050984Y607291D02*
X1050983Y607292D01*
G01X1077757Y607290D02*
X1077755Y607292D01*
G01X1107876Y4023D02*
X1107874D01*
G01X1114340Y9098D02*
Y9024D01*
X1114566Y8798D01*
Y4023D01*
G01X1124608D02*
X1124606D01*
G01X1137994D02*
X1137992D01*
G01X1144687D02*
X1144685D01*
G01X1140952Y29949D02*
X1141338Y29563D01*
Y22133D01*
G01X1141340D02*
X1141338D01*
G01X1134647D02*
X1134645D01*
G01X1147331Y14814D02*
X1147064Y15081D01*
Y17800D01*
G01X1127954Y22133D02*
X1127952D01*
G01Y14814D02*
Y22133D01*
G01X1151380Y4023D02*
X1151378D01*
G01X1151152Y9098D02*
Y9024D01*
X1151378Y8798D01*
Y4023D01*
G01X1131301D02*
X1131299D01*
G01Y-1751D02*
Y4023D01*
G01X1121261Y22133D02*
X1121259D01*
G01X1119440Y17114D02*
X1121259Y18933D01*
Y22133D01*
G01X1104529D02*
X1104527D01*
G01X1097836D02*
X1097834D01*
G01Y28100D02*
Y22133D01*
G01X1110253Y15081D02*
Y17800D01*
G01X1101183Y4023D02*
X1101181D01*
G01Y9114D02*
Y4023D01*
G01X1107874Y-1751D02*
Y4023D01*
G01X1124606Y-1751D02*
Y4023D01*
G01X1137992Y9114D02*
Y4023D01*
G01X1134645Y14814D02*
Y22133D01*
G01X1144685Y-1751D02*
Y4023D01*
G01X1156252Y17114D02*
X1158070Y18932D01*
Y22133D01*
G01X1101181Y4023D02*
Y-1801D01*
G01X1111220Y22133D02*
Y29400D01*
X1110520Y30100D01*
G01X1097834Y22133D02*
Y17666D01*
X1098500Y17000D01*
G01X1104527Y22133D02*
Y15164D01*
X1104177Y14814D01*
Y14714D01*
G01X1121259Y22133D02*
Y26130D01*
X1119453Y27936D01*
G01X1131299Y4023D02*
Y9114D01*
G01X1127952Y22133D02*
Y29949D01*
G01X1134645Y22133D02*
Y29949D01*
G01X1137992Y4023D02*
Y-1801D01*
G01X1124606Y4023D02*
Y9114D01*
G01X1114566Y4023D02*
X1114568D01*
G01X1107874D02*
Y9064D01*
X1107824Y9114D01*
X1107724D01*
G01X1151378Y4023D02*
Y-1575D01*
X1151152Y-1801D01*
G01X1148031Y22133D02*
Y29400D01*
X1147331Y30100D01*
G01X1141338Y22133D02*
Y15164D01*
X1140988Y14814D01*
Y14714D01*
G01X1158070Y22133D02*
Y26131D01*
X1156265Y27936D01*
G01X1144685Y4023D02*
Y9064D01*
X1144635Y9114D01*
X1144535D01*
G01X1114566Y4023D02*
Y-1575D01*
G01X1104141Y29949D02*
X1104527Y29563D01*
G01X1114566Y-1575D02*
X1114340Y-1801D01*
G01X1104527Y29563D02*
Y22133D01*
G01X1097836Y4023D02*
X1097834D01*
Y11100D01*
G01X1114568Y41823D02*
X1114566D01*
G01X1107876Y79623D02*
X1107874D01*
G01X1131301Y41823D02*
X1131299D01*
G01X1124608D02*
X1124606D01*
G01X1144685Y36049D02*
Y41823D01*
G01X1131301Y79623D02*
X1131299D01*
G01X1140988Y90314D02*
Y90414D01*
X1141338Y90764D01*
Y97733D01*
G01X1151380Y79623D02*
X1151378D01*
G01X1144687D02*
X1144685D01*
G01X1124608D02*
X1124606D01*
G01X1137994D02*
X1137992D01*
G01Y84714D02*
Y79623D01*
G01X1134647Y97733D02*
X1134645D01*
Y90414D01*
G01X1127954Y97733D02*
X1127952D01*
Y90414D01*
G01X1124606Y73849D02*
Y79623D01*
G01X1141340Y59933D02*
X1141338D01*
G01X1140952Y67749D02*
X1141338Y67363D01*
Y59933D01*
G01X1134647D02*
X1134645D01*
G01Y52614D02*
Y59933D01*
G01X1137994Y41823D02*
X1137992D01*
G01Y35999D02*
Y41823D01*
G01X1127954Y59933D02*
X1127952D01*
G01Y67749D02*
Y59933D01*
G01X1147331Y67900D02*
X1148031Y67200D01*
Y59933D01*
G01X1156265Y65736D02*
X1158070Y63931D01*
Y59933D01*
G01X1151380Y41823D02*
X1151378D01*
G01X1151152Y35999D02*
X1151378Y36225D01*
Y41823D01*
G01X1097836Y79623D02*
X1097834D01*
G01X1110253Y93400D02*
Y90581D01*
X1110520Y90314D01*
G01X1121261Y97733D02*
X1121259D01*
Y94533D01*
X1119440Y92714D01*
G01X1114568Y79623D02*
X1114566D01*
G01X1114340Y73799D02*
X1114566Y74025D01*
Y79623D01*
G01X1101183D02*
X1101181D01*
G01Y73799D02*
Y79623D01*
G01X1107876Y41823D02*
X1107874D01*
G01Y36049D02*
Y41823D01*
G01X1121261Y59933D02*
X1121259D01*
G01X1119453Y65736D02*
X1121259Y63930D01*
Y59933D01*
G01X1097836D02*
X1097834D01*
G01X1104529D02*
X1104527D01*
G01X1097836Y41823D02*
X1097834D01*
G01X1111222Y59933D02*
X1111220D01*
G01X1110520Y67900D02*
X1111220Y67200D01*
Y59933D01*
G01X1101183Y41823D02*
X1101181D01*
G01Y35999D02*
Y41823D01*
G01X1144535Y46914D02*
X1144635D01*
X1144685Y46864D01*
Y41823D01*
G01X1114340Y35999D02*
X1114566Y36225D01*
Y41823D01*
G01X1131299Y36049D02*
Y41823D01*
G01X1124606Y36049D02*
Y41823D01*
G01X1107724Y84714D02*
X1107824D01*
X1107874Y84664D01*
Y79623D01*
G01X1131299Y73849D02*
Y79623D01*
G01X1156252Y92714D02*
X1158070Y94532D01*
Y97733D01*
G01X1151152Y84698D02*
Y84624D01*
X1151378Y84398D01*
Y79623D01*
G01X1144535Y84714D02*
X1144635D01*
X1144685Y84664D01*
Y79623D01*
G01X1101181Y41823D02*
Y46900D01*
G01X1097834Y41823D02*
Y46684D01*
X1098125Y46975D01*
G01X1107874Y41823D02*
Y46864D01*
X1107824Y46914D01*
X1107724D01*
G01X1137992Y41823D02*
Y46914D01*
G01X1124606Y41823D02*
Y46914D01*
G01X1131299Y41823D02*
Y46914D01*
G01X1114566Y41823D02*
Y46598D01*
X1114340Y46824D01*
Y46898D01*
G01X1110253Y55600D02*
Y52881D01*
G01X1104527Y59933D02*
Y52964D01*
X1104177Y52614D01*
Y52514D01*
G01X1097834Y59933D02*
Y55630D01*
X1098581Y54883D01*
G01X1121259Y59933D02*
Y56733D01*
X1119440Y54914D01*
G01X1101181Y79623D02*
Y84714D01*
G01X1114566Y79623D02*
Y84398D01*
X1114340Y84624D01*
Y84698D01*
G01X1097834Y79623D02*
Y84912D01*
X1098218Y85296D01*
G01X1127952Y59933D02*
Y52614D01*
G01X1134645Y59933D02*
Y67749D01*
G01X1137992Y79623D02*
Y73799D01*
G01X1124606Y79623D02*
Y84714D01*
G01X1131299Y79623D02*
Y84714D01*
G01X1107874Y79623D02*
Y73849D01*
G01X1151378Y41823D02*
Y46598D01*
X1151152Y46824D01*
Y46898D01*
G01X1144685Y41823D02*
X1144687D01*
G01X1158070Y59933D02*
Y56732D01*
X1156252Y54914D01*
G01X1147064Y55600D02*
Y52881D01*
X1147331Y52614D01*
G01X1141338Y59933D02*
Y52964D01*
X1144535Y49767D01*
Y46914D01*
G01X1147064Y93400D02*
Y90681D01*
X1147331Y90414D01*
G01X1144685Y79623D02*
Y73849D01*
G01X1151378Y79623D02*
Y74025D01*
X1151152Y73799D01*
G01X1097834Y79623D02*
Y73962D01*
G01X1104527Y59933D02*
Y67363D01*
G01X1097834Y59933D02*
Y67689D01*
G01X1098022Y35761D02*
X1097834Y35949D01*
G01Y73962D02*
X1098207Y73589D01*
G01X1097834Y67689D02*
X1098235Y68090D01*
G01X1104527Y67363D02*
X1104141Y67749D01*
G01X1097834Y35949D02*
Y41823D01*
G01X1141340Y97733D02*
X1141338D01*
G01X1144685Y104314D02*
X1148031Y100968D01*
Y97733D01*
G01X1158070D02*
Y103246D01*
X1156265Y105051D01*
G01X1141338Y97733D02*
Y101218D01*
X1138242Y104314D01*
G01X1096756Y273246D02*
Y274841D01*
G01X1134647Y523134D02*
X1134645Y523133D01*
Y515814D01*
G01X1124608Y505024D02*
X1124606D01*
Y510114D01*
G01X1131301Y505024D02*
X1131299D01*
Y510114D01*
G01X1137994Y505024D02*
X1137992D01*
Y510114D01*
G01X1144687Y505024D02*
X1144685D01*
Y510064D01*
X1144635Y510114D01*
X1144535D01*
G01X1151380Y505024D02*
X1151378D01*
Y509798D01*
X1151152Y510024D01*
Y510098D01*
G01X1147064Y518800D02*
Y516081D01*
X1147331Y515814D01*
G01X1158072Y523134D02*
X1158070Y523133D01*
Y519932D01*
X1156252Y518114D01*
G01X1141340Y523134D02*
X1141338Y523133D01*
Y516164D01*
X1140988Y515814D01*
Y515714D01*
G01X1127954Y523134D02*
X1127952Y523133D01*
Y515814D01*
G01X1121259Y519933D02*
X1119440Y518114D01*
G01X1097836Y505024D02*
X1097834D01*
G01X1101183D02*
X1101181D01*
G01X1104177Y515714D02*
Y515814D01*
X1104527Y516164D01*
Y523133D01*
G01X1107724Y510114D02*
X1107824D01*
X1107874Y510064D01*
Y505024D01*
X1107876D01*
G01X1114340Y510098D02*
Y510024D01*
X1114566Y509798D01*
Y505024D01*
X1114568D01*
G01X1101181D02*
Y510114D01*
G01X1097834Y505024D02*
Y512303D01*
X1097343Y512794D01*
G01X1097834Y523133D02*
Y518014D01*
X1098300Y517548D01*
Y515300D01*
G01X1158072Y560934D02*
X1158070Y560933D01*
Y557732D01*
X1156252Y555914D01*
G01X1124608Y580624D02*
X1124606D01*
Y585714D01*
G01X1131301Y580624D02*
X1131299D01*
Y585714D01*
G01X1137994Y580624D02*
X1137992D01*
Y585714D01*
G01X1144687Y580624D02*
X1144685D01*
Y585664D01*
X1144635Y585714D01*
X1144535D01*
G01X1151152Y585698D02*
Y585624D01*
X1151378Y585398D01*
Y580624D01*
X1151380D01*
G01X1124608Y542824D02*
X1124606D01*
Y547914D01*
G01X1131301Y542824D02*
X1131299D01*
Y547914D01*
G01X1151380Y542824D02*
X1151378D01*
Y547598D01*
X1151152Y547824D01*
Y547898D01*
G01X1134647Y560934D02*
X1134645Y560933D01*
Y553614D01*
G01X1141340Y560934D02*
X1141338Y560933D01*
Y553964D01*
X1140988Y553614D01*
Y553514D01*
G01X1147064Y556600D02*
Y553881D01*
X1147331Y553614D01*
G01X1144535Y547914D02*
X1144635D01*
X1144685Y547864D01*
Y542824D01*
X1144687D01*
G01X1137992Y547914D02*
Y542824D01*
X1137994D01*
G01X1127954Y560934D02*
X1127952Y560933D01*
Y553614D01*
G01X1121261Y560934D02*
X1121259Y560933D01*
Y557733D01*
X1119440Y555914D01*
G01X1114568Y580624D02*
X1114566D01*
Y585398D01*
X1114340Y585624D01*
Y585698D01*
G01X1107876Y580624D02*
X1107874D01*
Y585664D01*
X1107824Y585714D01*
X1107724D01*
G01X1101183Y580624D02*
X1101181D01*
G01X1114340Y547898D02*
Y547824D01*
X1114566Y547598D01*
Y542824D01*
X1114568D01*
G01X1107724Y547914D02*
X1107824D01*
X1107874Y547864D01*
Y542824D01*
X1107876D01*
G01X1097836D02*
X1097834D01*
G01X1101183D02*
X1101181D01*
G01Y547914D02*
Y542824D01*
G01D02*
Y542823D01*
G01X1097834Y542824D02*
Y549559D01*
X1098118Y549843D01*
G01X1097834Y560933D02*
Y555814D01*
X1098300Y555348D01*
Y553100D01*
G01X1101181Y574799D02*
Y580624D01*
G01D02*
Y585714D01*
G01X1097834Y542824D02*
Y542823D01*
G01X1097836Y580624D02*
Y587901D01*
X1097343Y588394D01*
G01X1147064Y594400D02*
Y591681D01*
X1147331Y591414D01*
G01X1141340Y598734D02*
X1141480Y598594D01*
Y591906D01*
X1140988Y591414D01*
Y591314D01*
G01X1104529Y598734D02*
Y591766D01*
X1104177Y591414D01*
Y591314D01*
G01X1097836Y598734D02*
Y593612D01*
X1098300Y593148D01*
Y590900D01*
G01X1121261Y598734D02*
Y595535D01*
X1119440Y593714D01*
G01X1127954Y598734D02*
Y591416D01*
X1127952Y591414D01*
G01X1134647Y598734D02*
Y591416D01*
X1134645Y591414D01*
G01X1158072Y598734D02*
X1158207Y598599D01*
Y595669D01*
X1156252Y593714D01*
G01X1174805Y4023D02*
X1174803D01*
G01X1161419D02*
X1161417D01*
G01X1168112D02*
X1168110D01*
G01X1158072Y22133D02*
X1158070D01*
G01X1164765D02*
X1164763D01*
G01X1171458D02*
X1171456D01*
G01X1178151D02*
X1178149D01*
G01X1208269D02*
X1208267D01*
G01X1198230Y4023D02*
X1198228D01*
G01X1211616D02*
X1211614D01*
G01X1218309D02*
X1218307D01*
G01X1201576Y22133D02*
X1201574D01*
G01X1184844D02*
X1184842D01*
G01X1184142Y14814D02*
X1183875Y15081D01*
Y17800D01*
G01X1194883Y22133D02*
X1194881D01*
G01X1193063Y17114D02*
X1194881Y18932D01*
Y22133D01*
G01X1181498Y4023D02*
X1181496D01*
G01Y-1751D02*
Y4023D01*
G01X1204923D02*
X1204921D01*
G01Y-1751D02*
Y4023D01*
G01X1188191D02*
X1188189D01*
Y8798D01*
X1187963Y9024D01*
Y9098D01*
G01X1214574Y29949D02*
X1214960Y29563D01*
Y22133D01*
G01X1174803Y-1801D02*
Y4023D01*
G01X1161417Y-1751D02*
Y4023D01*
G01X1168110Y-1751D02*
Y4023D01*
G01X1164763Y14814D02*
Y22133D01*
G01X1171456Y14814D02*
Y22133D01*
G01X1177799Y14714D02*
Y14814D01*
X1178149Y15164D01*
Y22133D01*
G01X1198228Y9114D02*
Y4023D01*
G01X1208267Y29949D02*
Y22133D01*
G01X1211614Y-1801D02*
Y4023D01*
G01X1218307Y-1751D02*
Y4023D01*
G01X1201574Y29949D02*
Y22133D01*
G01X1181496Y4023D02*
Y9064D01*
X1181446Y9114D01*
X1181346D01*
G01X1194881Y22133D02*
Y26131D01*
X1193076Y27936D01*
G01X1184842Y22133D02*
Y29400D01*
X1184142Y30100D01*
G01X1198228Y4023D02*
Y-1751D01*
G01X1178149Y22133D02*
Y29563D01*
X1177763Y29949D01*
G01X1171456Y22133D02*
Y29949D01*
G01X1164763Y22133D02*
Y29949D01*
G01X1168110Y4023D02*
Y9114D01*
G01X1161417Y4023D02*
Y9114D01*
G01X1174803Y4023D02*
Y9114D01*
G01X1204921Y4023D02*
Y9114D01*
G01X1201574Y22133D02*
Y14814D01*
G01X1218307Y4023D02*
Y9064D01*
X1218257Y9114D01*
X1218157D01*
G01X1211614Y4023D02*
Y9114D01*
G01X1208267Y22133D02*
Y14814D01*
G01X1168112Y41823D02*
X1168110D01*
G01X1181346Y46914D02*
Y50854D01*
X1178149Y54051D01*
Y59933D01*
G01X1174805Y41823D02*
X1174803D01*
G01X1161419Y79623D02*
X1161417D01*
G01X1204923Y41823D02*
X1204921D01*
G01X1188191D02*
X1188189D01*
G01X1218309D02*
X1218307D01*
G01X1188191Y79623D02*
X1188189D01*
G01X1218309D02*
X1218307D01*
G01X1204923D02*
X1204921D01*
G01X1181498D02*
X1181496D01*
G01Y73849D02*
Y79623D01*
G01X1184142Y90414D02*
X1183875Y90681D01*
Y93400D01*
G01X1211616Y79623D02*
X1211614D01*
G01Y73799D02*
Y79623D01*
G01X1198230D02*
X1198228D01*
G01Y73849D02*
Y79623D01*
G01X1214962Y97733D02*
X1214960D01*
Y91240D01*
X1215786Y90414D01*
X1220953D01*
G01X1181498Y41823D02*
X1181496D01*
G01X1211616D02*
X1211614D01*
G01Y35999D02*
Y41823D01*
G01X1198230D02*
X1198228D01*
G01X1184844Y59933D02*
X1184842D01*
G01X1184142Y67900D02*
X1184842Y67200D01*
Y59933D01*
G01X1201576D02*
X1201574D01*
G01Y67749D02*
Y59933D01*
G01X1194883D02*
X1194881D01*
G01X1193076Y65736D02*
X1194881Y63931D01*
Y59933D01*
G01X1214574Y67749D02*
X1214960Y67363D01*
Y59933D01*
G01X1208269D02*
X1208267D01*
G01Y67749D02*
Y59933D01*
G01X1198228Y46914D02*
Y41823D01*
G01X1168112Y79623D02*
X1168110D01*
G01Y73849D02*
Y79623D01*
G01X1174805D02*
X1174803D01*
G01Y84714D02*
Y79623D01*
G01X1161419Y41823D02*
X1161417D01*
G01Y36049D02*
Y41823D01*
G01X1178151Y59933D02*
X1178149D01*
G01X1164765D02*
X1164763D01*
G01Y67749D02*
Y59933D01*
G01X1171458D02*
X1171456D01*
G01Y67749D02*
Y59933D01*
G01X1158072D02*
X1158070D01*
G01X1181346Y46914D02*
X1181446D01*
X1181496Y46864D01*
Y41823D01*
G01X1168110Y36049D02*
Y41823D01*
G01X1174803Y35999D02*
Y41823D01*
G01X1187963Y46898D02*
Y46824D01*
X1188189Y46598D01*
Y41823D01*
G01X1177799Y90314D02*
Y90414D01*
X1178149Y90764D01*
Y97733D01*
G01X1164763Y90414D02*
Y97733D01*
G01X1171456Y90414D02*
Y97733D01*
G01X1161417Y84714D02*
Y79623D01*
G01X1187963Y73799D02*
X1188189Y74025D01*
Y79623D01*
G01X1193063Y92714D02*
X1194881Y94532D01*
Y97733D01*
G01X1204921Y46914D02*
Y41823D01*
G01X1218157Y46914D02*
X1218257D01*
X1218307Y46864D01*
Y41823D01*
G01X1218157Y84714D02*
X1218257D01*
X1218307Y84664D01*
Y79623D01*
G01X1204921Y84714D02*
Y79623D01*
G01X1208267Y90414D02*
Y97733D01*
G01X1161417Y41823D02*
Y46914D01*
G01X1198228Y41823D02*
Y36049D01*
G01X1181496Y41823D02*
Y36049D01*
G01X1188189Y41823D02*
Y36225D01*
X1187963Y35999D01*
G01X1174803Y41823D02*
Y46914D01*
G01X1168110Y41823D02*
Y46914D01*
G01X1171456Y59933D02*
Y52614D01*
G01X1164763Y59933D02*
Y52614D01*
G01X1178149Y59933D02*
Y67363D01*
X1177763Y67749D01*
G01X1174803Y79623D02*
Y73799D01*
G01X1168110Y79623D02*
Y84714D01*
G01X1194881Y59933D02*
Y56732D01*
X1193063Y54914D01*
G01X1183875Y55600D02*
Y52881D01*
X1184142Y52614D01*
G01X1198228Y79623D02*
Y84714D01*
G01X1181496Y79623D02*
Y84564D01*
X1181346Y84714D01*
G01X1188189Y79623D02*
Y84472D01*
X1187963Y84698D01*
G01X1161417Y79623D02*
Y73849D01*
G01X1211614Y41823D02*
Y46914D01*
G01X1218307Y41823D02*
Y36049D01*
G01X1204921Y41823D02*
Y36049D01*
G01X1208267Y59933D02*
Y52614D01*
G01X1201574Y59933D02*
Y52614D01*
G01X1211614Y79623D02*
Y84714D01*
G01X1204921Y79623D02*
Y73849D01*
G01X1201574Y97733D02*
Y90414D01*
G01X1218307Y79623D02*
Y73849D01*
G01X1178151Y97733D02*
X1178149D01*
G01X1164765D02*
X1164763D01*
G01X1158072D02*
X1158070D01*
G01X1171458D02*
X1171456D01*
G01X1198228Y104314D02*
X1201574Y100968D01*
Y97733D01*
G01X1201576D02*
X1201574D01*
G01X1194883D02*
X1194881D01*
G01X1208269D02*
X1208267D01*
G01X1194881D02*
Y103246D01*
X1193076Y105051D01*
G01X1184842Y97733D02*
Y102118D01*
X1187989Y105265D01*
G01X1171456Y97733D02*
Y101028D01*
X1174742Y104314D01*
G01X1164763Y97733D02*
Y101002D01*
X1168075Y104314D01*
G01X1178149Y97733D02*
Y101117D01*
X1181346Y104314D01*
G01X1208267Y97733D02*
Y100968D01*
X1204921Y104314D01*
G01X1214962Y523134D02*
X1214960Y523133D01*
Y516640D01*
X1215786Y515814D01*
X1220953D01*
G01X1181498Y505024D02*
X1181496D01*
Y510064D01*
X1181446Y510114D01*
X1181346D01*
G01X1201576Y523134D02*
X1201574Y523133D01*
Y515814D01*
G01X1198230Y505024D02*
X1198228D01*
Y510114D01*
G01X1204923Y505024D02*
X1204921D01*
Y510114D01*
G01X1188191Y505024D02*
X1188189D01*
Y509798D01*
X1187963Y510024D01*
Y510098D01*
G01X1184142Y515814D02*
X1183875Y516081D01*
Y518800D01*
G01X1218157Y510114D02*
X1218257D01*
X1218307Y510064D01*
Y505024D01*
X1218309D01*
G01X1211614Y510114D02*
Y505024D01*
X1211616D01*
G01X1208269Y523134D02*
X1208267Y523133D01*
Y515814D01*
G01X1194883Y523134D02*
X1194881Y523133D01*
Y519932D01*
X1193063Y518114D01*
G01X1174805Y505024D02*
X1174803D01*
Y510114D01*
G01X1168110D02*
Y505024D01*
X1168112D01*
G01X1171458Y523134D02*
X1171456Y523133D01*
Y515814D01*
G01X1164765Y523134D02*
X1164763Y523133D01*
Y515814D01*
G01X1161417Y510114D02*
Y505024D01*
X1161419D01*
G01X1178151Y523134D02*
X1178149Y523133D01*
Y516164D01*
X1177799Y515814D01*
Y515714D01*
G01X1214962Y560934D02*
X1214960Y560933D01*
Y554440D01*
X1215786Y553614D01*
X1220953D01*
G01X1181498Y580624D02*
X1181496D01*
Y585564D01*
X1181346Y585714D01*
G01X1194883Y560934D02*
X1194881Y560933D01*
Y557732D01*
X1193063Y555914D01*
G01X1218309Y580624D02*
X1218307D01*
Y585664D01*
X1218257Y585714D01*
X1218157D01*
G01X1211616Y580624D02*
X1211614D01*
Y585714D01*
G01X1187963Y585698D02*
Y585624D01*
X1188189Y585398D01*
Y580624D01*
X1188191D01*
G01X1204921Y585714D02*
Y580624D01*
X1204923D01*
G01X1198228Y585714D02*
Y580624D01*
X1198230D01*
G01X1181498Y542824D02*
X1181496D01*
Y547864D01*
X1181446Y547914D01*
X1181346D01*
G01X1204923Y542824D02*
X1204921D01*
Y547914D01*
G01X1188191Y542824D02*
X1188189D01*
Y547598D01*
X1187963Y547824D01*
Y547898D01*
G01X1184142Y553614D02*
X1183875Y553881D01*
Y556600D01*
G01X1211616Y542824D02*
X1211614D01*
Y547914D01*
G01X1218157D02*
X1218257D01*
X1218307Y547864D01*
Y542824D01*
X1218309D01*
G01X1208269Y560934D02*
X1208267Y560933D01*
Y553614D01*
G01X1198228Y547914D02*
Y542824D01*
X1198230D01*
G01X1201576Y560934D02*
X1201574Y560933D01*
Y553614D01*
G01X1174805Y580624D02*
X1174803D01*
Y585714D01*
G01X1161419Y580624D02*
X1161417D01*
Y585714D01*
G01X1168112Y580624D02*
X1168110D01*
Y585714D01*
G01X1161419Y542824D02*
X1161417D01*
Y547914D01*
G01X1168112Y542824D02*
X1168110D01*
Y547914D01*
G01X1171458Y560934D02*
X1171456Y560933D01*
Y553614D01*
G01X1164765Y560934D02*
X1164763Y560933D01*
Y553614D01*
G01X1174803Y547914D02*
Y542824D01*
X1174805D01*
G01X1178151Y560934D02*
X1178149Y560933D01*
Y553964D01*
X1177799Y553614D01*
Y553514D01*
G01X1208269Y598734D02*
X1208267Y598733D01*
Y591414D01*
G01X1184142D02*
X1183875Y591681D01*
Y594400D01*
G01X1194883Y598734D02*
X1194881Y598733D01*
Y595532D01*
X1193063Y593714D01*
G01X1201576Y598734D02*
X1201574Y598733D01*
Y591414D01*
G01X1178151Y598734D02*
X1178149Y598733D01*
Y591764D01*
X1177799Y591414D01*
Y591314D01*
G01X1171458Y598734D02*
X1171456Y598733D01*
Y591414D01*
G01X1220953D02*
X1215786D01*
X1214960Y592240D01*
Y598733D01*
X1214962Y598734D01*
G01X1164765D02*
Y591416D01*
X1164763Y591414D01*
G01X1245080Y22133D02*
X1245078D01*
G01X1231694D02*
X1231692D01*
G01X1238387D02*
X1238385D01*
G01X1220953Y30100D02*
X1221653Y29400D01*
Y22133D01*
G01X1225002Y4023D02*
X1225000D01*
Y8798D01*
X1224774Y9024D01*
Y9098D01*
G01X1235041Y4023D02*
X1235039D01*
Y9114D01*
G01X1248608Y32000D02*
Y28082D01*
X1248425Y27899D01*
G01X1251773Y22133D02*
X1251771D01*
Y16999D01*
G01X1241734Y4023D02*
X1241732D01*
Y9114D01*
G01X1269800Y-5822D02*
X1268922Y-6700D01*
X1266108D01*
G01X1248427Y4023D02*
X1248425D01*
Y9157D01*
G01X1251771Y-9901D02*
X1250500Y-8630D01*
Y-7592D01*
X1249608Y-6700D01*
G01X1248425Y36049D02*
X1248608Y35866D01*
Y32000D01*
G01X1267960Y28494D02*
Y30400D01*
G01X1245078Y14814D02*
Y22133D01*
G01X1229887Y27936D02*
X1231692Y26131D01*
Y22133D01*
G01X1238385Y29949D02*
Y22133D01*
G01X1220686Y17800D02*
Y15081D01*
X1220953Y14814D01*
G01X1238385Y22133D02*
Y14814D01*
G01X1231692Y22133D02*
Y18932D01*
X1229874Y17114D01*
G01X1245078Y22133D02*
Y29949D01*
G01X1241734Y41823D02*
X1241732D01*
G01X1241734Y79623D02*
X1241732D01*
G01X1235041Y41823D02*
X1235039D01*
G01X1225002D02*
X1225000D01*
G01X1225002Y79623D02*
X1225000D01*
G01X1229874Y92714D02*
X1231692Y94532D01*
Y97733D01*
X1231694D01*
G01X1235041Y79623D02*
X1235039D01*
G01Y84714D02*
Y79623D01*
G01X1238387Y97733D02*
X1238385D01*
Y90414D01*
G01X1238387Y59933D02*
X1238385D01*
G01Y67749D02*
Y59933D01*
G01X1220953Y67900D02*
X1221653Y67200D01*
Y59933D01*
G01X1231694D02*
X1231692D01*
G01X1229887Y65736D02*
X1231692Y63931D01*
Y59933D01*
G01X1248427Y79623D02*
X1248425D01*
G01Y84757D02*
Y79623D01*
G01X1251773Y97733D02*
X1251771D01*
Y92599D01*
G01X1245080Y97733D02*
X1245078D01*
Y90414D01*
G01X1248427Y41823D02*
X1248425D01*
G01Y46957D02*
Y41823D01*
G01X1245080Y59933D02*
X1245078D01*
G01Y52614D02*
Y59933D01*
G01X1248608Y70000D02*
X1248425Y69817D01*
Y65699D01*
G01X1220953Y90414D02*
X1220686Y90681D01*
Y93400D01*
G01X1248425Y73849D02*
X1248608Y73666D01*
Y70000D01*
G01X1266108D02*
X1267976Y71868D01*
Y73676D01*
G01X1241732Y36049D02*
Y41823D01*
G01X1235039Y46914D02*
Y41823D01*
G01X1224774Y46898D02*
Y46824D01*
X1225000Y46598D01*
Y41823D01*
G01X1241732Y84714D02*
Y79623D01*
G01X1224774Y84698D02*
Y84624D01*
X1225000Y84398D01*
Y79623D01*
G01X1248425Y41823D02*
Y36049D01*
G01X1225000Y41823D02*
Y36225D01*
X1224774Y35999D01*
G01X1235039Y41823D02*
Y36049D01*
G01X1241732Y41823D02*
Y46914D01*
G01X1245078Y59933D02*
Y67749D01*
G01X1248425Y79623D02*
Y73849D01*
G01X1231692Y59933D02*
Y56732D01*
X1229874Y54914D01*
G01X1220686Y55600D02*
Y52881D01*
X1220953Y52614D01*
G01X1238385Y59933D02*
Y52614D01*
G01X1235039Y79623D02*
Y73849D01*
G01X1225000Y79623D02*
Y74025D01*
X1224774Y73799D01*
G01X1241732Y79623D02*
Y73849D01*
G01X1277100Y122670D02*
X1274484Y120054D01*
X1265464D01*
X1263950Y121568D01*
Y124350D01*
X1264550Y124950D01*
Y125670D01*
G01X1275050Y125857D02*
Y124720D01*
X1277100Y122670D01*
G01X1225002Y505024D02*
X1225000D01*
Y509798D01*
X1224774Y510024D01*
Y510098D01*
G01X1235041Y505024D02*
X1235039D01*
Y510114D01*
G01X1231694Y523134D02*
X1231692Y523133D01*
Y519932D01*
X1229874Y518114D01*
G01X1238387Y523134D02*
X1238385Y523133D01*
Y515814D01*
G01X1241732Y510114D02*
Y505024D01*
X1241734D01*
G01X1248427D02*
X1248425D01*
Y510157D01*
G01X1245080Y523134D02*
X1245078Y523133D01*
Y515814D01*
G01X1251773Y523134D02*
X1251771Y523133D01*
Y517999D01*
G01X1220953Y515814D02*
X1220686Y516081D01*
Y518800D01*
G01X1231694Y560934D02*
X1231692Y560933D01*
Y557732D01*
X1229874Y555914D01*
G01X1224774Y585698D02*
Y585624D01*
X1225000Y585398D01*
Y580624D01*
X1225002D01*
G01X1235041D02*
X1235039D01*
Y585714D01*
G01X1225002Y542824D02*
X1225000D01*
Y547598D01*
X1224774Y547824D01*
Y547898D01*
G01X1235039Y547914D02*
Y542824D01*
X1235041D01*
G01X1238387Y560934D02*
X1238385Y560933D01*
Y553614D01*
G01X1241732Y585714D02*
Y580624D01*
X1241734D01*
G01Y542824D02*
X1241732D01*
Y547914D01*
G01X1248608Y533000D02*
X1248425Y532817D01*
Y528899D01*
G01X1248427Y542824D02*
X1248425D01*
Y547957D01*
G01X1245080Y560934D02*
X1245078Y560933D01*
Y553614D01*
G01X1269800Y532978D02*
X1266130D01*
X1266108Y533000D01*
G01X1248425Y585757D02*
Y580624D01*
X1248427D01*
G01X1220953Y553614D02*
X1220686Y553881D01*
Y556600D01*
G01Y594400D02*
Y591681D01*
X1220953Y591414D01*
G01X1231694Y598734D02*
X1231692Y598733D01*
Y595532D01*
X1229874Y593714D01*
G01X1238387Y598734D02*
X1238385Y598733D01*
Y591414D01*
G01X1245080Y598734D02*
X1245078Y598733D01*
Y591414D01*
G01X1251773Y598734D02*
X1251771Y598733D01*
Y593599D01*
G01X1263800Y606800D02*
X1266500Y609500D01*
G01X1248374Y609456D02*
X1248425Y609507D01*
Y612649D01*
G01X1322430Y337460D02*
X1320471D01*
X1319906Y338025D01*
G01X1327400Y337430D02*
Y340209D01*
X1326300Y341309D01*
G01X1300315Y427902D02*
X1292870Y435347D01*
Y440314D01*
X1294645Y442089D01*
Y483855D01*
X1293000Y485500D01*
G01X1313640Y421291D02*
X1312691Y422240D01*
X1305977D01*
X1300315Y427902D01*
G01X1309870Y499254D02*
X1295404D01*
X1284850Y488700D01*
G01X1367089Y2676D02*
X1366789Y2976D01*
Y5776D01*
G01X1375212Y967D02*
X1373503Y2676D01*
X1370589D01*
G01D02*
Y4276D01*
X1369389Y5476D01*
Y5776D01*
G01X1369700Y37800D02*
Y39610D01*
X1371123Y41033D01*
G01X1369407Y396668D02*
Y399258D01*
X1369257Y399408D01*
G01X1369707Y393568D02*
X1369407Y393868D01*
Y396668D01*
G01X1373207Y393568D02*
Y394792D01*
X1372007Y395992D01*
Y396668D01*
G01X1371400Y581556D02*
X1371100Y581856D01*
Y584656D01*
G01X1371010Y587276D02*
Y584746D01*
X1371100Y584656D01*
G01X1374900Y581556D02*
Y582800D01*
X1373700Y584000D01*
Y584656D01*
G01X1367400Y616400D02*
X1368044Y615756D01*
X1371100D01*
G01D02*
Y615000D01*
X1370600Y614500D01*
Y613100D01*
G01X1373838Y616161D02*
Y615618D01*
X1374100Y615356D01*
Y613100D01*
G01D02*
X1374220Y612980D01*
X1378930D01*
G01X1432560Y541455D02*
Y544955D01*
G01X1441252Y548631D02*
Y549148D01*
X1439205Y551195D01*
X1436495D01*
X1432560Y547260D01*
Y544955D01*
G01X1469200Y610739D02*
X1467501D01*
X1465950Y612290D01*
G01X1526500Y506400D02*
X1524470D01*
X1522870Y504800D01*
Y503200D01*
G01X1474300Y615500D02*
Y613800D01*
X1475812Y612288D01*
Y611732D01*
G01X1508600Y616416D02*
Y615200D01*
X1510800Y613000D01*
X1511350D01*
G01X1466610Y607879D02*
X1469100D01*
X1469109Y607870D01*
X1469221D01*
X1469301Y607790D01*
G01D02*
X1469650Y608139D01*
X1472000D01*
X1472300Y608439D01*
G01X1504631Y605406D02*
X1504700Y605475D01*
Y608500D01*
G01D02*
X1507707D01*
X1507768Y608439D01*
X1507952D01*
G01X1504700Y611100D02*
X1505685D01*
X1506524Y611939D01*
X1507952D01*
G01X1472300D02*
X1471056D01*
X1469856Y610739D01*
X1469200D01*
G01X1547975Y457066D02*
X1546972Y456063D01*
Y453999D01*
G01X1549925Y446926D02*
X1548413Y448438D01*
X1547269D01*
G01X1543472Y453999D02*
Y451778D01*
X1543850Y451400D01*
G01X1584500Y586600D02*
X1582408D01*
X1581704Y585896D01*
G01X1611900Y55500D02*
X1609400D01*
X1609144Y55244D01*
G01X1660040Y22960D02*
X1658750Y24250D01*
Y25941D01*
G01X1709183Y588700D02*
Y584727D01*
G01X1709950Y592900D02*
X1711500Y591350D01*
Y582327D01*
X1709900Y580727D01*
X1709183D01*
G01X1707000Y600000D02*
X1710000D01*
G01X1707000Y604500D02*
X1710000D01*
G01X1707000Y595500D02*
X1710000D01*
G01X1772903Y112412D02*
Y111553D01*
X1770850Y109500D01*
G01X1751800Y141700D02*
X1752250Y141250D01*
X1755658D01*
G01X1752889Y146250D02*
X1753357Y145782D01*
X1755642D01*
X1755658Y145798D01*
G01Y127750D02*
Y125719D01*
X1754189Y124250D01*
G01X1752389Y132250D02*
X1755658D01*
G01X1752189Y136750D02*
X1755658D01*
G01X1751779Y151165D02*
X1754674D01*
X1755089Y150750D01*
G01X1772903Y112412D02*
X1777311D01*
X1778668Y113769D01*
X1780623D01*
G01X1812552Y523001D02*
Y522201D01*
X1814852Y519901D01*
G01D02*
X1817552Y522601D01*
Y523001D01*
G01X1828800Y575600D02*
X1828200D01*
X1827800Y576000D01*
X1822000D01*
G01X1828700Y569474D02*
X1828635Y569409D01*
X1827882D01*
X1827474Y569001D01*
X1825552D01*
G01X1833052Y575501D02*
X1835809D01*
X1837475Y573835D01*
G01X1813456Y583500D02*
X1815655Y581301D01*
X1816052D01*
G01X1822052Y569001D02*
X1817507D01*
X1816175Y567669D01*
G01X1838224Y586650D02*
X1837575Y586001D01*
X1833052D01*
G01X1811500Y603500D02*
X1812000Y604000D01*
Y606000D01*
G01X1933898Y216707D02*
X1933915D01*
Y216724D01*
X1933758D01*
Y216957D01*
X1932879Y217836D01*
Y221053D01*
X1932779Y221153D01*
G01X1915031Y208449D02*
Y208189D01*
G54D43*
X44100Y507100D03*
X1468500Y176700D03*
X1596130Y205480D03*
X1623800Y169500D03*
X1666300Y85000D03*
X1742200Y87950D03*
X1755708Y132250D03*
Y127750D03*
Y141250D03*
Y136750D03*
X1764270Y132250D03*
Y127750D03*
Y141250D03*
Y136750D03*
X1755708Y145798D03*
X1764222D03*
X1721900Y198700D03*
X1888500Y225100D03*
G54D190*
X1813505Y600103D03*
X1807599D03*
G54D181*
X1752480Y557738D03*
X1754448D03*
X1756417D03*
X1758386D03*
X1760354D03*
X1806115Y529899D03*
X1810052D03*
X1808083D03*
X1812021D03*
X1813989D03*
G54D163*
X1613069Y302692D03*
G54D154*
X1651250Y31059D03*
Y28500D03*
Y25941D03*
X1658750D03*
Y31059D03*
Y28500D03*
G54D61*
X94900Y332800D03*
X103900D03*
X94010Y343470D03*
X103010D03*
X1496800Y324500D03*
Y327060D03*
X1504200Y324500D03*
Y327060D03*
Y321940D03*
X1496800D03*
X1554500Y109940D03*
X1561900D03*
X1554500Y107380D03*
X1561900D03*
X1554500Y112500D03*
X1561900D03*
X1647500Y16500D03*
X1611900Y55500D03*
X1619300D03*
X1611900Y52940D03*
X1619300D03*
X1611900Y58060D03*
X1619300D03*
X1656500Y16500D03*
X1768628Y62395D03*
X1777628D03*
G54D25*
X15050Y30424D03*
X22050D03*
X22437Y66673D03*
X15437D03*
X22328Y73174D03*
X15328D03*
X22328Y79674D03*
X15328D03*
X15050Y37654D03*
X22050D03*
X15060Y44854D03*
X22060D03*
X4300Y242800D03*
X11300D03*
X-11190Y454200D03*
X-4190D03*
X12300Y584000D03*
X5300D03*
X12300Y577500D03*
X5300D03*
X12300Y555500D03*
X5300D03*
X12300Y549000D03*
X5300D03*
X12300Y542500D03*
X5300D03*
X12300Y590500D03*
X5300D03*
X103600Y31978D03*
Y-8400D03*
Y69778D03*
X61000Y216102D03*
X54000D03*
X110600Y31978D03*
Y-8400D03*
Y69778D03*
X136263Y261516D03*
X129263D03*
X136263Y268116D03*
X129263D03*
X136263Y255016D03*
X129263D03*
X136263Y229516D03*
X129263D03*
X136263Y236116D03*
X129263D03*
X136263Y223016D03*
X129263D03*
X136263Y287016D03*
X129263D03*
X136263Y293516D03*
X129263D03*
X136263Y300116D03*
X129263D03*
X136263Y332116D03*
X129263D03*
X136263Y325516D03*
X129263D03*
X136263Y319016D03*
X129263D03*
X136263Y364116D03*
X129263D03*
X136263Y357516D03*
X129263D03*
X136263Y351016D03*
X129263D03*
X136263Y396116D03*
X129263D03*
X136263Y383016D03*
X129263D03*
X136263Y389516D03*
X129263D03*
X378292Y13078D03*
X371292D03*
X379692Y31978D03*
X372692D03*
X408892Y-15000D03*
X401892D03*
X415892D03*
X372592Y-5810D03*
X379592D03*
X378892Y69100D03*
X371892D03*
X378312Y51178D03*
X371312D03*
X375492Y106500D03*
X382492D03*
X384448Y272041D03*
X391448D03*
X389956Y329710D03*
X382956D03*
X378120Y551360D03*
X371120D03*
X378262Y532978D03*
X371262D03*
X377340Y589650D03*
X370340D03*
X378232Y570818D03*
X371232D03*
X413324Y617756D03*
X399824D03*
X406824D03*
X379760Y618220D03*
X372760D03*
X360706Y618127D03*
X367706D03*
X436392Y-15000D03*
X429392D03*
X422892D03*
X446392Y107500D03*
X439392D03*
X440148Y274841D03*
X447148D03*
X448250Y496390D03*
X441250D03*
X427324Y617756D03*
X434324D03*
X420324D03*
X664500Y60000D03*
X657500D03*
X664500Y52000D03*
X657500D03*
X725230Y-10380D03*
X718230D03*
X721130Y42955D03*
X696000Y203000D03*
X703000D03*
X696000Y216500D03*
X703000D03*
X696000Y209500D03*
X703000D03*
X688700Y313000D03*
X695700D03*
X721900Y529700D03*
X753208Y31978D03*
X760208D03*
X753208Y-8400D03*
X760208D03*
X753208Y69778D03*
X760208D03*
X728130Y42955D03*
X785932Y261133D03*
X778932D03*
X785932Y254633D03*
X778932D03*
X785932Y236533D03*
X778932D03*
X785932Y230033D03*
X778932D03*
X786000Y223300D03*
X779000D03*
X785932Y267633D03*
X778932D03*
X785932Y299833D03*
X778932D03*
X785932Y286833D03*
X778932D03*
X785932Y293333D03*
X778932D03*
X785932Y319653D03*
X778932D03*
X785932Y326153D03*
X778932D03*
X786332Y332653D03*
X779332D03*
X786000Y383000D03*
X779000D03*
X785932Y357633D03*
X778932D03*
X785932Y364133D03*
X778932D03*
X785932Y351133D03*
X778932D03*
X786000Y389500D03*
X779000D03*
X786000Y396000D03*
X779000D03*
X728900Y529700D03*
X1029300Y31978D03*
X1022300D03*
X1029400Y13078D03*
X1022400D03*
X1023621Y-15762D03*
X1030621D03*
X1028600Y51400D03*
X1021600D03*
X1029300Y69100D03*
X1022300D03*
X1031200Y104500D03*
X1034056Y272041D03*
X1032564Y329710D03*
X1028800Y532978D03*
X1021800D03*
X1028900Y551500D03*
X1021900D03*
X1028300Y570778D03*
X1021300D03*
X1027070Y589650D03*
X1020070D03*
X1030700Y618200D03*
X1023700D03*
X1011234Y618177D03*
X1018234D03*
X1058500Y-15000D03*
X1051500D03*
X1072500D03*
X1065500D03*
X1086000D03*
X1079000D03*
X1096000Y105781D03*
X1089000D03*
X1038200Y104500D03*
X1089756Y274841D03*
X1096756D03*
X1041056Y272041D03*
X1039564Y329710D03*
X1041800Y496200D03*
X1048800D03*
X1095532Y617956D03*
X1088532D03*
X1068032D03*
X1061032D03*
X1081532D03*
X1074532D03*
X1320700Y111450D03*
X1313700D03*
X1320700Y119450D03*
X1313700D03*
X1360989Y-4107D03*
X1367989D03*
X1360989Y-10607D03*
X1367989D03*
X1360989Y-17207D03*
X1367989D03*
X1361400Y15200D03*
X1368400D03*
X1361400Y21700D03*
X1368400D03*
X1361400Y28200D03*
X1368400D03*
X1390531Y90354D03*
X1383531D03*
X1390531Y104354D03*
X1383531D03*
X1363700Y373500D03*
X1370700D03*
X1363800Y380200D03*
X1370800D03*
X1363700Y386700D03*
X1370700D03*
X1365500Y576156D03*
X1372500D03*
X1365500Y569156D03*
X1372500D03*
X1365500Y562656D03*
X1372500D03*
X1365400Y605800D03*
X1372400D03*
X1365100Y598576D03*
X1372100D03*
X1365100Y592076D03*
X1372100D03*
X1585270Y558204D03*
Y565204D03*
X1635876Y190731D03*
X1628876D03*
X1592270Y558204D03*
Y565204D03*
X1770600Y46800D03*
X1766600Y37800D03*
X1774600D03*
X1837000Y48500D03*
X1830000D03*
X1817772Y47218D03*
X1824772D03*
X1829800Y492500D03*
X1836800D03*
X1829800Y486000D03*
X1836800D03*
X1928000Y440730D03*
X1921000D03*
X1908000D03*
X1915000D03*
G36*
G01X1956463Y209274D02*
G02X1954500Y205493I-1963J-1381D01*
G01X1950000D01*
G02X1947600Y207893I0J2400D01*
G01Y210293D01*
G02X1952400I2400J0D01*
G01X1954500D01*
G02X1954986Y210243I-1J-2400D01*
G03X1956463Y209274I1904J1292D01*
G37*
G54D70*
X64500Y359300D03*
X68000D03*
X667500Y257800D03*
X1504631Y605456D03*
X1466610Y607929D03*
G54D145*
X1523200Y432600D03*
X1518300D03*
G54D109*
X1250110Y336170D03*
G54D136*
X1453327Y306678D03*
X1456477D03*
X1491925Y270500D03*
X1495075D03*
X1515050Y403500D03*
X1518200D03*
X1513925Y415175D03*
X1517075D03*
X1503925Y427100D03*
X1507075D03*
X1507625Y437225D03*
X1510775D03*
X1530350Y411300D03*
X1533500D03*
X1544225Y433200D03*
X1547375D03*
G54D172*
X1681717Y116349D03*
G54D34*
X12290Y264640D03*
X18450Y267010D03*
X22970Y244400D03*
X28720Y244450D03*
X17120Y244220D03*
X24200Y267060D03*
G54D127*
X1462000Y-5000D03*
Y-15000D03*
X1452000Y-5000D03*
Y-15000D03*
X1442000Y-5000D03*
X1525000Y-15000D03*
X1515000D03*
X1482000D03*
X1472000Y-5000D03*
Y-15000D03*
X1492000Y-5000D03*
Y-15000D03*
X1482000Y-5000D03*
X1575000Y-15000D03*
X1565000D03*
X1555000D03*
X1545000D03*
X1535000D03*
X1713503Y-5000D03*
Y-15000D03*
X1703503Y-5000D03*
X1743503Y-15000D03*
X1733503Y-5000D03*
Y-15000D03*
X1723503Y-5000D03*
Y-15000D03*
X1753503Y-5000D03*
Y-15000D03*
X1743503Y-5000D03*
X1769504D03*
X1809504Y-15000D03*
X1799504Y-5000D03*
Y-15000D03*
X1789504Y-5000D03*
Y-15000D03*
X1779504Y-5000D03*
Y-15000D03*
X1819504Y-5000D03*
Y-15000D03*
X1809504Y-5000D03*
G54D217*
X1952756Y589960D03*
X1944882Y582086D03*
X1952756D03*
X1944882Y574212D03*
X1952756D03*
X1944882Y566338D03*
X1952756D03*
X1944882Y558464D03*
Y589960D03*
Y605708D03*
X1952756D03*
X1944882Y597834D03*
X1952756D03*
G54D16*
X-15354Y109095D03*
Y124843D03*
Y140591D03*
Y156339D03*
Y365236D03*
Y380984D03*
Y396732D03*
Y412480D03*
X22835Y101221D03*
X6299D03*
X-10236D03*
X17716Y109095D03*
X1181D03*
X22835Y116969D03*
X6299D03*
X1181Y124843D03*
X22835Y132717D03*
X1181Y140591D03*
X22835Y148465D03*
X6299D03*
X-10236D03*
X17716Y156339D03*
X1181D03*
X-10236Y116969D03*
X-4725D03*
X23228Y124843D03*
X17716D03*
X-10236Y132717D03*
X-4725D03*
X6299D03*
X11811D03*
X17716Y140591D03*
X23228D03*
X-9843Y156339D03*
X23228Y109095D03*
X6693D03*
Y124843D03*
X-9843Y109095D03*
Y124843D03*
X-4725Y101221D03*
X11811Y148465D03*
Y101221D03*
Y116969D03*
X28346Y101221D03*
Y116969D03*
Y132717D03*
X6693Y140591D03*
X-9843D03*
X28346Y148465D03*
X6693Y156339D03*
X-4725Y148465D03*
X23228Y156339D03*
X22835Y357362D03*
X6299D03*
X-10236D03*
X17716Y365236D03*
X1181D03*
X22835Y373110D03*
X6299D03*
X1181Y380984D03*
X22835Y388858D03*
X1181Y396732D03*
X22835Y404606D03*
X6299D03*
X-10236D03*
Y373110D03*
X-4725D03*
X23228Y380984D03*
X17716D03*
X-10236Y388858D03*
X-4725D03*
X6299D03*
X11811D03*
X17716Y396732D03*
X23228D03*
Y365236D03*
X6693D03*
Y380984D03*
X-9843Y365236D03*
Y380984D03*
X-4725Y357362D03*
X11811Y404606D03*
Y357362D03*
Y373110D03*
X28346Y357362D03*
Y373110D03*
Y388858D03*
X6693Y396732D03*
X-9843D03*
X28346Y404606D03*
X-4725D03*
X17716Y412480D03*
X1181D03*
X-9843D03*
X6693D03*
X23228D03*
G54D118*
X1392264Y23976D03*
X1513918D03*
G54D52*
X57069Y147990D03*
X62560Y148940D03*
X69500Y388050D03*
X66809Y416405D03*
X60279Y415455D03*
X134000Y461350D03*
X139300Y453450D03*
X139776Y437704D03*
X121800Y462300D03*
X126700Y454400D03*
X130000Y446600D03*
X132100Y438654D03*
X427158Y122970D03*
X576115Y265575D03*
X1349730Y344550D03*
X1425443Y189960D03*
X1443930Y309840D03*
X1442169Y450250D03*
X1442646Y440250D03*
X1458100Y439300D03*
X1435500Y462230D03*
X1448000Y463180D03*
X1466800Y156800D03*
X1525567Y241237D03*
X1470768Y446550D03*
X1484200Y492420D03*
X1474488Y493370D03*
X1479303Y495800D03*
X1471829Y498585D03*
X1479300Y501438D03*
X1487200Y502388D03*
X1475483Y488050D03*
X1586771Y500628D03*
X1576075Y499693D03*
X1587815Y493308D03*
X1598477Y118900D03*
X1604603Y140607D03*
X1602600Y135856D03*
X1595851Y499678D03*
X1670733Y140300D03*
X1677740Y152650D03*
X1673132Y154625D03*
X1706296Y158650D03*
X1747300Y141050D03*
X1747654Y155850D03*
X1740779Y133050D03*
X1741419Y157650D03*
X1775900Y588400D03*
X1901671Y542000D03*
X1908295Y541050D03*
X1915085Y540100D03*
G54D236*
G01X1626250Y106064D02*
X1627913Y107727D01*
Y119488D01*
X1626364Y121037D01*
Y121765D01*
G01X1626250Y106064D02*
X1624700Y107614D01*
Y117924D01*
X1624763Y117987D01*
Y120164D01*
X1626364Y121765D01*
G54D227*
G01X394682Y68492D02*
X394683Y68491D01*
Y59933D01*
G01X654600Y296000D02*
X650856Y292256D01*
G01X899500Y364500D02*
X909134D01*
X914437Y359197D01*
X916789D01*
G01X918520Y348300D02*
X918130Y347910D01*
X916590D01*
X916293Y348207D01*
G01X916789Y357293D02*
X912757D01*
X908550Y361500D01*
X903600D01*
G01D02*
X899500D01*
G01X1346800Y340800D02*
X1349000D01*
X1349700Y341500D01*
G01X1376027Y352778D02*
Y350346D01*
X1375493Y349812D01*
X1373950D01*
G01X1354650Y346662D02*
X1351984D01*
X1350846Y347800D01*
X1349700D01*
G01X1354650Y343513D02*
X1351713D01*
X1349700Y341500D01*
G01X1349730Y344550D02*
X1351670D01*
X1352207Y345087D01*
X1354650D01*
G01X1346800Y344300D02*
X1347860D01*
X1348110Y344550D01*
X1349730D01*
G01X1457000Y104750D02*
Y108500D01*
G01X1444614Y482523D02*
X1442243D01*
X1441842Y482924D01*
G01X1442141Y477623D02*
X1442641Y478123D01*
X1444614D01*
G01X1487000Y73500D02*
X1490571D01*
X1490821Y73750D01*
G01X1487000Y73500D02*
X1483500D01*
X1483000Y74000D01*
Y77000D01*
X1482500Y77500D01*
G01X1487000Y83500D02*
X1488404D01*
X1490057Y85153D01*
Y85165D01*
G01X1487000Y83500D02*
X1482500D01*
G01X1544300Y243200D02*
Y245602D01*
X1542984Y246918D01*
X1542030D01*
X1541210Y247738D01*
Y250300D01*
X1539595Y251915D01*
X1538456D01*
X1537938Y252433D01*
Y253033D01*
X1537258Y253713D01*
X1536150D01*
G01X1534833Y309798D02*
X1535598D01*
X1540359Y305037D01*
X1551003D01*
X1559805Y296235D01*
Y295825D01*
X1561519Y294111D01*
X1565459D01*
X1570816Y288754D01*
X1573056D01*
X1575066Y286744D01*
X1619675D01*
X1629017Y296086D01*
Y320816D01*
X1636391Y328190D01*
X1637299D01*
X1637346Y328237D01*
X1637347D01*
X1653263Y344153D01*
Y344154D01*
X1655903Y346794D01*
Y368946D01*
X1653396Y371453D01*
Y390402D01*
G01X1849000Y496000D02*
X1846925Y493925D01*
Y490784D01*
X1845262Y489121D01*
Y484880D01*
X1847962Y482180D01*
Y457235D01*
X1849761Y455436D01*
Y452753D01*
X1848395Y451387D01*
X1844841D01*
X1838767Y445313D01*
X1736921D01*
X1731550Y450684D01*
Y472475D01*
X1725288Y478737D01*
X1674115D01*
X1656511Y461133D01*
Y395887D01*
X1653396Y392772D01*
Y390402D01*
G01X1757383Y63002D02*
X1759932D01*
X1763300Y66370D01*
Y68300D01*
G01X1763400Y71300D02*
Y69992D01*
X1763300Y69892D01*
Y68300D01*
G01X1763250Y75940D02*
Y73994D01*
X1763400Y73844D01*
Y71300D01*
G01X1773750Y89500D02*
X1780700D01*
G01X1773750Y99500D02*
X1780700D01*
G01X1765000Y102000D02*
X1771700D01*
X1773750Y99950D01*
Y99500D01*
G01Y94500D02*
X1780700D01*
G01X1821250D02*
X1819221D01*
X1817767Y95954D01*
Y101100D01*
G01X1869914Y517225D02*
X1868670Y518469D01*
Y519656D01*
X1865101Y523225D01*
Y526122D01*
X1861706Y529517D01*
X1857954D01*
X1857384Y530087D01*
Y533922D01*
X1855598Y535708D01*
X1855561D01*
X1855509Y535760D01*
X1845733D01*
X1842170Y539323D01*
Y544664D01*
X1842730Y545224D01*
G01X1845341Y534860D02*
X1845217D01*
X1840550Y539527D01*
Y545839D01*
X1843521Y548810D01*
X1844820D01*
X1845900Y549890D01*
Y554575D01*
X1849006Y557681D01*
X1853779D01*
X1854400Y558302D01*
Y560835D01*
X1858149Y564584D01*
X1860075D01*
X1860999Y565508D01*
X1864804D01*
G01X1878272Y522965D02*
X1876806D01*
X1875871Y522030D01*
X1871334D01*
X1869290Y524074D01*
Y527560D01*
G01X1881293Y522986D02*
X1879538Y524741D01*
X1876932D01*
X1875392Y523201D01*
X1872424D01*
X1871850Y523775D01*
Y527560D01*
G01X1852190Y537760D02*
X1855750Y541320D01*
Y542500D01*
G01X1874704Y572718D02*
Y569641D01*
X1871548Y566485D01*
Y562248D01*
X1871900Y561896D01*
Y560404D01*
X1870846Y559350D01*
X1869354D01*
X1868316Y560388D01*
X1864804D01*
G01X1877704Y572718D02*
X1874704D01*
G01X1894654Y569968D02*
Y568468D01*
X1896154Y566968D01*
G01X1892554Y565000D02*
X1891308D01*
X1890800Y565508D01*
X1887004D01*
G01X1892554Y565000D02*
X1893400D01*
X1894000Y565600D01*
X1894786D01*
X1896154Y566968D01*
G01Y563968D02*
Y560968D01*
G01X1887004Y562948D02*
X1890952D01*
X1891600Y562300D01*
X1893100D01*
X1894768Y563968D01*
X1896154D01*
G01X1887004Y568068D02*
X1883137D01*
X1880704Y570501D01*
Y572718D01*
G01X1864804Y562948D02*
X1860799D01*
X1860149Y563598D01*
X1858666D01*
X1855400Y560332D01*
Y557955D01*
X1854126Y556681D01*
X1849279D01*
X1846900Y554302D01*
Y549394D01*
X1842730Y545224D01*
G01X1869935Y563612D02*
X1869271Y562948D01*
X1864804D01*
G01X1868442Y565778D02*
X1868172Y565508D01*
X1864804D01*
G01X1869310Y533140D02*
Y527580D01*
X1869290Y527560D01*
G01X1869310Y533140D02*
Y534790D01*
X1871420Y536900D01*
X1891475D01*
X1896325Y532050D01*
X1918365D01*
X1920900Y529515D01*
Y527600D01*
X1923085Y525415D01*
X1924217D01*
G01X1916343D02*
X1917567D01*
X1919621Y527469D01*
Y529379D01*
X1917850Y531150D01*
X1895810D01*
X1891182Y535778D01*
X1872722D01*
G01X1947686Y187022D02*
X1946923Y187785D01*
X1942556D01*
X1941487Y188854D01*
G01X1947686Y187022D02*
X1950939D01*
X1951341Y187424D01*
G01X1936369Y190204D02*
Y191469D01*
X1939200Y194300D01*
G01X1947646Y181828D02*
X1947200Y182274D01*
Y183797D01*
X1945037Y185960D01*
X1938180D01*
X1937770Y185800D01*
X1937370D01*
X1936369Y184799D01*
Y183204D01*
G01X1951318Y181882D02*
X1949579D01*
X1949420Y181723D01*
X1947751D01*
X1947646Y181828D01*
G01X1947686Y193522D02*
X1957834D01*
X1958593Y194281D01*
X1964095D01*
X1966383Y191993D01*
Y187983D01*
X1964509Y186109D01*
X1962551D01*
G01X1955081Y175040D02*
X1957400Y177359D01*
Y187300D01*
X1958178Y188078D01*
X1960252D01*
G01Y186109D02*
X1962551D01*
G01X1963300Y191000D02*
Y190500D01*
X1962551Y189751D01*
Y188078D01*
G01D02*
X1960252D01*
G54D164*
X1595943Y441200D03*
Y447800D03*
G54D119*
X1373950Y337213D03*
Y338788D03*
Y340363D03*
Y341938D03*
Y343513D03*
Y345087D03*
Y346662D03*
Y348237D03*
Y349812D03*
Y351387D03*
G54D209*
X1915031Y208449D03*
X1922431D03*
G54D44*
X40200Y495721D03*
Y487879D03*
X36458D03*
X43942D03*
Y495721D03*
X36458D03*
G54D62*
X84781Y327900D03*
X86750Y332500D03*
X82813Y327900D03*
Y332500D03*
X84781D03*
X100431Y312900D03*
X102400Y317500D03*
X98463Y312900D03*
Y317500D03*
X100431D03*
X1613999Y23700D03*
X1615968Y28300D03*
X1612031Y23700D03*
Y28300D03*
X1613999D03*
G54D71*
X57745Y483757D03*
Y490757D03*
X412501Y275410D03*
Y268410D03*
X398048Y275441D03*
Y268441D03*
X405301Y275410D03*
Y268410D03*
X411001Y327910D03*
Y334910D03*
X418201Y327910D03*
Y334910D03*
X413001Y320410D03*
Y313410D03*
X377648Y315841D03*
Y322841D03*
X396348Y327941D03*
Y334941D03*
X403748Y327941D03*
Y334941D03*
X391401Y320410D03*
Y313410D03*
X384201Y320410D03*
Y313410D03*
X398601Y320410D03*
Y313410D03*
X405801Y320410D03*
Y313410D03*
X411501Y299410D03*
Y306410D03*
Y282410D03*
Y289410D03*
X382701Y282410D03*
Y289410D03*
X375501Y282410D03*
Y289410D03*
X368301Y282410D03*
Y289410D03*
X382701Y299410D03*
Y306410D03*
X389901Y282410D03*
Y289410D03*
Y299410D03*
Y306410D03*
X375501Y299410D03*
Y306410D03*
X368301Y299410D03*
Y306410D03*
X404301Y299410D03*
Y306410D03*
Y282410D03*
Y289410D03*
X397101Y299410D03*
Y306410D03*
Y282410D03*
Y289410D03*
X371148Y315841D03*
Y322841D03*
X434101Y275410D03*
Y268410D03*
X419701Y275410D03*
Y268410D03*
X426901Y275410D03*
Y268410D03*
X425401Y327910D03*
Y334910D03*
X432601Y327910D03*
Y334910D03*
X455648Y322341D03*
Y315341D03*
X420201Y320410D03*
Y313410D03*
X441801Y320291D03*
Y313291D03*
X434601Y320410D03*
Y313410D03*
X449001Y320410D03*
Y313410D03*
X427401Y320410D03*
Y313410D03*
X447648Y289341D03*
Y282341D03*
X425901Y299410D03*
Y306410D03*
Y282410D03*
Y289410D03*
X418701Y299410D03*
Y306410D03*
Y282410D03*
Y289410D03*
X440301Y299410D03*
Y306410D03*
X433101Y299410D03*
Y306410D03*
X447648Y299341D03*
Y306341D03*
X440301Y282410D03*
Y289410D03*
X433101Y282410D03*
Y289410D03*
X440194Y332291D03*
Y325291D03*
X655550Y7490D03*
Y14490D03*
X656170Y574690D03*
Y581690D03*
X721500Y60500D03*
Y53500D03*
X721900Y544100D03*
Y537100D03*
X1027256Y315841D03*
Y322841D03*
X1020756Y315841D03*
Y322841D03*
X1033809Y320410D03*
Y313410D03*
X1017909Y299410D03*
Y306410D03*
Y282410D03*
Y289410D03*
X1025109Y299410D03*
Y306410D03*
Y282410D03*
Y289410D03*
X1032309Y299410D03*
Y306410D03*
Y282410D03*
Y289410D03*
X1083709Y275410D03*
Y268410D03*
X1076509Y275410D03*
Y268410D03*
X1069309Y275410D03*
Y268410D03*
X1062109Y275410D03*
Y268410D03*
X1054909Y275410D03*
Y268410D03*
X1047656Y275441D03*
Y268441D03*
X1082209Y327910D03*
Y334910D03*
X1077009Y320410D03*
Y313410D03*
X1084209Y320410D03*
Y313410D03*
X1091409Y320410D03*
Y313410D03*
X1082709Y282410D03*
Y289410D03*
X1097256Y299341D03*
Y306341D03*
Y289341D03*
Y282341D03*
X1082709Y299410D03*
Y306410D03*
X1089909Y299410D03*
Y306410D03*
Y282410D03*
Y289410D03*
X1075009Y327910D03*
Y334910D03*
X1069809Y320410D03*
Y313410D03*
X1062609Y320410D03*
Y313410D03*
X1055409Y320410D03*
Y313410D03*
X1048209Y320410D03*
Y313410D03*
X1041009Y320410D03*
Y313410D03*
X1067809Y327910D03*
Y334910D03*
X1060609Y327910D03*
Y334910D03*
X1053356Y327941D03*
Y334941D03*
X1045956Y327941D03*
Y334941D03*
X1075509Y299410D03*
Y306410D03*
Y282410D03*
Y289410D03*
X1068309Y299410D03*
Y306410D03*
Y282410D03*
Y289410D03*
X1039509Y282410D03*
Y289410D03*
X1061109Y299410D03*
Y306410D03*
X1053909Y299410D03*
Y306410D03*
X1061109Y282410D03*
Y289410D03*
X1053909Y282410D03*
Y289410D03*
X1046709Y299410D03*
Y306410D03*
Y282410D03*
Y289410D03*
X1039509Y299410D03*
Y306410D03*
X1088900Y332800D03*
Y325800D03*
X1105256Y322341D03*
Y315341D03*
X1098609Y320410D03*
Y313410D03*
X1382000Y119500D03*
Y112500D03*
X1384500Y524500D03*
X1376500D03*
X1365413Y524149D03*
X1384500Y531500D03*
X1376500D03*
X1365413Y531149D03*
X1521668Y602139D03*
Y609139D03*
X1528168Y602139D03*
Y609139D03*
X1514668Y602139D03*
Y609139D03*
X1480200Y601099D03*
Y608099D03*
X1487200Y601099D03*
Y608099D03*
X1493700Y601139D03*
Y608139D03*
X1601106Y459700D03*
Y452700D03*
X1607614Y459696D03*
Y452696D03*
X1621900Y487300D03*
Y480300D03*
X1628500Y487000D03*
Y480000D03*
X1803495Y66060D03*
Y73060D03*
X1809995Y66060D03*
Y73060D03*
X1858769Y55803D03*
Y62803D03*
X1871500Y128000D03*
Y135000D03*
X1902340Y105391D03*
Y112391D03*
X1910500Y112000D03*
Y119000D03*
G54D173*
X1660158Y539547D03*
X1788110D03*
G54D182*
X1762519Y560809D03*
Y566793D03*
X1816154Y532970D03*
Y538954D03*
G54D26*
X11980Y21330D03*
X15480D03*
X5440Y21090D03*
X8940D03*
X17276Y59655D03*
X13776D03*
X20260Y49500D03*
X16760D03*
X8500Y62800D03*
X5000D03*
X34900Y164100D03*
X38400D03*
X4800Y197300D03*
X8300D03*
X6500Y236000D03*
X10000D03*
X-8700Y449350D03*
X-5200D03*
X-13400Y502800D03*
X-9900D03*
X-13400Y506300D03*
X-9900D03*
X37568Y480095D03*
X34068D03*
X6500Y570300D03*
X3000D03*
X7000Y534500D03*
X3500D03*
X-1750Y574100D03*
X-5250D03*
X58308Y-14773D03*
X54808D03*
X58308Y-17864D03*
X54808D03*
X58316Y-11754D03*
X54816D03*
X93714Y124724D03*
X97214D03*
X94000Y118500D03*
X97500D03*
X67000Y183000D03*
X70500D03*
X67000Y186500D03*
X70500D03*
X51500Y163000D03*
X55000D03*
X66000Y166500D03*
X69500D03*
X51500Y159500D03*
X55000D03*
X93500Y223800D03*
X97000D03*
X105800Y338200D03*
X102300D03*
X76600Y331900D03*
X73100D03*
X92000Y338200D03*
X95500D03*
X92000Y327500D03*
X95500D03*
X76600Y307300D03*
X80100D03*
X87500Y313000D03*
X91000D03*
X67500Y319500D03*
X64000D03*
X73000Y324500D03*
X76500D03*
X73000Y328000D03*
X76500D03*
X65620Y296680D03*
X62120D03*
X65520Y300680D03*
X62020D03*
X92370Y293020D03*
X88870D03*
X65000Y351500D03*
X68500D03*
X61100Y343150D03*
X64600D03*
X58000Y351000D03*
X54500D03*
X55130Y385820D03*
X51630D03*
X55130Y395520D03*
X51630D03*
X73730Y396080D03*
X70230D03*
X73730Y392580D03*
X70230D03*
X55130Y392020D03*
X51630D03*
X73730Y403380D03*
X70230D03*
X55110Y382340D03*
X51610D03*
X52330Y403420D03*
X48830D03*
X52330Y399920D03*
X48830D03*
X73730Y414180D03*
X70230D03*
X73730Y417680D03*
X70230D03*
X57990Y423170D03*
X54490D03*
X57990Y419670D03*
X54490D03*
X69730Y424980D03*
X66230D03*
X69730Y428480D03*
X66230D03*
X73730Y406880D03*
X70230D03*
X75830Y531361D03*
X79330D03*
X75846Y528307D03*
X79346D03*
X123392Y31978D03*
X119892D03*
X123392Y-6000D03*
X119892D03*
X123392Y69778D03*
X119892D03*
X130800Y214600D03*
X127300D03*
X130700Y278700D03*
X127200D03*
X130500Y246600D03*
X127000D03*
X130600Y310800D03*
X127100D03*
X130600Y342600D03*
X127100D03*
X130500Y374600D03*
X127000D03*
X151254Y417659D03*
X154754D03*
X151361Y420954D03*
X154861D03*
X151341Y424439D03*
X154841D03*
X164897Y410444D03*
X161397D03*
X164667Y407412D03*
X161167D03*
X123792Y532800D03*
X120292D03*
X123392Y570778D03*
X119892D03*
X123392Y608800D03*
X119892D03*
X251700Y366800D03*
X248200D03*
X252700Y362800D03*
X249200D03*
X252700Y358800D03*
X249200D03*
X252700Y354300D03*
X249200D03*
X252700Y349800D03*
X249200D03*
X313000Y253000D03*
X316500D03*
X313000Y256500D03*
X316500D03*
X312063Y341509D03*
X315563D03*
X312063Y345009D03*
X315563D03*
X343802Y496030D03*
X340302D03*
X444378Y117880D03*
X440878D03*
X452500Y278500D03*
X456000D03*
X438934Y270091D03*
X442434D03*
X461500Y301000D03*
X458000D03*
X461500Y295000D03*
X458000D03*
X457900Y283000D03*
X461400D03*
X458000Y307000D03*
X461500D03*
X458000Y304000D03*
X461500D03*
X458000Y310000D03*
X461500D03*
Y298000D03*
X458000D03*
X457900Y286000D03*
X461400D03*
X457900Y289000D03*
X461400D03*
X507472Y255647D03*
X510972D03*
X512430Y258547D03*
X515930D03*
X649600Y-9000D03*
X653100D03*
X659755Y-8699D03*
X656255D03*
X658300Y-4800D03*
X654800D03*
X656405Y89566D03*
X659905D03*
X656406Y92766D03*
X659906D03*
X653000Y264800D03*
X649500D03*
X653000Y261300D03*
X649500D03*
X646000Y272000D03*
X649500D03*
X646000Y268500D03*
X649500D03*
X644400Y302000D03*
X640900D03*
X644400Y316300D03*
X640900D03*
X644000Y327000D03*
X640500D03*
X644890Y337000D03*
X641390D03*
X644890Y332000D03*
X641390D03*
X644000Y322000D03*
X640500D03*
X644400Y312000D03*
X640900D03*
X644400Y307000D03*
X640900D03*
X653000Y320500D03*
X649500D03*
X653000Y316500D03*
X649500D03*
X653000Y333500D03*
X649500D03*
X612307Y470019D03*
X615807D03*
X660500Y494500D03*
X660320Y585600D03*
X663820D03*
X683950Y14500D03*
X687450D03*
X684726Y18015D03*
X688226D03*
X703919Y79550D03*
X700419D03*
X703919Y82850D03*
X700419D03*
X664888Y89189D03*
X668388D03*
X664888Y92766D03*
X668388D03*
X683000Y256000D03*
X686500D03*
X702000Y223500D03*
X705500D03*
X702036Y269061D03*
X705536D03*
X702011Y272561D03*
X705511D03*
X690000Y300500D03*
X693500D03*
X690251Y330500D03*
X693751D03*
X690251Y335500D03*
X693751D03*
X690420Y325500D03*
X693920D03*
X709100Y303600D03*
X712600D03*
Y300100D03*
X709100D03*
X690420Y320500D03*
X693920D03*
X690000Y305500D03*
X693500D03*
X686784Y291412D03*
X690284D03*
X681000Y317500D03*
X684500D03*
X681000Y321500D03*
X684500D03*
X681000Y333000D03*
X684500D03*
X670500Y494500D03*
X667000D03*
X664000D03*
X677400Y581900D03*
X673900D03*
X683600Y578500D03*
X687100D03*
X773000Y31978D03*
X769500D03*
X773000Y-6000D03*
X769500D03*
X773000Y69778D03*
X769500D03*
X780032Y214689D03*
X776532D03*
X780032Y246689D03*
X776532D03*
X780032Y278689D03*
X776532D03*
X772300Y252000D03*
X768800D03*
X772100Y220000D03*
X768600D03*
X780032Y310689D03*
X776532D03*
X771900Y284100D03*
X768400D03*
X771900Y315900D03*
X768400D03*
X779982Y374689D03*
X776482D03*
X780032Y342689D03*
X776532D03*
X772100Y380200D03*
X768600D03*
X772400Y348200D03*
X768900D03*
X726500Y574500D03*
X730000D03*
X773000Y570778D03*
X769500D03*
X773400Y532800D03*
X769900D03*
X773000Y608800D03*
X769500D03*
X806500Y415500D03*
X810000D03*
X806500Y418500D03*
X810000D03*
X806500Y412500D03*
X810000D03*
X898100Y341000D03*
X901600D03*
X899500Y367500D03*
X896000D03*
X899500Y364500D03*
X896000D03*
X899500Y361500D03*
X896000D03*
X899500Y355500D03*
X896000D03*
X899500Y358500D03*
X896000D03*
X898100Y344800D03*
X901600D03*
X961139Y253100D03*
X964639D03*
X961139Y256600D03*
X964639D03*
X961630Y340840D03*
X965130D03*
X961630Y344340D03*
X965130D03*
X1093800Y115500D03*
X1090300D03*
X1092000Y270000D03*
X1088500D03*
X1043300Y490900D03*
X1046800D03*
X1105456Y278241D03*
X1101956D03*
X1107700Y304100D03*
X1111200D03*
X1107756Y310241D03*
X1111256D03*
X1107756Y307241D03*
X1111256D03*
X1107756Y286141D03*
X1111256D03*
X1111300Y294500D03*
X1107800D03*
X1111300Y298100D03*
X1107800D03*
X1111300Y301100D03*
X1107800D03*
X1107756Y289341D03*
X1111256D03*
X1107756Y282941D03*
X1111256D03*
X1165400Y257726D03*
X1161900D03*
X1165522Y261143D03*
X1162022D03*
X1271550Y111670D03*
X1275050D03*
X1271550Y125857D03*
X1275050D03*
X1271550Y129670D03*
X1275050D03*
X1271139Y117373D03*
X1274639D03*
X1275050Y107918D03*
X1271550D03*
X1264550Y107670D03*
X1268050D03*
Y129670D03*
X1264550D03*
X1268050Y125670D03*
X1264550D03*
X1268050Y111670D03*
X1264550D03*
X1252300Y130700D03*
X1255800D03*
X1252300Y134700D03*
X1255800D03*
X1248700Y473700D03*
X1245200D03*
X1245300Y477300D03*
X1248800D03*
X1330100Y71510D03*
X1333600D03*
X1330100Y68000D03*
X1333600D03*
X1291524Y214952D03*
X1288024D03*
X1303072Y249560D03*
X1299572D03*
X1303171Y245893D03*
X1299671D03*
X1299750Y241500D03*
X1303250D03*
X1288000Y219000D03*
X1291500D03*
X1287670Y231199D03*
X1291170D03*
X1291000Y237500D03*
X1287500D03*
Y243500D03*
X1291000D03*
X1303040Y264840D03*
X1299540D03*
X1303040Y260840D03*
X1299540D03*
X1299589Y257102D03*
X1303089D03*
X1303072Y252660D03*
X1299572D03*
X1287500Y240500D03*
X1291000D03*
X1298000Y219000D03*
X1294500D03*
X1341500Y329100D03*
Y332700D03*
Y325600D03*
X1340969Y354526D03*
X1337469D03*
X1281350Y488700D03*
X1284850D03*
X1367089Y2676D03*
X1370589D03*
X1367400Y34700D03*
X1370900D03*
X1382080Y328782D03*
X1385580D03*
X1345000Y329100D03*
Y332700D03*
Y325600D03*
X1346800Y340800D03*
X1343300D03*
X1385300Y341500D03*
X1381800D03*
X1385850Y286700D03*
X1389350D03*
X1385850Y283600D03*
X1389350D03*
X1388750Y293500D03*
X1392250D03*
X1385850Y289700D03*
X1389350D03*
X1395512Y339812D03*
X1399012D03*
X1385300Y332000D03*
X1381800D03*
X1386300Y338400D03*
X1382800D03*
X1386300Y335200D03*
X1382800D03*
X1343300Y347800D03*
X1346800D03*
Y344300D03*
X1343300D03*
X1381800Y344500D03*
X1385300D03*
X1385900Y353803D03*
X1382400D03*
X1381780Y356848D03*
X1385280D03*
X1385300Y347518D03*
X1381800D03*
X1359649Y358155D03*
X1356149D03*
X1369707Y393568D03*
X1373207D03*
X1385920Y350658D03*
X1382420D03*
X1358300Y443800D03*
X1361800D03*
X1391341Y498523D03*
X1394841D03*
X1391341Y494223D03*
X1394841D03*
X1388841Y482923D03*
X1392341D03*
X1388841Y487323D03*
X1392341D03*
X1371041Y497423D03*
X1374541D03*
X1368941Y482123D03*
X1372441D03*
X1371041Y493023D03*
X1374541D03*
X1368841Y486523D03*
X1372341D03*
X1354871Y512287D03*
X1351371D03*
X1394841Y498523D03*
X1398341D03*
X1394841Y494223D03*
X1398341D03*
X1392341Y482923D03*
X1395841D03*
X1392341Y487323D03*
X1395841D03*
X1372341Y486523D03*
X1375841D03*
X1374541Y493023D03*
X1378041D03*
X1374541Y497423D03*
X1378041D03*
X1372441Y482123D03*
X1375941D03*
X1371400Y581556D03*
X1374900D03*
X1370600Y613100D03*
X1374100D03*
X1460577Y163412D03*
X1464077D03*
Y159912D03*
X1460577D03*
X1419511Y176559D03*
X1423011D03*
Y173059D03*
X1419511D03*
Y170059D03*
X1423011D03*
X1419511Y166559D03*
X1423011D03*
Y163559D03*
X1419511D03*
Y179559D03*
X1423011D03*
X1419511Y186059D03*
X1423011D03*
X1419511Y183059D03*
X1423011D03*
X1452659Y188296D03*
X1456159D03*
X1438072Y189932D03*
X1434572D03*
X1458500Y252000D03*
X1462000D03*
X1435500Y311400D03*
X1439000D03*
X1435500Y308400D03*
X1439000D03*
X1435500Y305400D03*
X1439000D03*
X1434700Y315100D03*
X1438200D03*
X1453811Y369748D03*
X1457311D03*
X1449564Y362601D03*
X1453064D03*
X1451000Y448000D03*
X1454500D03*
X1451000Y437000D03*
X1454500D03*
X1451000Y442500D03*
X1454500D03*
X1435500Y437000D03*
X1439000D03*
X1435500Y448000D03*
X1439000D03*
X1435500Y453500D03*
X1439000D03*
X1451000Y431500D03*
X1454500D03*
X1435500Y442500D03*
X1439000D03*
X1444614Y482523D03*
X1448114D03*
X1444614Y478123D03*
X1448114D03*
X1444641Y489723D03*
X1448141D03*
X1444641Y494123D03*
X1448141D03*
X1421014Y482323D03*
X1424514D03*
X1421014Y477923D03*
X1424514D03*
X1420841Y494323D03*
X1424341D03*
X1420841Y489923D03*
X1424341D03*
X1424514Y477923D03*
X1428014D03*
X1448141Y489723D03*
X1451641D03*
X1448141Y494123D03*
X1451641D03*
X1448114Y482523D03*
X1451614D03*
X1448114Y478123D03*
X1451614D03*
X1424341Y489923D03*
X1427841D03*
X1424341Y494323D03*
X1427841D03*
X1424514Y482323D03*
X1428014D03*
X1436060Y541455D03*
X1432560D03*
X1436060Y544955D03*
X1432560D03*
X1501900Y12541D03*
X1505400D03*
X1526000Y64500D03*
X1520106Y93976D03*
X1516606D03*
X1497500Y76000D03*
X1494000D03*
X1497500Y79500D03*
X1494000D03*
X1526337Y136439D03*
X1522837D03*
X1520106Y97976D03*
X1516606D03*
X1521071Y104358D03*
X1517571D03*
X1521071Y108358D03*
X1517571D03*
X1520610Y120361D03*
X1517110D03*
X1520610Y116361D03*
X1517110D03*
X1472072Y142112D03*
X1468572D03*
X1520250Y215000D03*
X1516750D03*
X1521500Y194500D03*
X1518000D03*
X1523500Y189000D03*
X1520000D03*
Y186000D03*
X1523500D03*
X1518979Y179889D03*
X1522479D03*
X1494000Y194000D03*
X1490500D03*
X1480250Y180000D03*
X1476750D03*
X1477442Y190269D03*
X1473942D03*
Y187269D03*
X1477442D03*
X1468300Y181400D03*
X1471800D03*
X1470223Y156988D03*
X1473723D03*
X1508750Y177000D03*
X1505250D03*
X1508750Y174000D03*
X1505250D03*
X1473123Y163088D03*
X1476623D03*
X1473123Y160088D03*
X1476623D03*
X1469700Y211850D03*
X1473200D03*
X1468300Y184400D03*
X1471800D03*
X1480250Y176800D03*
X1476750D03*
X1515312Y231532D03*
X1518812D03*
X1515250Y237000D03*
X1518750D03*
X1470729Y240547D03*
X1467229D03*
X1467750Y220000D03*
X1471250D03*
X1467750Y223500D03*
X1471250D03*
X1467750Y227000D03*
X1471250D03*
X1525422Y227625D03*
Y230625D03*
X1526610Y336680D03*
Y333680D03*
X1480500Y323500D03*
X1477000D03*
X1526660Y315900D03*
X1487000Y322400D03*
X1490500D03*
X1498430Y311510D03*
X1501930D03*
X1513060Y319170D03*
X1509560D03*
X1503519Y283694D03*
X1507019D03*
X1506996Y280694D03*
X1503496D03*
X1487000Y325500D03*
X1490500D03*
X1522810Y327640D03*
X1519310D03*
X1479200Y401900D03*
X1475700D03*
X1479000Y394900D03*
X1475500D03*
X1470100Y360500D03*
X1466600D03*
X1470200Y357500D03*
X1466700D03*
X1469750Y369500D03*
X1466250D03*
X1469750Y366500D03*
X1466250D03*
X1475755Y376254D03*
X1479255D03*
X1475500Y398400D03*
X1479000D03*
X1502302Y410686D03*
X1505802D03*
X1524100Y494123D03*
X1527600D03*
X1511000Y526000D03*
X1507500D03*
X1474300Y615500D03*
X1477800D03*
X1508600Y616416D03*
X1512100D03*
X1508600Y623110D03*
X1512100D03*
X1586600Y-13300D03*
Y-9600D03*
X1555450Y81200D03*
X1558950D03*
X1529500Y64500D03*
X1552050Y78000D03*
X1555550D03*
X1548850Y81200D03*
X1552350D03*
X1587100Y91000D03*
X1583600D03*
X1534436Y95154D03*
X1537936D03*
X1534436Y85354D03*
X1537936D03*
X1534436Y88754D03*
X1537936D03*
X1534436Y91954D03*
X1537936D03*
X1536000Y64500D03*
X1532500D03*
X1534889Y34238D03*
X1531389D03*
X1536000Y68000D03*
X1532500D03*
X1585000Y137000D03*
X1581500D03*
X1584450Y155600D03*
X1580950D03*
Y152600D03*
X1584450D03*
Y146100D03*
X1580950D03*
Y149200D03*
X1584450D03*
X1577271Y101142D03*
X1573771D03*
X1563502Y117500D03*
X1560002D03*
X1553500D03*
X1557000D03*
X1543169Y143954D03*
X1539669D03*
X1584599Y143038D03*
X1581099D03*
X1584599Y140038D03*
X1581099D03*
X1545500Y112500D03*
X1549000D03*
X1545500Y109000D03*
X1549000D03*
X1534436Y101554D03*
X1537936D03*
X1534436Y98354D03*
X1537936D03*
X1534750Y152065D03*
X1538250D03*
X1534750Y148565D03*
X1538250D03*
X1534750Y155565D03*
X1538250D03*
X1580750Y166000D03*
X1584250D03*
X1584099Y162838D03*
X1580599D03*
X1584099Y159838D03*
X1580599D03*
X1580750Y169000D03*
X1584250D03*
X1578920Y190920D03*
X1575420D03*
X1556000Y257250D03*
X1552500D03*
X1556008Y260918D03*
X1552508D03*
X1528750Y241500D03*
X1532250D03*
X1536000Y260500D03*
X1532500D03*
X1528922Y227625D03*
Y230625D03*
X1532650Y253713D03*
X1536150D03*
X1566817Y243681D03*
X1570317D03*
X1552500Y264000D03*
X1556000D03*
X1555500Y247000D03*
X1552000D03*
X1555500Y250500D03*
X1552000D03*
X1587971Y311952D03*
X1530110Y336680D03*
Y333680D03*
X1530160Y315900D03*
X1576100Y292000D03*
X1572600D03*
X1562500Y296050D03*
X1566000D03*
X1589250Y379500D03*
Y385500D03*
Y382500D03*
Y388500D03*
X1546032Y352846D03*
X1549532D03*
Y347696D03*
X1546032D03*
X1585352Y366117D03*
X1588852D03*
X1585352Y369117D03*
X1588852D03*
X1574250Y418000D03*
X1577750D03*
X1547269Y448438D03*
X1543769D03*
X1546972Y453999D03*
X1543472D03*
X1535200Y494123D03*
X1531700D03*
X1583255Y502596D03*
X1579755D03*
X1583255Y497596D03*
X1579755D03*
X1576456Y491096D03*
X1572956D03*
X1576456Y494596D03*
X1572956D03*
X1588300Y583000D03*
X1574569Y589228D03*
X1578069D03*
X1581000Y603500D03*
X1584500D03*
X1581000Y600500D03*
X1584500D03*
X1557039Y614627D03*
X1560539D03*
X1538110Y598430D03*
X1541610D03*
X1548371Y594310D03*
X1551871D03*
X1552172Y604536D03*
X1548672D03*
X1538430Y604180D03*
X1541930D03*
X1551871Y597810D03*
X1548371D03*
X1551871Y601310D03*
X1548371D03*
X1549075Y619000D03*
X1552575D03*
X1590100Y-13300D03*
X1627250Y17000D03*
X1630750D03*
X1634250D03*
X1637750D03*
X1613250Y18000D03*
X1609750D03*
X1605000Y-1100D03*
X1608500D03*
X1590100Y-9600D03*
X1616250Y17000D03*
X1619750D03*
X1624750Y72000D03*
X1628250D03*
X1614250Y78000D03*
X1610750D03*
X1628500Y80300D03*
X1632000D03*
X1624750Y69000D03*
X1628250D03*
X1603550Y58200D03*
X1607050D03*
X1609450Y34500D03*
X1605950D03*
X1613550Y34700D03*
X1617050D03*
X1617727Y46763D03*
X1621227D03*
X1622750Y43311D03*
X1619250D03*
X1645000Y35500D03*
X1648500D03*
X1609099Y86038D03*
X1612599D03*
X1611059Y46684D03*
X1614559D03*
X1598439Y128600D03*
X1601939D03*
X1606500Y110000D03*
X1603000D03*
X1604500Y107000D03*
X1601000D03*
X1599401Y138165D03*
X1595901D03*
X1599400Y135092D03*
X1595900D03*
X1594600Y131600D03*
X1598100D03*
X1595300Y121500D03*
X1591800D03*
X1595250Y118500D03*
X1591750D03*
X1594150Y115500D03*
X1590650D03*
X1641854Y138592D03*
X1645354D03*
X1635480Y146470D03*
X1638980D03*
X1646111Y150750D03*
X1642611D03*
X1645601Y144750D03*
X1649101D03*
X1639250Y115500D03*
X1635750D03*
X1648090Y118640D03*
X1616750Y131500D03*
X1620250D03*
X1626750Y137500D03*
X1623250D03*
X1616592Y156055D03*
X1620092D03*
X1616599Y137538D03*
X1620099D03*
X1622250Y109500D03*
X1618750D03*
X1622750Y96000D03*
X1626250D03*
X1622750Y99500D03*
X1626250D03*
X1622750Y103000D03*
X1626250D03*
X1608250Y96000D03*
X1611750D03*
X1622888Y116340D03*
X1619388D03*
X1616498Y122472D03*
X1619998D03*
X1645597Y147750D03*
X1649097D03*
X1623700Y143900D03*
X1620200D03*
X1622791Y113140D03*
X1619291D03*
X1644950Y189600D03*
X1648450D03*
Y192600D03*
X1644950D03*
X1619846Y188276D03*
X1623346D03*
X1619781Y191683D03*
X1623281D03*
X1599740Y200550D03*
X1596240D03*
X1629380Y179436D03*
X1632880D03*
X1591471Y311952D03*
X1592750Y379500D03*
Y385500D03*
Y382500D03*
Y388500D03*
X1626200Y352050D03*
X1629700D03*
X1591852Y366117D03*
X1595352D03*
X1591852Y372117D03*
X1595352D03*
X1591852Y369117D03*
X1595352D03*
X1605250Y430000D03*
X1608750D03*
X1622783Y419548D03*
X1626283D03*
X1619500Y494000D03*
X1616000D03*
X1591800Y583000D03*
X1628600Y559200D03*
X1632100D03*
X1615000Y555200D03*
X1618500D03*
X1628600D03*
X1632100D03*
X1609100Y582500D03*
X1612600D03*
X1609100Y578500D03*
X1612600D03*
X1618000Y576500D03*
X1621500D03*
X1618000Y572500D03*
X1621500D03*
X1615000Y559200D03*
X1618500D03*
X1619500Y586880D03*
X1616000D03*
X1611000Y596500D03*
X1607500D03*
X1619500Y599500D03*
X1616000D03*
X1619500Y603000D03*
X1616000D03*
X1610400Y608200D03*
X1606900D03*
X1611000Y593000D03*
X1607500D03*
X1610400Y604700D03*
X1606900D03*
X1619500Y590380D03*
X1616000D03*
X1661250Y16500D03*
X1664750D03*
X1711250Y68500D03*
X1707750D03*
Y72000D03*
X1711250D03*
X1686250Y80000D03*
X1682750D03*
X1686250Y83000D03*
X1682750D03*
X1662500Y58800D03*
X1659000D03*
X1671700Y59300D03*
X1675200D03*
X1673750Y46000D03*
X1677250D03*
X1671700Y55800D03*
X1675200D03*
X1680736Y47039D03*
X1684236D03*
X1684250Y44000D03*
X1680750D03*
X1688350Y71000D03*
X1684850D03*
Y68000D03*
X1688350D03*
X1685661Y60161D03*
X1689161D03*
X1685661Y63161D03*
X1689161D03*
X1690250Y49000D03*
X1693750D03*
X1689750Y54000D03*
X1693250D03*
X1692272Y60161D03*
X1695772D03*
X1686125Y51223D03*
X1682625D03*
X1682638Y54311D03*
X1686138D03*
X1682750Y86000D03*
X1686250D03*
X1682750Y89000D03*
X1686250D03*
Y92000D03*
X1682750D03*
X1686250Y95000D03*
X1682750D03*
X1702749Y69233D03*
X1699249D03*
X1651590Y118640D03*
X1657500Y128000D03*
X1654000D03*
X1656599Y189608D03*
X1653099D03*
X1660679Y179278D03*
X1657179D03*
Y175778D03*
X1660679D03*
X1653099Y192608D03*
X1656599D03*
X1711535Y172070D03*
X1708035D03*
X1710811Y165400D03*
X1711506Y168970D03*
X1708006D03*
X1658800Y327300D03*
X1662300D03*
X1705683Y580727D03*
X1709183D03*
Y584727D03*
X1705683D03*
X1699780Y558817D03*
X1696280D03*
X1699780Y555517D03*
X1696280D03*
X1667680Y587000D03*
X1664180D03*
X1656000Y578500D03*
X1659500D03*
X1656000Y582000D03*
X1659500D03*
X1703500Y604500D03*
X1707000D03*
X1703500Y595500D03*
X1707000D03*
X1703500Y600000D03*
X1707000D03*
X1659500Y597500D03*
X1656000D03*
X1659500Y594000D03*
X1656000D03*
X1659500Y613500D03*
X1656000D03*
X1659500Y610000D03*
X1656000D03*
X1667500Y606000D03*
X1664000D03*
X1667500Y602500D03*
X1664000D03*
X1667680Y590500D03*
X1664180D03*
X1768100Y31700D03*
X1771600D03*
X1759900Y71300D03*
X1763400D03*
X1773750Y94500D03*
X1770250D03*
Y89500D03*
X1773750D03*
X1763300Y68300D03*
X1759800D03*
X1731960Y83830D03*
X1728460D03*
X1743000Y51600D03*
X1739500D03*
Y57800D03*
X1743000D03*
X1756879Y87674D03*
X1760379D03*
X1756961Y93081D03*
X1760461D03*
X1737589Y63639D03*
X1734089D03*
X1723681Y89100D03*
X1727181D03*
X1772211Y67650D03*
Y70650D03*
X1743000Y54700D03*
X1739500D03*
X1770250Y99500D03*
X1773750D03*
X1751779Y151165D03*
X1748279D03*
X1730289Y130319D03*
X1726789D03*
X1730289Y126381D03*
X1726789D03*
X1761035Y116600D03*
X1764535D03*
X1770250Y104500D03*
X1773750D03*
X1761035Y113400D03*
X1764535D03*
X1725250Y191500D03*
X1728750D03*
X1714311Y165400D03*
X1734930Y228440D03*
X1738430D03*
X1745920Y228410D03*
X1742420D03*
X1759400Y243400D03*
X1755900D03*
X1759400Y246400D03*
X1755900D03*
X1765000Y517000D03*
X1768500D03*
X1774000Y555500D03*
X1770500D03*
X1741200Y559200D03*
X1744700D03*
X1773900Y562450D03*
X1770400D03*
X1769000Y581900D03*
X1772500D03*
X1769000Y578900D03*
X1772500D03*
X1746292Y578251D03*
X1742792D03*
X1769050Y588100D03*
X1772550D03*
X1745200Y555363D03*
X1741700D03*
X1769050Y585000D03*
X1772550D03*
X1746269Y581351D03*
X1742769D03*
X1769000Y591100D03*
X1772500D03*
X1768397Y613578D03*
X1771897D03*
X1730232Y618712D03*
X1726732D03*
X1832250Y17500D03*
X1828750D03*
X1835250D03*
X1784415Y15168D03*
X1780915D03*
X1784415Y18168D03*
X1780915D03*
X1804500Y16600D03*
X1801000D03*
X1797000D03*
X1793500D03*
X1782200Y21700D03*
X1778700D03*
X1819930Y52029D03*
X1823430D03*
X1775711Y67650D03*
Y70650D03*
X1804814Y84623D03*
X1801314D03*
X1819136Y42120D03*
X1822636D03*
X1792127Y125981D03*
X1788627D03*
Y122981D03*
X1792127D03*
X1814900Y137600D03*
X1811400D03*
Y140600D03*
X1814900D03*
X1783300Y519100D03*
X1786800D03*
X1809052Y523001D03*
X1812552D03*
X1821052D03*
X1817552D03*
X1824750Y498000D03*
X1828250D03*
X1807600Y515600D03*
X1804100D03*
X1825552Y537501D03*
X1822052D03*
X1825552Y541001D03*
X1822052D03*
X1819552Y581301D03*
X1816052D03*
X1786200Y574700D03*
X1789700D03*
Y580900D03*
X1786200D03*
X1805100Y567500D03*
X1801600D03*
X1822000Y576000D03*
X1818500D03*
X1786200Y577800D03*
X1789700D03*
X1812000Y606000D03*
X1808500D03*
X1838750Y17500D03*
X1873336Y22480D03*
X1869836D03*
X1873336Y18980D03*
X1869836D03*
X1883993Y13300D03*
X1880493D03*
X1883951Y9897D03*
X1880451D03*
X1845197Y27000D03*
X1841697D03*
X1848486Y29680D03*
X1851986D03*
X1848386Y17980D03*
X1851886D03*
X1876993Y13300D03*
X1880493D03*
X1876951Y9897D03*
X1880451D03*
X1862539Y78537D03*
X1866039D03*
Y75138D03*
X1862539D03*
X1856163Y150948D03*
X1859663D03*
X1863500Y151000D03*
X1867000D03*
X1893150Y155600D03*
X1889650D03*
X1892050Y152100D03*
X1888550D03*
X1885750Y130500D03*
X1889250D03*
X1871290Y121480D03*
X1867790D03*
X1871290Y117980D03*
X1867790D03*
X1891250Y119000D03*
X1894750D03*
X1891290Y115580D03*
X1894790D03*
X1897000Y209200D03*
X1847000Y216500D03*
X1850500D03*
X1893200Y170900D03*
X1889700D03*
X1893200Y167700D03*
X1889700D03*
X1893250Y174500D03*
X1889750D03*
X1892750Y159100D03*
X1889250D03*
X1896735Y231622D03*
Y228622D03*
X1892963Y231387D03*
X1889463D03*
X1892963Y228387D03*
X1889463D03*
X1896735Y225622D03*
X1847000Y222000D03*
X1850500D03*
X1847000Y240000D03*
X1850500D03*
X1847000Y243000D03*
X1850500D03*
X1847000Y246000D03*
X1850500D03*
X1847000Y228000D03*
X1850500D03*
X1847000Y237000D03*
X1850500D03*
X1847000Y225000D03*
X1850500D03*
Y234000D03*
X1847000D03*
X1850500Y231000D03*
X1847000D03*
X1858500Y445100D03*
X1855000D03*
Y441500D03*
X1858500D03*
X1895200Y445300D03*
X1898000Y451000D03*
X1894500D03*
X1865847Y500954D03*
X1869347D03*
X1865799Y504018D03*
X1869299D03*
X1862700Y491650D03*
X1859200D03*
X1854550Y505510D03*
X1858050D03*
X1862700Y488500D03*
X1859200D03*
X1896154Y563968D03*
Y560968D03*
Y566968D03*
X1894654Y569968D03*
X1855750Y545500D03*
X1852250D03*
Y542500D03*
X1855750D03*
X1871500Y579500D03*
X1875000D03*
X1872146Y533140D03*
X1875646D03*
X1869310D03*
X1865810D03*
X1852500Y530700D03*
X1849000D03*
X1845750Y542500D03*
X1849250D03*
X1841500Y552600D03*
X1838000D03*
X1861538Y572746D03*
X1865038D03*
X1859187Y534585D03*
X1862687D03*
X1859217Y531331D03*
X1862717D03*
X1913143Y-19572D03*
X1909643D03*
X1909661Y-16368D03*
X1913161D03*
X1908166Y67073D03*
X1904666D03*
X1901661Y67193D03*
X1898161D03*
X1920500Y71500D03*
X1924000D03*
X1898143Y70589D03*
X1901643D03*
X1904736Y70607D03*
X1908236D03*
X1959619Y136676D03*
X1956321Y149724D03*
D03*
X1952821D03*
X1920100Y143100D03*
X1923600D03*
X1914700Y137600D03*
X1918200D03*
X1942637Y103377D03*
X1939137D03*
X1951341Y187424D03*
X1954841D03*
X1951318Y181882D03*
X1954818D03*
X1912850Y196300D03*
X1909350D03*
X1900500Y209200D03*
X1930449Y183722D03*
X1926949D03*
X1930341Y188701D03*
X1926841D03*
X1919150Y163100D03*
X1922650D03*
X1933250Y157600D03*
X1936750D03*
X1898250Y191000D03*
X1901750D03*
X1918750Y171600D03*
X1922250D03*
X1918474Y175140D03*
X1921974D03*
X1902250Y187500D03*
X1898750D03*
X1900235Y231622D03*
Y228622D03*
Y225622D03*
X1917336Y231924D03*
X1913836D03*
X1925665Y239441D03*
X1922165D03*
X1917356Y228756D03*
X1913856D03*
X1925660Y236318D03*
X1922160D03*
X1913970Y239458D03*
X1910470D03*
X1913959Y236258D03*
X1910459D03*
X1910500Y445800D03*
X1914000D03*
X1926500D03*
X1923000D03*
X1898700Y445300D03*
X1905000Y451000D03*
X1901500D03*
X1929860Y486480D03*
X1933360D03*
X1934150Y475400D03*
X1930650D03*
X1934150Y478400D03*
X1930650D03*
X1944710Y484520D03*
X1941210D03*
X1931285Y583000D03*
X1927785D03*
X1931285Y579500D03*
X1927785D03*
X1931285Y575500D03*
X1927785D03*
X1931285Y572000D03*
X1927785D03*
X1899654Y563968D03*
Y560968D03*
Y566968D03*
X1898154Y569968D03*
X1921500Y549900D03*
X1918000D03*
X1921000Y554400D03*
X1917500D03*
X1927750Y611550D03*
X1931250D03*
X1929740Y594760D03*
X1926240D03*
Y591260D03*
X1929740D03*
X1921250Y596900D03*
X1917750D03*
Y600400D03*
X1921250D03*
X1963119Y136676D03*
X1966619D03*
X1963119D03*
X1959821Y149724D03*
X1968249Y149881D03*
X1971749D03*
X1965973Y169460D03*
X1969473D03*
X1963500Y518200D03*
X1967000D03*
X1966500Y545500D03*
X1963000D03*
X1966500Y540500D03*
X1963000D03*
X1971000Y603100D03*
X1967500D03*
G54D155*
X1651800Y92500D03*
Y87500D03*
X1624300Y90800D03*
X1651800Y97500D03*
G54D128*
X1442000Y-15000D03*
X1505000D03*
X1703503D03*
X1769504D03*
G54D218*
X1952756Y558464D03*
G54D53*
X63093Y202300D03*
X72936D03*
X82779D03*
X1892720Y525415D03*
X1914911Y495775D03*
X1934597D03*
X1924754D03*
X1900595Y525415D03*
X1908469D03*
X1916343D03*
X1924217D03*
X1922248Y518328D03*
X1912406D03*
X1904532D03*
G54D17*
X-14488Y434094D03*
X-4488D03*
X5512D03*
X15512D03*
X89980Y145531D03*
X99980D03*
X109980D03*
X119980D03*
G54D191*
X1895945Y-2322D03*
Y5670D03*
Y13662D03*
Y21654D03*
Y29646D03*
Y37638D03*
Y45630D03*
X1900945Y-6318D03*
Y1674D03*
Y9666D03*
Y17658D03*
Y25650D03*
Y33642D03*
Y41634D03*
Y49626D03*
G54D35*
X48700Y261300D03*
X29000D03*
X48700Y250260D03*
X29000D03*
G54D80*
X346748Y492120D03*
X367615Y491120D03*
X1037657Y487300D03*
G54D137*
X1431595Y422663D03*
G54D146*
X1508500Y432500D03*
X1513400D03*
G54D237*
G01X1592700Y154600D02*
Y154595D01*
X1590569Y152464D01*
G01X1595901Y138165D02*
X1593865D01*
X1593500Y137800D01*
G01X1595900Y135092D02*
X1594672D01*
X1593539Y136225D01*
X1592847D01*
X1591272Y137800D01*
X1590800D01*
G01X1629487Y109280D02*
X1631094Y107673D01*
G01X1599401Y138165D02*
X1600759D01*
X1603201Y140607D01*
X1604603D01*
G01D02*
X1605792D01*
X1607441Y138958D01*
Y137538D01*
G01X1602600Y135856D02*
X1603814D01*
X1604292Y135378D01*
Y134388D01*
G01X1602600Y135856D02*
X1601176D01*
X1600412Y135092D01*
X1599400D01*
G01X1601400Y113100D02*
X1598400D01*
X1597307Y114193D01*
G01X1601400Y113100D02*
X1605800D01*
X1606700Y114000D01*
X1609100D01*
X1610591Y115491D01*
G01X1597307Y114193D02*
X1596000Y115500D01*
X1594150D01*
G01X1666701Y179511D02*
X1679250D01*
G01X1615900Y172800D02*
X1614800Y171700D01*
X1612376D01*
X1611100Y170424D01*
Y169260D01*
X1610025Y168185D01*
X1609640D01*
X1609585Y168130D01*
X1608338D01*
X1607240Y169228D01*
Y169230D01*
X1606538Y169932D01*
Y173091D01*
G01X1609222Y173389D02*
X1609116Y173283D01*
Y170006D01*
G01X1678846Y97595D02*
X1678845D01*
G01X1672500Y109800D02*
Y111900D01*
X1672200Y112200D01*
G01X1672500Y106300D02*
X1671676Y107124D01*
X1668208D01*
X1667600Y106516D01*
Y106232D01*
G01D02*
Y105153D01*
X1668293Y104460D01*
X1670373D01*
X1670388Y104475D01*
X1673425D01*
X1674800Y103100D01*
G01X1657835Y162735D02*
X1656360Y164210D01*
Y166496D01*
X1657223Y167359D01*
X1658869D01*
X1660891Y169381D01*
G01D02*
X1662389Y170879D01*
Y173642D01*
X1662400Y173653D01*
Y174200D01*
X1663400Y175200D01*
Y179475D01*
G01X1656700Y171014D02*
Y173039D01*
X1657179Y173518D01*
Y175778D01*
G01X1657835Y159585D02*
X1659510Y161260D01*
Y166497D01*
X1660373Y167360D01*
X1661524D01*
X1663550Y169386D01*
Y174266D01*
X1665295Y176011D01*
X1666701D01*
G01D02*
X1671209D01*
G01X1784023Y162523D02*
X1785500Y164000D01*
G01X1821600Y227200D02*
Y231068D01*
X1822638Y232106D01*
G01X1795358Y238669D02*
X1797333Y236694D01*
X1804403D01*
X1808197Y232900D01*
Y229254D01*
X1813727Y223724D01*
X1834576D01*
X1845354Y212946D01*
X1847699D01*
G01X1800728Y238920D02*
X1803607D01*
X1806989Y235538D01*
X1810783D01*
X1819674Y226647D01*
Y226402D01*
X1820802Y225274D01*
X1821047D01*
X1821597Y224724D01*
X1835200D01*
X1845324Y214600D01*
X1848400D01*
X1850054Y212946D01*
X1850876D01*
G54D228*
G01X1658580Y-41408D02*
X1470810D01*
G03Y-45109I0J-1850D01*
G01X1657350D01*
G02Y-52410I0J-3651D01*
G01X1463564D01*
X1459311Y-48157D01*
X1456358D01*
X1452258Y-52257D01*
G01X1658580Y-39608D02*
X1470809D01*
G03X1470811Y-46909I1J-3650D01*
G01X1657350D01*
G02Y-50610I0J-1851D01*
G01X1464310D01*
X1460057Y-46357D01*
X1456358D01*
X1452258Y-42257D01*
G54D72*
X47500Y507100D03*
X1471900Y176700D03*
X1599530Y205480D03*
X1627200Y169500D03*
X1669700Y85000D03*
X1745600Y87950D03*
X1759108Y132250D03*
Y127750D03*
Y141250D03*
Y136750D03*
X1767670Y132250D03*
Y127750D03*
Y141250D03*
Y136750D03*
X1759108Y145798D03*
X1767622D03*
X1725300Y198700D03*
X1891900Y225100D03*
G54D219*
X1899972Y615413D03*
Y609913D03*
G54D183*
X1760354Y569942D03*
X1758386D03*
X1756417D03*
X1754448D03*
X1752480D03*
X1810052Y542103D03*
X1813989D03*
X1812021D03*
X1808083D03*
X1806115D03*
G54D63*
X86750Y328000D03*
X102400Y313000D03*
X1615968Y23800D03*
G54D192*
X1871988Y55350D03*
X1875924D03*
Y47250D03*
X1871988D03*
X1873956Y55350D03*
X1877892D03*
X1873956Y47250D03*
X1877892D03*
G54D156*
X1646200Y92500D03*
Y87500D03*
X1618700Y90800D03*
X1646200Y97500D03*
G54D27*
X42800Y35300D03*
Y56300D03*
Y77300D03*
X43100Y568100D03*
X42900Y547900D03*
X43100Y588600D03*
Y608600D03*
X70800Y35300D03*
Y56300D03*
Y77300D03*
X71100Y568100D03*
X70900Y547900D03*
X71100Y588600D03*
Y608600D03*
X150000Y267500D03*
Y246500D03*
Y224500D03*
Y288500D03*
Y310500D03*
Y330500D03*
X151574Y396363D03*
X150000Y352000D03*
X151574Y376363D03*
X178000Y267500D03*
Y246500D03*
Y224500D03*
Y288500D03*
Y310500D03*
Y330500D03*
X179574Y396363D03*
X178000Y352000D03*
X179574Y376363D03*
X568500Y483500D03*
X596500D03*
X649500Y217500D03*
Y238800D03*
X667900Y562300D03*
X730000Y195700D03*
X677500Y217500D03*
Y238800D03*
X695900Y562300D03*
X758000Y195700D03*
X802108Y246500D03*
X830108D03*
X802108Y224500D03*
X830108D03*
X802108Y267500D03*
X830108D03*
X802108Y310500D03*
X830108D03*
X802108Y288500D03*
X830108D03*
X802108Y330500D03*
X830108D03*
X801182Y376363D03*
X829182D03*
X801182Y396363D03*
X829182D03*
X802108Y352800D03*
X830108D03*
X1343000Y-8000D03*
X1315000D03*
X1343000Y13000D03*
X1315000D03*
X1323000Y371000D03*
Y391000D03*
X1347600Y431000D03*
X1323000Y411000D03*
X1339081Y473466D03*
X1311081D03*
X1340172Y491683D03*
X1312172D03*
X1343000Y592000D03*
X1315000D03*
X1335500Y556500D03*
X1307500D03*
X1334300Y533100D03*
X1306300D03*
X1343000Y612000D03*
X1315000D03*
X1356000Y137000D03*
X1384000D03*
X1377700Y183700D03*
X1349700D03*
X1351000Y371000D03*
Y391000D03*
X1375600Y431000D03*
X1351000Y411000D03*
X1871725Y87256D03*
X1899725D03*
X1897200Y463700D03*
X1925200D03*
G54D90*
X601049Y345981D03*
G54D45*
X42724Y644684D03*
Y644656D03*
Y654684D03*
Y654656D03*
X67724Y644684D03*
Y644656D03*
Y654684D03*
Y654656D03*
X221656Y644656D03*
X196656D03*
X231446Y644756D03*
Y644784D03*
X221656Y644684D03*
X196656D03*
X221656Y654656D03*
X196656D03*
X231446Y654756D03*
Y654784D03*
X221656Y654684D03*
X196656D03*
X256446Y644756D03*
Y644784D03*
Y654756D03*
Y654784D03*
X409240Y644564D03*
X384240D03*
X418914Y644486D03*
Y644514D03*
X409240Y644536D03*
X384240D03*
X409240Y654564D03*
X384240D03*
X418914Y654486D03*
Y654514D03*
X409240Y654536D03*
X384240D03*
X443914Y644486D03*
Y644514D03*
Y654486D03*
Y654514D03*
X596707Y644293D03*
X571707D03*
X596708Y644266D03*
X571708D03*
X596707Y654293D03*
X571707D03*
X596708Y654266D03*
X571708D03*
X606462Y644245D03*
X631462D03*
X606462Y644217D03*
X631462D03*
X606462Y654245D03*
X631462D03*
X606462Y654217D03*
X631462D03*
X912351Y644245D03*
X887351D03*
X912351Y644273D03*
X887351D03*
X912351Y654245D03*
X887351D03*
X912351Y654273D03*
X887351D03*
X922116Y644206D03*
X947116D03*
X922116Y644234D03*
X947116D03*
X922116Y654206D03*
X947116D03*
X922116Y654234D03*
X947116D03*
X1200877Y644262D03*
Y644234D03*
Y654262D03*
Y654234D03*
X1225877Y644262D03*
X1235614Y644236D03*
X1260614D03*
X1235614Y644264D03*
X1260614D03*
X1225877Y644234D03*
Y654262D03*
X1235614Y654236D03*
X1260614D03*
X1235614Y654264D03*
X1260614D03*
X1225877Y654234D03*
X1514375Y644292D03*
Y644264D03*
Y654292D03*
Y654264D03*
X1539375Y644292D03*
Y644264D03*
Y654292D03*
Y654264D03*
G54D129*
X1449933Y49950D03*
X1469689Y49000D03*
X1697872Y116423D03*
X1682141Y136233D03*
X1705138Y114470D03*
X1709277Y120700D03*
X1715318Y128300D03*
G54D174*
X1694000Y610000D03*
G54D54*
X95275Y217545D03*
X91626Y215364D03*
X85156Y212774D03*
X89386Y212744D03*
X87416Y215504D03*
X87542Y210043D03*
X83366Y215624D03*
X95140Y220946D03*
X91809Y221009D03*
X88447Y221136D03*
X85188Y221341D03*
X72074Y243282D03*
X65180Y243368D03*
X61800Y243400D03*
X68498Y243368D03*
X49560Y649770D03*
Y644670D03*
X54360D03*
X49560Y649570D03*
Y644670D03*
X54360D03*
X49560Y654670D03*
X54360D03*
X49560D03*
X54360D03*
X214820Y649570D03*
Y644670D03*
X210020D03*
X214820Y649770D03*
Y644670D03*
X210020D03*
X214820Y654670D03*
X210020D03*
X214820D03*
X210020D03*
X238282Y649670D03*
Y644770D03*
X243082D03*
X238282Y649870D03*
Y644770D03*
X243082D03*
X238282Y654770D03*
X243082D03*
X238282D03*
X243082D03*
X402404Y649650D03*
Y644550D03*
X397604D03*
X402404Y649450D03*
Y644550D03*
X397604D03*
X402404Y654550D03*
X397604D03*
X402404D03*
X397604D03*
X425750Y649400D03*
Y644500D03*
X430550D03*
X425750Y649600D03*
Y644500D03*
X430550D03*
X425750Y654500D03*
X430550D03*
X425750D03*
X430550D03*
X589871Y649379D03*
Y644279D03*
X585071D03*
X589872Y649180D03*
Y644280D03*
X585072D03*
X589871Y654279D03*
X585071D03*
X589872Y654280D03*
X585072D03*
X613298Y649331D03*
Y644231D03*
X618098D03*
X613298Y649131D03*
Y644231D03*
X618098D03*
X613298Y654231D03*
X618098D03*
X613298D03*
X618098D03*
X905515Y649159D03*
Y644259D03*
X900715D03*
X905515Y649359D03*
Y644259D03*
X900715D03*
X905515Y654259D03*
X900715D03*
X905515D03*
X900715D03*
X928952Y649120D03*
Y644220D03*
X933752D03*
X928952Y649320D03*
Y644220D03*
X933752D03*
X928952Y654220D03*
X933752D03*
X928952D03*
X933752D03*
X1219041Y649348D03*
Y644248D03*
X1214241D03*
X1219041Y649148D03*
Y644248D03*
X1214241D03*
X1219041Y654248D03*
X1214241D03*
X1219041D03*
X1214241D03*
X1242450Y649150D03*
Y644250D03*
X1247250D03*
X1242450Y649350D03*
Y644250D03*
X1247250D03*
X1242450Y654250D03*
X1247250D03*
X1242450D03*
X1247250D03*
X1527739Y644278D03*
D03*
Y654278D03*
D03*
X1532539Y649378D03*
Y644278D03*
Y649178D03*
Y644278D03*
Y654278D03*
D03*
G54D18*
X-17084Y467626D03*
X-16766Y500106D03*
X2934Y26933D03*
X23728Y18731D03*
X1826Y56447D03*
X47100Y327000D03*
X-5680Y524570D03*
X10932Y523601D03*
X14700Y517000D03*
X-7360Y512000D03*
X-2083Y513704D03*
X-1000Y479000D03*
X5689Y481983D03*
X27280Y510420D03*
X-6200Y505400D03*
X-6566Y568363D03*
X-9291Y535201D03*
X51090Y8080D03*
X53382Y-1173D03*
X91306Y157194D03*
X61356Y181000D03*
X61256Y186000D03*
X64187Y176332D03*
X104820Y195700D03*
X97800Y200800D03*
X86731Y189148D03*
X73500Y191500D03*
X97200Y265000D03*
X91600Y278700D03*
X53250Y302800D03*
X48550Y301650D03*
X64700Y310525D03*
X84300Y305700D03*
Y310700D03*
X61625Y283201D03*
X72904Y284898D03*
X84300Y289000D03*
X82050Y283951D03*
X77103Y283900D03*
X84866Y294213D03*
X84300Y299000D03*
X58600Y302700D03*
X72600Y310800D03*
X77500Y312500D03*
X53025Y337475D03*
X93500Y285000D03*
X101828Y371096D03*
X51923Y346164D03*
X60934Y362307D03*
X57395Y366795D03*
X55500Y371700D03*
X61914Y368731D03*
X60900Y348300D03*
X79100Y347000D03*
X49100Y354500D03*
X57800Y376100D03*
X60565Y380131D03*
X65000Y383000D03*
X74800Y379700D03*
X80200D03*
X62600Y375100D03*
X102160Y354780D03*
X101770Y363150D03*
X97472Y380934D03*
X71050Y478670D03*
X92326Y480398D03*
X115536Y213508D03*
X154130Y190186D03*
X162788Y200650D03*
X162800Y195600D03*
X150000Y199850D03*
Y194850D03*
X115525Y245372D03*
X115536Y277508D03*
Y309508D03*
Y341508D03*
X109500Y370000D03*
X206800Y246500D03*
X203947Y280933D03*
X206600Y372400D03*
X195233Y348402D03*
X239778Y274478D03*
X438187Y609864D03*
X579497Y202003D03*
X578980Y217884D03*
X592300Y220500D03*
X617400Y115800D03*
X605028Y119000D03*
X604977Y110200D03*
X606148Y229494D03*
X633410Y269610D03*
Y274610D03*
X656100Y275500D03*
X649800Y252600D03*
X652700Y270600D03*
X618279Y251393D03*
X632869Y293720D03*
X646520Y297400D03*
X657950Y296850D03*
X637681Y332390D03*
Y337390D03*
X620400Y463990D03*
X629600Y425100D03*
X622100Y417900D03*
X608800Y463475D03*
X609284Y480055D03*
X618800Y474500D03*
X619390Y469450D03*
X639120Y475620D03*
X608800Y468475D03*
Y473475D03*
X636500Y493924D03*
X627000Y478300D03*
X680200Y13100D03*
X714300Y-1900D03*
X724837Y13852D03*
X701525Y35610D03*
X720572Y88700D03*
X717420Y249920D03*
X679300Y261700D03*
X677800Y254100D03*
X667700Y275600D03*
X709949Y272647D03*
X706800Y278100D03*
X710700Y260200D03*
X723400Y250000D03*
X673922Y298078D03*
X686140Y298260D03*
X667900Y339000D03*
X710272Y281911D03*
X724000Y291700D03*
X705800Y301600D03*
X697521Y325500D03*
X697352Y335500D03*
Y330500D03*
X697120Y300349D03*
X678730Y362841D03*
X686619Y392600D03*
X691240Y390039D03*
X669194Y351206D03*
X674194D03*
X679194D03*
X684194D03*
X676900Y381800D03*
X679385Y388705D03*
X687427Y384926D03*
X721894Y501346D03*
X675080Y485570D03*
X696000Y496800D03*
X679700Y489400D03*
X686200Y511700D03*
X680000Y511800D03*
X711704Y525483D03*
X707850Y505700D03*
X680029Y577503D03*
X718200Y581000D03*
X713132Y609306D03*
X765144Y213508D03*
X759700Y232000D03*
X739500Y247500D03*
X749126Y220843D03*
X742897Y226773D03*
X739400Y253400D03*
X730000Y254675D03*
X754263Y254207D03*
X754846Y276340D03*
X765144Y245508D03*
X749090Y270250D03*
X765144Y277508D03*
X757956Y328095D03*
X729405Y290725D03*
X743600Y304100D03*
X737750Y298894D03*
X737912Y315500D03*
X764980Y287980D03*
X765144Y309508D03*
Y341508D03*
X760500Y359800D03*
X767155Y385550D03*
X764159Y373743D03*
X799620Y186547D03*
X798337Y181216D03*
X813700Y198900D03*
X804470Y186814D03*
X1248616Y133817D03*
X1261800Y154973D03*
X1262569Y147201D03*
X1252000Y145300D03*
X1252437Y140192D03*
X1260737Y133877D03*
X1251980Y106960D03*
X1250200Y122900D03*
X1240010Y144754D03*
X1257800Y120800D03*
X1220580Y179810D03*
X1323000Y83000D03*
X1335120Y94450D03*
X1337400Y72000D03*
X1328500Y92500D03*
X1336900Y61600D03*
X1281799Y193190D03*
X1306585Y258250D03*
X1308887Y285015D03*
X1316600Y305500D03*
X1336336Y333825D03*
X1332600Y506300D03*
X1379025Y-9799D03*
X1348945Y40264D03*
X1370975Y67225D03*
X1343260Y53770D03*
X1351488Y74000D03*
X1358500Y74500D03*
X1347500Y83000D03*
X1357000Y86640D03*
X1383171Y57549D03*
X1379110Y45033D03*
X1392149Y68006D03*
X1371910Y48800D03*
X1370849Y59349D03*
X1380500Y50500D03*
X1372300Y86400D03*
X1363500Y77400D03*
X1403264Y82000D03*
X1345257Y100000D03*
X1348615Y96239D03*
X1353500Y96959D03*
X1345500Y107529D03*
X1364700Y96440D03*
X1373850Y120450D03*
X1396470Y330014D03*
X1381431Y284259D03*
X1383700Y392300D03*
X1388900Y387800D03*
X1380872Y378098D03*
X1347081Y507919D03*
X1390500Y539000D03*
X1383074Y581963D03*
X1398010Y590040D03*
X1407422Y13139D03*
X1455347Y92065D03*
X1457000Y82000D03*
X1452232Y109500D03*
X1457300Y373600D03*
X1420075Y378375D03*
Y393402D03*
Y383375D03*
Y388402D03*
X1413735Y396302D03*
Y391302D03*
X1448000Y431500D03*
X1431900Y453500D03*
X1447500Y448000D03*
X1431900Y442600D03*
X1448000Y437000D03*
X1431900Y448000D03*
X1447700Y442500D03*
X1431900Y437100D03*
X1436358Y525142D03*
X1451533Y527867D03*
X1413600Y531300D03*
X1432560Y561160D03*
X1428791Y535512D03*
X1419600Y531500D03*
X1453533Y532667D03*
X1426870Y530800D03*
X1423800Y534800D03*
X1421560Y563455D03*
X1415582Y562904D03*
X1439822Y537382D03*
X1428281Y546119D03*
X1429026Y541026D03*
X1410950Y589670D03*
X1499875Y90481D03*
X1524000Y123300D03*
X1490674Y98787D03*
X1498810Y108290D03*
X1526813Y108958D03*
X1526513Y115769D03*
X1500455Y114388D03*
X1496726Y120588D03*
X1473100Y128950D03*
X1514425Y137980D03*
X1526310Y142190D03*
X1485755Y131671D03*
X1500806Y133339D03*
X1526744Y98265D03*
X1483366Y115902D03*
X1498660Y102746D03*
X1520150Y127600D03*
X1502165Y251200D03*
X1505946Y254432D03*
X1498600Y334800D03*
X1467262Y420711D03*
X1503400Y524663D03*
X1563200Y3400D03*
X1543500D03*
X1577269Y95344D03*
X1530101Y132671D03*
X1541765Y114000D03*
X1541831Y149030D03*
X1558042Y172448D03*
X1545802Y233529D03*
X1575645Y320664D03*
X1565244Y300934D03*
X1568524Y312885D03*
X1582800Y312100D03*
X1564400Y308383D03*
X1587032Y350996D03*
X1585155Y538574D03*
X1579680Y610279D03*
X1545407Y598393D03*
X1632006Y94500D03*
X1643500Y80400D03*
X1621100Y69600D03*
X1597987Y79500D03*
X1630826Y88087D03*
X1594452Y111377D03*
X1603300Y185100D03*
X1639258Y185620D03*
X1647852Y197374D03*
X1635621Y208259D03*
X1606849Y241210D03*
X1643775Y246137D03*
X1632128Y225472D03*
X1622000Y279495D03*
X1620159Y332004D03*
X1625400Y327667D03*
X1608764Y322440D03*
X1621800Y386300D03*
Y381500D03*
X1630800Y378500D03*
X1640266Y365500D03*
Y360500D03*
X1590154Y354762D03*
X1590037Y432515D03*
X1590581Y404170D03*
X1639113Y496734D03*
X1598700Y479225D03*
X1617771Y498714D03*
X1629530Y496374D03*
X1629500Y491500D03*
X1639271Y491135D03*
X1625094Y555200D03*
X1603919Y592750D03*
X1650869Y614200D03*
Y609200D03*
X1678400Y103000D03*
X1691439Y174354D03*
X1677600Y172700D03*
X1707100Y188300D03*
X1664390Y201163D03*
X1659643Y213505D03*
X1676924Y196731D03*
X1671688Y182925D03*
X1680769Y242605D03*
X1664762Y440735D03*
X1676041Y458884D03*
X1660834Y404934D03*
X1651754Y488025D03*
X1684650Y505200D03*
X1672159Y494042D03*
X1701617Y482706D03*
X1676800Y483800D03*
X1660680Y586750D03*
X1658369Y602250D03*
X1652499Y597950D03*
X1749085Y9177D03*
X1715100Y70500D03*
X1722251Y250532D03*
X1766077Y232681D03*
X1751900Y249700D03*
X1746900Y249804D03*
X1749462Y232955D03*
X1719560Y501770D03*
X1743000Y570000D03*
X1765300Y574700D03*
X1742381Y588530D03*
X1815150Y26650D03*
X1797700Y21018D03*
X1791500Y26918D03*
X1813795Y12165D03*
X1808795D03*
X1828874Y-13520D03*
X1819837Y21700D03*
X1786865Y22375D03*
X1829888Y10735D03*
X1817352Y36909D03*
X1812352Y36949D03*
X1797700Y36804D03*
X1792700Y36871D03*
X1794100Y70898D03*
X1807818Y124179D03*
X1827500Y144900D03*
X1809810Y155858D03*
X1790100Y154000D03*
X1807440Y165530D03*
X1836100Y179700D03*
X1807440Y169030D03*
Y162030D03*
X1826682Y196841D03*
X1784878Y496701D03*
X1825900Y523500D03*
X1832200Y567760D03*
X1831500Y544500D03*
X1831800Y552300D03*
X1809600Y582800D03*
X1793100Y578500D03*
X1816020Y571448D03*
X1812802Y578693D03*
X1829051Y591299D03*
X1822273Y595046D03*
X1788290Y612006D03*
X1838500Y40400D03*
X1856333Y34518D03*
X1894855Y142122D03*
X1893640Y147042D03*
X1888639D03*
X1887497Y105444D03*
X1881165Y105561D03*
X1886000Y156700D03*
X1885102Y101134D03*
X1876001Y105438D03*
X1861932Y146431D03*
X1869668Y146750D03*
X1848532Y144360D03*
X1897507Y124450D03*
X1883800Y210575D03*
X1854868Y184667D03*
X1836900Y165800D03*
X1889400Y191200D03*
X1896710Y194380D03*
X1847200Y202050D03*
X1840900Y179700D03*
X1845700D03*
X1858686Y180377D03*
X1885465Y166285D03*
X1855000Y167100D03*
X1864170Y211869D03*
X1892791Y200069D03*
X1884000Y188100D03*
X1865100Y174600D03*
X1846517Y253500D03*
X1854720Y253700D03*
X1863137Y452710D03*
X1867500Y447900D03*
X1837857Y468630D03*
X1842857D03*
X1868167Y467855D03*
X1863000Y480000D03*
X1859600Y476200D03*
X1876945Y471316D03*
X1877407Y479046D03*
X1855206Y471112D03*
X1839126Y583354D03*
X1847070Y537610D03*
X1914690Y152580D03*
X1929736Y128337D03*
X1899855Y142122D03*
X1909216Y142812D03*
X1908327Y149353D03*
X1923800Y151000D03*
X1916310Y149676D03*
X1919514Y131701D03*
X1943660Y98180D03*
X1940500Y157600D03*
X1925400Y196300D03*
X1909438Y204307D03*
X1929700Y163400D03*
X1940240Y169970D03*
X1931065Y175520D03*
X1927500Y170400D03*
X1929000Y158600D03*
X1939400Y198400D03*
X1929090Y193190D03*
X1933100Y436200D03*
X1957063Y474769D03*
X1948200Y474300D03*
X1900890Y477200D03*
G54D165*
X1629039Y580079D03*
X1626087Y585591D03*
X1629039Y565118D03*
X1626087Y570630D03*
X1637898Y580079D03*
X1634945Y585591D03*
X1637898Y565118D03*
X1634945Y570630D03*
X1643803D03*
X1646756Y565118D03*
Y580079D03*
X1643803Y585591D03*
X1640850Y582835D03*
X1631992D03*
X1623134D03*
X1640850Y567874D03*
X1631992D03*
X1623134D03*
X1646756Y610000D03*
Y595039D03*
X1643803Y600551D03*
Y615512D03*
X1629039Y610000D03*
X1626087Y615512D03*
X1629039Y595039D03*
X1626087Y600551D03*
X1637898Y610000D03*
X1634945Y615512D03*
X1637898Y595039D03*
X1634945Y600551D03*
X1623134Y612756D03*
X1640850Y597795D03*
X1631992D03*
X1623134D03*
X1640850Y612756D03*
X1631992D03*
X1676283Y580079D03*
X1673331Y585591D03*
X1676283Y565118D03*
X1673331Y570630D03*
X1685142Y580079D03*
X1682189Y585591D03*
X1685142Y565118D03*
X1682189Y570630D03*
X1691047D03*
X1694000Y565118D03*
Y580079D03*
X1691047Y585591D03*
X1688094Y582835D03*
X1679236D03*
X1670378D03*
X1688094Y567874D03*
X1679236D03*
X1670378D03*
X1694000Y595039D03*
X1691047Y600551D03*
Y615512D03*
X1676283Y610000D03*
X1673331Y615512D03*
X1676283Y595039D03*
X1673331Y600551D03*
X1685142Y610000D03*
X1682189Y615512D03*
X1685142Y595039D03*
X1682189Y600551D03*
X1688094Y612756D03*
X1679236D03*
X1670378D03*
X1688094Y597795D03*
X1679236D03*
X1670378D03*
G54D36*
X48700Y255780D03*
X29000D03*
G54D138*
X1458271Y446520D03*
G54D147*
X1467570Y481702D03*
X1473246Y482312D03*
G54D81*
X388187Y-5822D03*
Y31978D03*
Y13078D03*
Y69778D03*
Y50878D03*
Y88678D03*
Y514079D03*
Y532955D03*
Y570755D03*
Y589679D03*
Y551879D03*
Y608555D03*
X1037797Y-5822D03*
Y31978D03*
Y13078D03*
Y69778D03*
Y88678D03*
Y50878D03*
Y514079D03*
Y570755D03*
Y532955D03*
Y589679D03*
Y551879D03*
Y608555D03*
G54D238*
G01X146394Y-42265D02*
X439822D01*
G02Y-45915I0J-1825D01*
G01X144165D01*
X140500Y-42250D01*
G01X130313Y22133D02*
Y17157D01*
G01X160431Y22133D02*
Y17157D01*
G01X163777Y4023D02*
Y11814D01*
X163477Y12114D01*
G01X133659Y4023D02*
Y9433D01*
X132959Y10133D01*
Y12114D01*
G01X153738Y22133D02*
Y17157D01*
G01X157084Y4023D02*
Y12114D01*
G01X123620Y22133D02*
Y17157D01*
G01X126666Y12114D02*
X126966Y11814D01*
Y4023D01*
G01X147045Y22133D02*
Y17157D01*
G01X150392Y4023D02*
X150391Y4024D01*
Y12114D01*
G01X167124Y22133D02*
Y17157D01*
G01X170470Y4023D02*
Y9433D01*
X169770Y10133D01*
Y12114D01*
G01X140352Y4023D02*
Y7555D01*
X139356Y8551D01*
Y11990D01*
X141880Y14514D01*
G01X140352Y22133D02*
Y19547D01*
X138606Y17801D01*
Y16400D01*
X139306Y15700D01*
Y14400D01*
X138440Y13534D01*
X137546D01*
X136780Y14300D01*
G01X143699Y4023D02*
Y9993D01*
X144406Y10700D01*
Y12470D01*
X143856Y13020D01*
X142986D01*
X141880Y11914D01*
G01X137006Y22133D02*
Y19701D01*
X135210Y17905D01*
X134906Y17384D01*
Y13858D01*
X135250Y13230D01*
X136780Y11700D01*
G01X130313Y92757D02*
Y97733D01*
G01X160431Y92757D02*
Y97733D01*
G01X163777Y79623D02*
Y87414D01*
X163477Y87714D01*
G01X133659Y79623D02*
Y85033D01*
X132959Y85733D01*
Y87714D01*
G01X153738Y92757D02*
Y97733D01*
G01X157084Y87714D02*
Y79623D01*
G01X123620Y92757D02*
Y97733D01*
G01X126966Y79623D02*
Y87414D01*
X126666Y87714D01*
G01X147045Y92757D02*
Y97733D01*
G01X150392Y79623D02*
X150391Y79624D01*
Y87714D01*
G01X167124Y92757D02*
Y97733D01*
G01X170470Y79623D02*
Y85033D01*
X169770Y85733D01*
Y87714D01*
G01X140352Y79623D02*
Y83195D01*
X139848Y83699D01*
Y84699D01*
X138848Y85699D01*
Y87000D01*
X140248Y88400D01*
X140994D01*
X141880Y87514D01*
G01X140352Y97733D02*
X140353Y97732D01*
Y95148D01*
X138606Y93401D01*
Y92000D01*
X139306Y91300D01*
Y90000D01*
X138440Y89134D01*
X137546D01*
X136780Y89900D01*
G01X143699Y79623D02*
Y84151D01*
X143848Y84300D01*
Y89100D01*
X142834Y90114D01*
X141880D01*
G01X137006Y97733D02*
Y95301D01*
X135210Y93505D01*
X134906Y92984D01*
Y89458D01*
X135250Y88830D01*
X136780Y87300D01*
G01X130313Y54957D02*
Y59933D01*
G01X160431D02*
Y54957D01*
G01X163777Y41823D02*
Y49614D01*
X163477Y49914D01*
G01X133659Y41823D02*
Y47233D01*
X132959Y47933D01*
Y49914D01*
G01X153738Y59933D02*
Y54957D01*
G01X157084Y41823D02*
Y49914D01*
G01X123620Y59933D02*
Y54957D01*
G01X126966Y41823D02*
Y47527D01*
X126666Y47827D01*
Y49914D01*
G01X147045Y59933D02*
Y54957D01*
G01X150392Y41823D02*
Y43743D01*
X150391Y43744D01*
Y49914D01*
G01X167124Y59933D02*
Y54957D01*
G01X170470Y41823D02*
Y47123D01*
X169770Y47823D01*
Y49914D01*
G01X140352Y41823D02*
Y45355D01*
X139356Y46351D01*
Y49790D01*
X141880Y52314D01*
G01X140352Y59933D02*
Y57347D01*
X138606Y55601D01*
Y54200D01*
X139306Y53500D01*
Y52200D01*
X138440Y51334D01*
X137546D01*
X136780Y52100D01*
G01X143699Y41823D02*
Y43199D01*
X143698Y43200D01*
Y47792D01*
X144406Y48500D01*
Y50270D01*
X143856Y50820D01*
X142986D01*
X141880Y49714D01*
G01X137006Y59933D02*
Y57501D01*
X135210Y55705D01*
X134906Y55184D01*
Y51658D01*
X135250Y51030D01*
X136780Y49500D01*
G01X130313Y523134D02*
Y518157D01*
G01X160431Y523134D02*
Y518157D01*
G01X163777Y505024D02*
Y512814D01*
X163477Y513114D01*
G01X133659Y505024D02*
Y510433D01*
X132959Y511133D01*
Y513114D01*
G01X153738Y523134D02*
Y518157D01*
G01X157084Y505024D02*
Y513114D01*
G01X123620Y523134D02*
Y518157D01*
G01X126966Y505024D02*
Y512814D01*
X126666Y513114D01*
G01X147045Y523134D02*
Y518157D01*
G01X150392Y505024D02*
X150391D01*
Y513114D01*
G01X167124Y523134D02*
Y518157D01*
G01X170470Y505024D02*
Y510433D01*
X169770Y511133D01*
Y513114D01*
G01X140352Y505024D02*
Y508595D01*
X139848Y509099D01*
Y510099D01*
X138848Y511099D01*
Y512400D01*
X140248Y513800D01*
X140994D01*
X141880Y512914D01*
G01X140352Y523134D02*
X140353Y523132D01*
Y520548D01*
X138606Y518801D01*
Y517400D01*
X139306Y516700D01*
Y515400D01*
X138440Y514534D01*
X137546D01*
X136780Y515300D01*
G01X143699Y505024D02*
Y509551D01*
X143848Y509700D01*
Y514500D01*
X142834Y515514D01*
X141880D01*
G01X137006Y523134D02*
Y520701D01*
X135210Y518905D01*
X134906Y518384D01*
Y514858D01*
X135250Y514230D01*
X136780Y512700D01*
G01X130313Y560934D02*
Y555957D01*
G01X160431Y560934D02*
Y555957D01*
G01X163777Y542824D02*
Y550614D01*
X163477Y550914D01*
G01X133659Y542824D02*
Y548233D01*
X132959Y548933D01*
Y550914D01*
G01X153738Y560934D02*
Y555957D01*
G01X157084Y542824D02*
Y550914D01*
G01X123620Y560934D02*
Y555957D01*
G01X126966Y542824D02*
Y550614D01*
X126666Y550914D01*
G01X147045Y560934D02*
Y555957D01*
G01X150392Y542824D02*
X150391D01*
Y550914D01*
G01X167124Y560934D02*
Y555957D01*
G01X170470Y542824D02*
Y548233D01*
X169770Y548933D01*
Y550914D01*
G01X140352Y542824D02*
Y546395D01*
X139848Y546899D01*
Y547899D01*
X138848Y548899D01*
Y550200D01*
X140248Y551600D01*
X140994D01*
X141880Y550714D01*
G01X140352Y560934D02*
X140353Y560932D01*
Y558348D01*
X138606Y556601D01*
Y555200D01*
X139306Y554500D01*
Y553200D01*
X138440Y552334D01*
X137546D01*
X136780Y553100D01*
G01X143699Y542824D02*
Y547351D01*
X143848Y547500D01*
Y552300D01*
X142834Y553314D01*
X141880D01*
G01X137006Y560934D02*
Y558501D01*
X135210Y556705D01*
X134906Y556184D01*
Y552658D01*
X135250Y552030D01*
X136780Y550500D01*
G01X163777Y580624D02*
Y588414D01*
X163477Y588714D01*
G01X133659Y580624D02*
Y586033D01*
X132959Y586733D01*
Y588714D01*
G01X157084Y580624D02*
Y588714D01*
G01X126966Y580624D02*
Y588414D01*
X126666Y588714D01*
G01X150392Y580624D02*
X150391D01*
Y588714D01*
G01X170470Y580624D02*
Y586033D01*
X169770Y586733D01*
Y588714D01*
G01X140352Y580624D02*
Y584195D01*
X139848Y584699D01*
Y585699D01*
X138848Y586699D01*
Y588000D01*
X140248Y589400D01*
X140994D01*
X141880Y588514D01*
G01X143699Y580624D02*
Y585151D01*
X143848Y585300D01*
Y590100D01*
X142834Y591114D01*
X141880D01*
G01X137006Y598734D02*
Y596301D01*
X135210Y594505D01*
X134906Y593984D01*
Y590458D01*
X135250Y589830D01*
X136780Y588300D01*
G01X130313Y598734D02*
Y593757D01*
G01X160431Y598734D02*
Y593757D01*
G01X153738Y598734D02*
Y593757D01*
G01X123620Y598734D02*
Y593757D01*
G01X147045Y598734D02*
Y593757D01*
G01X167124Y598734D02*
Y593757D01*
G01X140352Y598734D02*
X140353Y598732D01*
Y596148D01*
X138606Y594401D01*
Y593000D01*
X139306Y592300D01*
Y591000D01*
X138440Y590134D01*
X137546D01*
X136780Y590900D01*
G01X190549Y22133D02*
Y17157D01*
G01X193896Y4023D02*
X193895Y4024D01*
Y12114D01*
G01X183856Y22133D02*
Y17157D01*
G01X187203Y4023D02*
X187202Y4024D01*
Y12114D01*
G01X203935Y22133D02*
Y17157D01*
G01X207281Y4023D02*
Y9433D01*
X206581Y10133D01*
Y12114D01*
G01X227360Y22133D02*
Y17157D01*
G01X230707Y4023D02*
X230706Y4024D01*
Y12114D01*
G01X197242Y22133D02*
Y17157D01*
G01X200588Y4023D02*
Y11814D01*
X200288Y12114D01*
G01X220667Y22133D02*
Y17157D01*
G01X224014Y4023D02*
X224013Y4024D01*
Y12114D01*
G01X177163Y22133D02*
Y19547D01*
X175417Y17801D01*
Y16400D01*
X176117Y15700D01*
Y14400D01*
X175251Y13534D01*
X174357D01*
X173591Y14300D01*
G01X213974Y22133D02*
Y19547D01*
X212228Y17801D01*
Y16400D01*
X212928Y15700D01*
Y14400D01*
X212062Y13534D01*
X211168D01*
X210402Y14300D01*
G01X177163Y4023D02*
Y7555D01*
X176167Y8551D01*
Y11990D01*
X178691Y14514D01*
G01X213974Y4023D02*
Y7555D01*
X212978Y8551D01*
Y11990D01*
X215502Y14514D01*
G01X173817Y22133D02*
Y19701D01*
X172021Y17905D01*
X171717Y17384D01*
Y13858D01*
X172061Y13230D01*
X173591Y11700D01*
G01X210628Y22133D02*
Y19701D01*
X208832Y17905D01*
X208528Y17384D01*
Y13858D01*
X208872Y13230D01*
X210402Y11700D01*
G01X180510Y4023D02*
Y9993D01*
X181217Y10700D01*
Y12470D01*
X180667Y13020D01*
X179797D01*
X178691Y11914D01*
G01X217321Y4023D02*
Y9993D01*
X218028Y10700D01*
Y12470D01*
X217478Y13020D01*
X216608D01*
X215502Y11914D01*
G01X190549Y92757D02*
Y97733D01*
G01X193896Y79623D02*
X193895Y79624D01*
Y87714D01*
G01X183856Y92757D02*
Y97733D01*
G01X187203Y79623D02*
X187202Y79624D01*
Y87714D01*
G01X203935Y92757D02*
Y97733D01*
G01X207281Y79623D02*
Y85033D01*
X206581Y85733D01*
Y87714D01*
G01X227360Y92757D02*
Y97733D01*
G01X230707Y79623D02*
X230706Y79624D01*
Y87714D01*
G01X197242Y92757D02*
Y97733D01*
G01X200588Y79623D02*
Y87414D01*
X200288Y87714D01*
G01X220667Y92761D02*
Y97733D01*
G01X224014Y79623D02*
X224013Y79624D01*
Y87714D01*
G01X177163Y97733D02*
X177164Y97732D01*
Y95148D01*
X175417Y93401D01*
Y92000D01*
X176117Y91300D01*
Y90000D01*
X175251Y89134D01*
X174357D01*
X173591Y89900D01*
G01X213974Y97733D02*
X213975Y97732D01*
Y95148D01*
X212228Y93401D01*
Y92000D01*
X212928Y91300D01*
Y90000D01*
X212062Y89134D01*
X211168D01*
X210402Y89900D01*
G01X177163Y79623D02*
Y83195D01*
X176659Y83699D01*
Y84699D01*
X175659Y85699D01*
Y87000D01*
X177059Y88400D01*
X177805D01*
X178691Y87514D01*
G01X213974Y79623D02*
Y83195D01*
X213470Y83699D01*
Y84699D01*
X212470Y85699D01*
Y87000D01*
X213870Y88400D01*
X214616D01*
X215502Y87514D01*
G01X173817Y97733D02*
Y95301D01*
X172021Y93505D01*
X171717Y92984D01*
Y89458D01*
X172061Y88830D01*
X173591Y87300D01*
G01X210628Y97733D02*
Y95301D01*
X208832Y93505D01*
X208528Y92984D01*
Y89458D01*
X208872Y88830D01*
X210402Y87300D01*
G01X180510Y79623D02*
Y84151D01*
X180659Y84300D01*
Y89100D01*
X179645Y90114D01*
X178691D01*
G01X217321Y79623D02*
Y84151D01*
X217470Y84300D01*
Y89100D01*
X216456Y90114D01*
X215502D01*
G01X190549Y59933D02*
Y54957D01*
G01X193896Y41823D02*
Y42543D01*
X193895Y42544D01*
Y49914D01*
G01X183856Y59933D02*
Y54957D01*
G01X187203Y41823D02*
Y42443D01*
X187202Y42444D01*
Y49914D01*
G01X203935Y59933D02*
Y54957D01*
G01X207281Y41823D02*
Y47233D01*
X206581Y47933D01*
Y49914D01*
G01X227360Y59933D02*
Y54957D01*
G01X230707Y41823D02*
Y42843D01*
X230706Y42844D01*
Y49914D01*
G01X197242Y59933D02*
Y54957D01*
G01X200588Y41823D02*
Y49614D01*
X200288Y49914D01*
G01X220667Y59933D02*
Y54957D01*
G01X224014Y41823D02*
Y43743D01*
X224013Y43744D01*
Y49914D01*
G01X177163Y59933D02*
Y57347D01*
X175417Y55601D01*
Y54200D01*
X176117Y53500D01*
Y52200D01*
X175251Y51334D01*
X174357D01*
X173591Y52100D01*
G01X213974Y59933D02*
Y57347D01*
X212228Y55601D01*
Y54200D01*
X212928Y53500D01*
Y52200D01*
X212062Y51334D01*
X211168D01*
X210402Y52100D01*
G01X177163Y41823D02*
Y45355D01*
X176167Y46351D01*
Y49790D01*
X178691Y52314D01*
G01X213974Y41823D02*
Y45355D01*
X212978Y46351D01*
Y49790D01*
X215502Y52314D01*
G01X173817Y59933D02*
Y57501D01*
X172021Y55705D01*
X171717Y55184D01*
Y51658D01*
X172061Y51030D01*
X173591Y49500D01*
G01X210628Y59933D02*
Y57501D01*
X208832Y55705D01*
X208528Y55184D01*
Y51658D01*
X208872Y51030D01*
X210402Y49500D01*
G01X180510Y41823D02*
Y43199D01*
X180509Y43200D01*
Y47016D01*
X181217Y47724D01*
Y50270D01*
X180667Y50820D01*
X179797D01*
X178691Y49714D01*
G01X217321Y41823D02*
Y43199D01*
X217320Y43200D01*
Y47792D01*
X218028Y48500D01*
Y50270D01*
X217478Y50820D01*
X216608D01*
X215502Y49714D01*
G01X190549Y523134D02*
Y518157D01*
G01X193896Y505024D02*
X193895D01*
Y513114D01*
G01X183856Y523134D02*
Y518157D01*
G01X187203Y505024D02*
X187202D01*
Y513114D01*
G01X203935Y523134D02*
Y518157D01*
G01X207281Y505024D02*
Y510433D01*
X206581Y511133D01*
Y513114D01*
G01X227360Y523134D02*
Y518157D01*
G01X230707Y505024D02*
X230706D01*
Y513114D01*
G01X197242Y523134D02*
Y518157D01*
G01X200588Y505024D02*
Y512814D01*
X200288Y513114D01*
G01X220667Y523134D02*
Y518161D01*
G01X224014Y505024D02*
X224013D01*
Y513114D01*
G01X177163Y523134D02*
Y520547D01*
X175417Y518801D01*
Y517400D01*
X176117Y516700D01*
Y515400D01*
X175251Y514534D01*
X174357D01*
X173591Y515300D01*
G01X213974Y523134D02*
X213975Y523132D01*
Y520548D01*
X212228Y518801D01*
Y517400D01*
X212928Y516700D01*
Y515400D01*
X212062Y514534D01*
X211168D01*
X210402Y515300D01*
G01X177163Y505024D02*
Y508595D01*
X176659Y509099D01*
Y510099D01*
X175659Y511099D01*
Y512400D01*
X177059Y513800D01*
X177805D01*
X178691Y512914D01*
G01X213974Y505024D02*
Y508595D01*
X213470Y509099D01*
Y510099D01*
X212470Y511099D01*
Y512400D01*
X213870Y513800D01*
X214616D01*
X215502Y512914D01*
G01X173817Y523134D02*
Y520701D01*
X172021Y518905D01*
X171717Y518384D01*
Y514858D01*
X172061Y514230D01*
X173591Y512700D01*
G01X210628Y523134D02*
Y520701D01*
X208832Y518905D01*
X208528Y518384D01*
Y514858D01*
X208872Y514230D01*
X210402Y512700D01*
G01X180510Y505024D02*
Y509551D01*
X180659Y509700D01*
Y514500D01*
X179645Y515514D01*
X178691D01*
G01X217321Y505024D02*
Y509551D01*
X217470Y509700D01*
Y514500D01*
X216456Y515514D01*
X215502D01*
G01X190549Y560934D02*
Y555957D01*
G01X193896Y542824D02*
X193895D01*
Y550914D01*
G01X183856Y560934D02*
Y555957D01*
G01X187203Y542824D02*
X187202D01*
Y550914D01*
G01X203935Y560934D02*
Y555957D01*
G01X207281Y542824D02*
Y548233D01*
X206581Y548933D01*
Y550914D01*
G01X227360Y560934D02*
Y555957D01*
G01X230707Y542824D02*
X230706D01*
Y550914D01*
G01X197242Y560934D02*
Y555957D01*
G01X200588Y542824D02*
Y550614D01*
X200288Y550914D01*
G01X220667Y560934D02*
Y555961D01*
G01X224014Y542824D02*
X224013D01*
Y550914D01*
G01X177163Y560934D02*
Y558347D01*
X175417Y556601D01*
Y555200D01*
X176117Y554500D01*
Y553200D01*
X175251Y552334D01*
X174357D01*
X173591Y553100D01*
G01X213974Y560934D02*
X213975Y560932D01*
Y558348D01*
X212228Y556601D01*
Y555200D01*
X212928Y554500D01*
Y553200D01*
X212062Y552334D01*
X211168D01*
X210402Y553100D01*
G01X177163Y542824D02*
Y546395D01*
X176659Y546899D01*
Y547899D01*
X175659Y548899D01*
Y550200D01*
X177059Y551600D01*
X177805D01*
X178691Y550714D01*
G01X213974Y542824D02*
Y546395D01*
X213470Y546899D01*
Y547899D01*
X212470Y548899D01*
Y550200D01*
X213870Y551600D01*
X214616D01*
X215502Y550714D01*
G01X173817Y560934D02*
Y558501D01*
X172021Y556705D01*
X171717Y556184D01*
Y552658D01*
X172061Y552030D01*
X173591Y550500D01*
G01X210628Y560934D02*
Y558501D01*
X208832Y556705D01*
X208528Y556184D01*
Y552658D01*
X208872Y552030D01*
X210402Y550500D01*
G01X180510Y542824D02*
Y547351D01*
X180659Y547500D01*
Y552300D01*
X179645Y553314D01*
X178691D01*
G01X217321Y542824D02*
Y547351D01*
X217470Y547500D01*
Y552300D01*
X216456Y553314D01*
X215502D01*
G01X193896Y580624D02*
X193895D01*
Y588714D01*
G01X187203Y580624D02*
X187202D01*
Y588714D01*
G01X207281Y580624D02*
Y586033D01*
X206581Y586733D01*
Y588714D01*
G01X230707Y580624D02*
X230706D01*
Y588714D01*
G01X200588Y580624D02*
Y588414D01*
X200288Y588714D01*
G01X224014Y580624D02*
X224013D01*
Y588714D01*
G01X177163Y580624D02*
Y584195D01*
X176659Y584699D01*
Y585699D01*
X175659Y586699D01*
Y588000D01*
X177059Y589400D01*
X177805D01*
X178691Y588514D01*
G01X213974Y580624D02*
Y584195D01*
X213470Y584699D01*
Y585699D01*
X212470Y586699D01*
Y588000D01*
X213870Y589400D01*
X214616D01*
X215502Y588514D01*
G01X173817Y598734D02*
Y596301D01*
X172021Y594505D01*
X171717Y593984D01*
Y590458D01*
X172061Y589830D01*
X173591Y588300D01*
G01X210628Y598734D02*
Y596301D01*
X208832Y594505D01*
X208528Y593984D01*
Y590458D01*
X208872Y589830D01*
X210402Y588300D01*
G01X180510Y580624D02*
Y585151D01*
X180659Y585300D01*
Y590100D01*
X179645Y591114D01*
X178691D01*
G01X217321Y580624D02*
Y585151D01*
X217470Y585300D01*
Y590100D01*
X216456Y591114D01*
X215502D01*
G01X190549Y598734D02*
Y593757D01*
G01X183856Y598734D02*
Y593757D01*
G01X203935Y598734D02*
Y593757D01*
G01X227360Y598734D02*
Y593757D01*
G01X197242Y598734D02*
Y593757D01*
G01X220667Y598734D02*
Y593761D01*
G01X177163Y598734D02*
Y596147D01*
X175417Y594401D01*
Y593000D01*
X176117Y592300D01*
Y591000D01*
X175251Y590134D01*
X174357D01*
X173591Y590900D01*
G01X213974Y598734D02*
X213975Y598732D01*
Y596148D01*
X212228Y594401D01*
Y593000D01*
X212928Y592300D01*
Y591000D01*
X212062Y590134D01*
X211168D01*
X210402Y590900D01*
G01X240746Y22133D02*
Y17157D01*
G01X244092Y4023D02*
Y9433D01*
X243392Y10133D01*
Y12114D01*
G01X264171Y22133D02*
Y17157D01*
G01X267518Y4023D02*
X267517Y4024D01*
Y12114D01*
G01X234053Y22133D02*
Y17157D01*
G01X237399Y4023D02*
Y11814D01*
X237099Y12114D01*
G01X257478Y22133D02*
Y17157D01*
G01X260825Y4023D02*
X260824Y4024D01*
Y12114D01*
G01X250785Y22133D02*
Y19547D01*
X249039Y17801D01*
Y16400D01*
X249739Y15700D01*
Y14400D01*
X248873Y13534D01*
X247979D01*
X247213Y14300D01*
G01X287596Y22133D02*
Y19547D01*
X285850Y17801D01*
Y16400D01*
X286550Y15700D01*
Y14400D01*
X285684Y13534D01*
X284790D01*
X284024Y14300D01*
G01X250785Y4023D02*
Y7555D01*
X249789Y8551D01*
Y11990D01*
X252313Y14514D01*
G01X287596Y4023D02*
Y7555D01*
X286600Y8551D01*
Y11990D01*
X289124Y14514D01*
G01X247439Y22133D02*
Y19701D01*
X245643Y17905D01*
X245339Y17384D01*
Y13858D01*
X245683Y13230D01*
X247213Y11700D01*
G01X284250Y22133D02*
Y19701D01*
X282454Y17905D01*
X282150Y17384D01*
Y13858D01*
X282494Y13230D01*
X284024Y11700D01*
G01X254132Y4023D02*
Y9993D01*
X254839Y10700D01*
Y12470D01*
X254289Y13020D01*
X253419D01*
X252313Y11914D01*
G01X290943Y4023D02*
Y9991D01*
X290942Y9992D01*
X291650Y10700D01*
Y12470D01*
X291100Y13020D01*
X290230D01*
X289124Y11914D01*
G01X277557Y22133D02*
Y17157D01*
G01X280903Y4023D02*
Y9433D01*
X280203Y10133D01*
Y12114D01*
G01X270864Y22133D02*
Y17157D01*
G01X274210Y4023D02*
Y11814D01*
X273910Y12114D01*
G01X240746Y92757D02*
Y97733D01*
G01X244092Y79623D02*
Y85033D01*
X243392Y85733D01*
Y87714D01*
G01X264171Y92757D02*
Y97733D01*
G01X267518Y79623D02*
X267517Y79624D01*
Y87714D01*
G01X234053Y92757D02*
Y97733D01*
G01X237399Y79623D02*
Y87414D01*
X237099Y87714D01*
G01X257478Y92757D02*
Y97733D01*
G01X260825Y79623D02*
X260824Y79624D01*
Y87714D01*
G01X250785Y97733D02*
X250786Y97732D01*
Y95148D01*
X249039Y93401D01*
Y92000D01*
X249739Y91300D01*
Y90000D01*
X248873Y89134D01*
X247979D01*
X247213Y89900D01*
G01X287596Y97733D02*
X287597Y97732D01*
Y95148D01*
X285850Y93401D01*
Y92000D01*
X286550Y91300D01*
Y90000D01*
X285684Y89134D01*
X284790D01*
X284024Y89900D01*
G01X250785Y79623D02*
Y83195D01*
X250281Y83699D01*
Y84699D01*
X249281Y85699D01*
Y87000D01*
X250681Y88400D01*
X251427D01*
X252313Y87514D01*
G01X287596Y79623D02*
Y83195D01*
X287092Y83699D01*
Y84699D01*
X286092Y85699D01*
Y87000D01*
X287492Y88400D01*
X288238D01*
X289124Y87514D01*
G01X247439Y97733D02*
Y95301D01*
X245643Y93505D01*
X245339Y92984D01*
Y89458D01*
X245683Y88830D01*
X247213Y87300D01*
G01X284250Y97733D02*
Y95301D01*
X282454Y93505D01*
X282150Y92984D01*
Y89458D01*
X282494Y88830D01*
X284024Y87300D01*
G01X254132Y79623D02*
Y84151D01*
X254281Y84300D01*
Y89100D01*
X253267Y90114D01*
X252313D01*
G01X290943Y79623D02*
Y84151D01*
X291092Y84300D01*
Y89100D01*
X290078Y90114D01*
X289124D01*
G01X277557Y92757D02*
Y97733D01*
G01X280903Y79623D02*
Y85033D01*
X280203Y85733D01*
Y87714D01*
G01X270864Y92757D02*
Y97733D01*
G01X274210Y79623D02*
Y87414D01*
X273910Y87714D01*
G01X240746Y59933D02*
Y54957D01*
G01X244092Y41823D02*
Y47233D01*
X243392Y47933D01*
Y49914D01*
G01X264171Y59933D02*
Y54957D01*
G01X267518Y41823D02*
Y42343D01*
X267517Y42344D01*
Y49914D01*
G01X234053Y59933D02*
Y54957D01*
G01X237399Y41823D02*
Y49614D01*
X237099Y49914D01*
G01X257478Y59933D02*
Y54957D01*
G01X260825Y41823D02*
X260824D01*
Y49914D01*
G01X250785Y59933D02*
X250786Y59932D01*
Y57348D01*
X249039Y55601D01*
Y54200D01*
X249739Y53500D01*
Y52200D01*
X248873Y51334D01*
X247979D01*
X247213Y52100D01*
G01X287596Y59933D02*
X287597Y59932D01*
Y57348D01*
X285850Y55601D01*
Y54200D01*
X286550Y53500D01*
Y52200D01*
X285684Y51334D01*
X284790D01*
X284024Y52100D01*
G01X250785Y41823D02*
Y45395D01*
X250281Y45899D01*
Y46899D01*
X249281Y47899D01*
Y49200D01*
X250681Y50600D01*
X251427D01*
X252313Y49714D01*
G01X287596Y41823D02*
Y45395D01*
X287092Y45899D01*
Y46899D01*
X286092Y47899D01*
Y49200D01*
X287492Y50600D01*
X288238D01*
X289124Y49714D01*
G01X247439Y59933D02*
Y57501D01*
X245643Y55705D01*
X245339Y55184D01*
Y51658D01*
X245683Y51030D01*
X247213Y49500D01*
G01X284250Y59933D02*
Y57501D01*
X282454Y55705D01*
X282150Y55184D01*
Y51658D01*
X282494Y51030D01*
X284024Y49500D01*
G01X254132Y41823D02*
Y46351D01*
X254281Y46500D01*
Y51300D01*
X253267Y52314D01*
X252313D01*
G01X290943Y41823D02*
Y46351D01*
X291092Y46500D01*
Y51300D01*
X290078Y52314D01*
X289124D01*
G01X277557Y59933D02*
Y54957D01*
G01X280903Y41823D02*
Y47233D01*
X280203Y47933D01*
Y49914D01*
G01X270864Y59933D02*
Y54957D01*
G01X274210Y41823D02*
Y49614D01*
X273910Y49914D01*
G01X240746Y523134D02*
Y518157D01*
G01X244092Y505024D02*
Y510433D01*
X243392Y511133D01*
Y513114D01*
G01X264171Y523134D02*
Y518157D01*
G01X267518Y505024D02*
X267517D01*
Y513114D01*
G01X234053Y523134D02*
Y518157D01*
G01X237399Y505024D02*
Y512814D01*
X237099Y513114D01*
G01X257478Y523134D02*
Y518157D01*
G01X260825Y505024D02*
X260824D01*
Y513114D01*
G01X250785Y523134D02*
Y520547D01*
X249039Y518801D01*
Y517400D01*
X249739Y516700D01*
Y515400D01*
X248873Y514534D01*
X247979D01*
X247213Y515300D01*
G01X287596Y523134D02*
X287597Y523132D01*
Y520548D01*
X285850Y518801D01*
Y517400D01*
X286550Y516700D01*
Y515400D01*
X285684Y514534D01*
X284790D01*
X284024Y515300D01*
G01X250785Y505024D02*
Y508595D01*
X250281Y509099D01*
Y510099D01*
X249281Y511099D01*
Y512400D01*
X250681Y513800D01*
X251427D01*
X252313Y512914D01*
G01X287596Y505024D02*
Y508595D01*
X287092Y509099D01*
Y510099D01*
X286092Y511099D01*
Y512400D01*
X287492Y513800D01*
X288238D01*
X289124Y512914D01*
G01X247439Y523134D02*
Y520701D01*
X245643Y518905D01*
X245339Y518384D01*
Y514858D01*
X245683Y514230D01*
X247213Y512700D01*
G01X284250Y523134D02*
Y520701D01*
X282454Y518905D01*
X282150Y518384D01*
Y514858D01*
X282494Y514230D01*
X284024Y512700D01*
G01X254132Y505024D02*
Y509551D01*
X254281Y509700D01*
Y514500D01*
X253267Y515514D01*
X252313D01*
G01X290943Y505024D02*
Y509551D01*
X291092Y509700D01*
Y514500D01*
X290078Y515514D01*
X289124D01*
G01X277557Y523134D02*
Y518157D01*
G01X280903Y505024D02*
Y510433D01*
X280203Y511133D01*
Y513114D01*
G01X270864Y523134D02*
Y518157D01*
G01X274210Y505024D02*
Y512814D01*
X273910Y513114D01*
G01X240746Y560934D02*
Y555957D01*
G01X244092Y542824D02*
Y548233D01*
X243392Y548933D01*
Y550914D01*
G01X264171Y560934D02*
Y555957D01*
G01X267518Y542824D02*
X267517D01*
Y550914D01*
G01X234053Y560934D02*
Y555957D01*
G01X237399Y542824D02*
Y550614D01*
X237099Y550914D01*
G01X257478Y560934D02*
Y555957D01*
G01X260825Y542824D02*
X260824D01*
Y550914D01*
G01X250785Y560934D02*
Y558347D01*
X249039Y556601D01*
Y555200D01*
X249739Y554500D01*
Y553200D01*
X248873Y552334D01*
X247979D01*
X247213Y553100D01*
G01X287596Y560934D02*
X287597Y560932D01*
Y558348D01*
X285850Y556601D01*
Y555200D01*
X286550Y554500D01*
Y553200D01*
X285684Y552334D01*
X284790D01*
X284024Y553100D01*
G01X250785Y542824D02*
Y546395D01*
X250281Y546899D01*
Y547899D01*
X249281Y548899D01*
Y550200D01*
X250681Y551600D01*
X251427D01*
X252313Y550714D01*
G01X287596Y542824D02*
Y546395D01*
X287092Y546899D01*
Y547899D01*
X286092Y548899D01*
Y550200D01*
X287492Y551600D01*
X288238D01*
X289124Y550714D01*
G01X247439Y560934D02*
Y558501D01*
X245643Y556705D01*
X245339Y556184D01*
Y552658D01*
X245683Y552030D01*
X247213Y550500D01*
G01X284250Y560934D02*
Y558501D01*
X282454Y556705D01*
X282150Y556184D01*
Y552658D01*
X282494Y552030D01*
X284024Y550500D01*
G01X254132Y542824D02*
Y547351D01*
X254281Y547500D01*
Y552300D01*
X253267Y553314D01*
X252313D01*
G01X290943Y542824D02*
Y547351D01*
X291092Y547500D01*
Y552300D01*
X290078Y553314D01*
X289124D01*
G01X277557Y560934D02*
Y555957D01*
G01X280903Y542824D02*
Y548233D01*
X280203Y548933D01*
Y550914D01*
G01X270864Y560934D02*
Y555957D01*
G01X274210Y542824D02*
Y550614D01*
X273910Y550914D01*
G01X244092Y580624D02*
Y586033D01*
X243392Y586733D01*
Y588714D01*
G01X267518Y580624D02*
X267517D01*
Y588714D01*
G01X237399Y580624D02*
Y588414D01*
X237099Y588714D01*
G01X260825Y580624D02*
X260824D01*
Y588714D01*
G01X250785Y580624D02*
Y584195D01*
X250281Y584699D01*
Y585699D01*
X249281Y586699D01*
Y588000D01*
X250681Y589400D01*
X251427D01*
X252313Y588514D01*
G01X287596Y580624D02*
Y584195D01*
X287092Y584699D01*
Y585699D01*
X286092Y586699D01*
Y588000D01*
X287492Y589400D01*
X288238D01*
X289124Y588514D01*
G01X247439Y598734D02*
Y596301D01*
X245643Y594505D01*
X245339Y593984D01*
Y590458D01*
X245683Y589830D01*
X247213Y588300D01*
G01X284250Y598734D02*
Y596301D01*
X282454Y594505D01*
X282150Y593984D01*
Y590458D01*
X282494Y589830D01*
X284024Y588300D01*
G01X254132Y580624D02*
Y585151D01*
X254281Y585300D01*
Y590100D01*
X253267Y591114D01*
X252313D01*
G01X290943Y580624D02*
Y585151D01*
X291092Y585300D01*
Y590100D01*
X290078Y591114D01*
X289124D01*
G01X280903Y580624D02*
Y586033D01*
X280203Y586733D01*
Y588714D01*
G01X274210Y580624D02*
Y588414D01*
X273910Y588714D01*
G01X240746Y598734D02*
Y593757D01*
G01X264171Y598734D02*
Y593757D01*
G01X234053Y598734D02*
Y593757D01*
G01X257478Y598734D02*
Y593757D01*
G01X250785Y598734D02*
Y596149D01*
X250786Y596148D01*
X249039Y594401D01*
Y593000D01*
X249739Y592300D01*
Y591000D01*
X248873Y590134D01*
X247979D01*
X247213Y590900D01*
G01X287596Y598734D02*
X287597Y598732D01*
Y596148D01*
X285850Y594401D01*
Y593000D01*
X286550Y592300D01*
Y591000D01*
X285684Y590134D01*
X284790D01*
X284024Y590900D01*
G01X277557Y598734D02*
Y593757D01*
G01X270864Y598734D02*
Y593757D01*
G01X321061Y22133D02*
Y17057D01*
G01X327754Y4023D02*
Y9114D01*
G01X324407Y22133D02*
Y17057D01*
G01Y4023D02*
Y9114D01*
G01X314368Y22133D02*
Y17057D01*
G01X311021Y9114D02*
Y4023D01*
G01X300982Y22133D02*
Y17157D01*
G01X304329Y4023D02*
X304328Y4024D01*
Y12114D01*
G01X294289Y22133D02*
Y17157D01*
G01X297636Y4023D02*
X297635Y4024D01*
Y12114D01*
G01X334447Y4023D02*
Y9113D01*
X334446Y9114D01*
G01X331100Y22133D02*
Y17057D01*
G01X354525Y22133D02*
Y17158D01*
X354526Y17157D01*
Y17057D01*
G01X354525Y9122D02*
Y4023D01*
G01X351179Y22133D02*
Y17057D01*
G01X347833Y4023D02*
Y9122D01*
G01X344486Y4023D02*
Y9122D01*
G01Y22133D02*
Y17057D01*
G01X337793Y4023D02*
Y9114D01*
G01X341140Y22133D02*
Y17057D01*
G01X334447Y22133D02*
Y17057D01*
G01X321061Y92757D02*
Y97733D01*
G01X327754Y87392D02*
Y79623D01*
G01X324407Y89964D02*
Y97733D01*
G01Y79623D02*
Y84599D01*
G01X314368Y92657D02*
Y97733D01*
G01X311021Y84714D02*
Y79623D01*
G01X300982Y92757D02*
Y97733D01*
G01X304329Y79623D02*
Y82573D01*
X304328Y82574D01*
Y87714D01*
G01X294289Y92757D02*
Y97733D01*
G01X297636Y79623D02*
X297635Y79624D01*
Y87714D01*
G01X334447Y87392D02*
Y79623D01*
G01X331100Y89964D02*
Y97733D01*
G01X354525D02*
Y92867D01*
X354415Y92757D01*
G01X354525Y79623D02*
Y87282D01*
X354415Y87392D01*
G01X351179Y89964D02*
Y97733D01*
G01X347833Y87392D02*
Y79623D01*
G01X344486D02*
Y84714D01*
G01Y89964D02*
Y97733D01*
G01X337793Y79623D02*
Y84599D01*
G01X341140Y92757D02*
Y97733D01*
G01X334447Y92757D02*
Y97733D01*
G01X321061Y59933D02*
Y54857D01*
G01X327754Y41823D02*
Y46914D01*
G01X324407Y59933D02*
Y54857D01*
G01Y41823D02*
Y46914D01*
G01X314368Y59933D02*
Y54857D01*
G01X311021Y46914D02*
Y41823D01*
G01X300982Y59933D02*
Y54957D01*
G01X304329Y41823D02*
X304328Y41824D01*
Y49914D01*
G01X294289Y59933D02*
Y54957D01*
G01X297636Y41823D02*
Y43743D01*
X297635Y43744D01*
Y49914D01*
G01X334447Y41823D02*
Y46913D01*
X334446Y46914D01*
G01X331100Y59933D02*
Y54857D01*
G01X354525Y59933D02*
Y54958D01*
X354526Y54957D01*
Y54857D01*
G01X354525Y46922D02*
Y41823D01*
G01X351179Y59933D02*
Y54857D01*
G01X347833Y41823D02*
Y46922D01*
G01X344486Y41823D02*
Y46922D01*
G01Y59933D02*
Y54857D01*
G01X337793Y41823D02*
Y46914D01*
G01X341140Y59933D02*
Y54857D01*
G01X334447Y59933D02*
Y54857D01*
G01X316500Y253000D02*
X319851D01*
X320585Y253734D01*
X322654D01*
X324320Y252068D01*
X325742D01*
X327520Y250290D01*
X328949D01*
X330898Y248341D01*
X332934D01*
X334609Y250016D01*
X336008D01*
X337907Y248117D01*
X339770D01*
X341503Y246384D01*
X342933D01*
X344428Y247879D01*
X346311D01*
X348262Y245928D01*
X349691D01*
X351324Y244295D01*
X352924D01*
X354557Y245928D01*
X356450D01*
X358393Y243985D01*
X359832D01*
X361327Y242490D01*
X363667D01*
X365162Y243985D01*
X366592D01*
X368118Y242459D01*
X369939D01*
X371465Y243985D01*
X373352D01*
X375127Y242210D01*
X376548D01*
X378569Y240189D01*
X379766D01*
X381756Y242179D01*
X383347D01*
X384991Y240535D01*
X386872D01*
X388710Y242373D01*
X389913D01*
X391751Y240535D01*
X393631D01*
X395580Y242484D01*
X397460D01*
X399185Y244209D01*
X407706D01*
G01X399676Y246160D02*
X395357D01*
X393632Y244435D01*
X391751D01*
X390026Y246160D01*
X388597D01*
X386872Y244435D01*
X384991D01*
X383492Y245934D01*
X381611D01*
X380112Y244435D01*
X378231D01*
X376693Y245973D01*
X375264D01*
X373335Y247902D01*
X371490D01*
X369656Y246068D01*
X368409D01*
X366592Y247885D01*
X365064D01*
X363216Y246037D01*
X362034D01*
X359952Y248119D01*
X358159D01*
X356450Y249828D01*
X354565D01*
X353072Y248335D01*
X351184D01*
X349691Y249828D01*
X348270D01*
X346313Y251785D01*
X344434D01*
X342933Y250284D01*
X341054D01*
X339553Y251785D01*
X338375D01*
X336432Y253728D01*
X334278D01*
X332680Y252130D01*
X331009D01*
X329255Y253884D01*
X327827D01*
X327523Y254187D01*
X326031Y255679D01*
X324600D01*
X322450Y257829D01*
X319816D01*
G01X316500Y256500D02*
X318487D01*
X319816Y257829D01*
G01X321061Y523134D02*
Y518157D01*
G01X327754Y505024D02*
Y512792D01*
G01X324407Y523134D02*
Y515364D01*
G01Y505024D02*
Y509999D01*
G01X314368Y523134D02*
Y518057D01*
G01X311021Y510114D02*
Y505024D01*
G01X300982Y523134D02*
Y518157D01*
G01X304329Y505024D02*
Y507973D01*
X304328Y507974D01*
Y513114D01*
G01X294289Y523134D02*
Y518157D01*
G01X297636Y505024D02*
X297635D01*
Y513114D01*
G01X334447Y505024D02*
Y512792D01*
G01X331100Y523134D02*
Y515364D01*
G01X354525Y523134D02*
Y518158D01*
X354526Y518157D01*
G01X354525Y505024D02*
Y512574D01*
X354307Y512792D01*
G01X351179Y523134D02*
Y515364D01*
G01X347833Y505024D02*
Y512792D01*
G01X344486Y505024D02*
Y510114D01*
G01Y523134D02*
Y515364D01*
G01X337793Y505024D02*
Y509999D01*
G01X341140Y523134D02*
Y518157D01*
G01X334447Y523134D02*
Y518157D01*
G01X321061Y560934D02*
Y555857D01*
G01X327754Y547914D02*
Y542824D01*
G01X324407Y560934D02*
Y555857D01*
G01Y547914D02*
Y542824D01*
G01X314368Y560934D02*
Y555857D01*
G01X311021Y542824D02*
Y547914D01*
G01X300982Y560934D02*
Y555957D01*
G01X304329Y542824D02*
Y545773D01*
X304328Y545774D01*
Y550914D01*
G01X294289Y560934D02*
Y555957D01*
G01X297636Y542824D02*
X297635D01*
Y550914D01*
G01X334447Y542824D02*
Y547913D01*
X334446Y547914D01*
G01X331100Y560934D02*
Y555857D01*
G01X354525Y560934D02*
Y555958D01*
X354526Y555957D01*
Y555857D01*
G01X354525Y542824D02*
Y547922D01*
G01X351179Y560934D02*
Y555857D01*
G01X347833Y547922D02*
Y542824D01*
G01X344486Y547922D02*
Y542824D01*
G01Y560934D02*
Y555857D01*
G01X337793Y547914D02*
Y542824D01*
G01X341140Y560934D02*
Y555857D01*
G01X334447Y560934D02*
Y555857D01*
G01X327754Y585714D02*
Y580624D01*
G01X324407Y585714D02*
Y580624D01*
G01X311021D02*
Y585714D01*
G01X304329Y580624D02*
Y583573D01*
X304328Y583574D01*
Y588714D01*
G01X297636Y580624D02*
X297635D01*
Y588714D01*
G01X334447Y580624D02*
Y585713D01*
X334446Y585714D01*
G01X354525Y580624D02*
Y585722D01*
G01X347833D02*
Y580624D01*
G01X344486Y585722D02*
Y580624D01*
G01X337793Y585714D02*
Y580624D01*
G01X321061Y598734D02*
Y593657D01*
G01X324407Y598734D02*
Y593657D01*
G01X314368Y598734D02*
Y593657D01*
G01X300982Y598734D02*
Y593757D01*
G01X294289Y598734D02*
Y593757D01*
G01X331100Y598734D02*
Y593657D01*
G01X354525Y598734D02*
Y593758D01*
X354526Y593757D01*
Y593657D01*
G01X351179Y598734D02*
Y593657D01*
G01X344486Y598734D02*
Y593657D01*
G01X341140Y598734D02*
Y593657D01*
G01X334447Y598734D02*
Y593657D01*
G01X404722Y22133D02*
Y17058D01*
X404723Y17057D01*
G01X401376Y4023D02*
Y9121D01*
G01X364565Y22133D02*
Y17788D01*
X365311Y17042D01*
G01X364565Y4023D02*
Y9114D01*
G01X361218Y22133D02*
Y19284D01*
X361802Y17874D01*
X362662Y17014D01*
G01X361218Y4023D02*
Y9114D01*
G01X414762Y17058D02*
Y22133D01*
G01X398029D02*
Y17042D01*
G01X404722Y4023D02*
Y9121D01*
G01X414762Y4023D02*
Y9121D01*
X414763Y9122D01*
G01X408069Y22133D02*
Y17042D01*
G01X394683Y4023D02*
Y11791D01*
X394682Y11792D01*
G01X404722Y89964D02*
Y97733D01*
G01X401376Y79623D02*
Y87391D01*
X401375Y87392D01*
G01X364565Y97733D02*
Y93542D01*
X365607Y92500D01*
G01X364565Y79623D02*
Y83528D01*
X364079Y84014D01*
Y86345D01*
X365234Y87500D01*
G01X361218Y97733D02*
Y94074D01*
X362792Y92500D01*
G01X361218Y79623D02*
Y82325D01*
X362929Y84036D01*
Y87006D01*
X362435Y87500D01*
G01X414762Y97733D02*
Y92758D01*
X414761Y92757D01*
G01X398029Y89964D02*
Y97733D01*
G01X404722Y79623D02*
Y84599D01*
G01X414762Y79623D02*
X414761Y79624D01*
Y87392D01*
G01X408069Y97733D02*
Y92758D01*
X408068Y92757D01*
G01X394683Y79623D02*
Y87391D01*
X394682Y87392D01*
G01X404722Y59933D02*
Y54858D01*
X404723Y54857D01*
G01X401376Y41823D02*
Y46921D01*
X401377Y46922D01*
G01X364565Y59933D02*
Y54842D01*
G01Y41823D02*
Y46614D01*
X364265Y46914D01*
G01X361218Y59933D02*
Y54842D01*
G01Y41823D02*
Y46614D01*
X361518Y46914D01*
G01X414762Y59933D02*
Y54858D01*
X414763Y54857D01*
G01X398029Y59933D02*
Y54842D01*
G01X404722Y41823D02*
Y46921D01*
X404723Y46922D01*
G01X414762Y41823D02*
Y46921D01*
X414763Y46922D01*
G01X408069Y59933D02*
Y54842D01*
G01X394683Y41823D02*
X394682Y41824D01*
Y49592D01*
G01X404722Y523134D02*
Y515364D01*
G01X401376Y505024D02*
Y512791D01*
X401375Y512792D01*
G01X364565Y523134D02*
Y515452D01*
X364265Y515152D01*
G01X364565Y505024D02*
Y509814D01*
X364265Y510114D01*
G01X361218Y523134D02*
Y515624D01*
X361642Y515200D01*
G01X361218Y505024D02*
Y509814D01*
X361518Y510114D01*
G01X414762Y523134D02*
Y518158D01*
X414761Y518157D01*
G01X398029Y523134D02*
Y515364D01*
G01X404722Y505024D02*
Y509999D01*
G01X414761Y512792D02*
Y505024D01*
X414762D01*
G01X408069Y523134D02*
Y518158D01*
X408068Y518157D01*
G01X394683Y505024D02*
Y512791D01*
X394682Y512792D01*
G01X404722Y560934D02*
Y555858D01*
X404723Y555857D01*
G01X401376Y542824D02*
Y547922D01*
G01X364565Y560934D02*
Y555842D01*
G01Y542824D02*
Y547614D01*
X364265Y547914D01*
G01X361218Y560934D02*
Y555944D01*
X361320Y555842D01*
G01X361218Y542824D02*
Y547614D01*
X361518Y547914D01*
G01X414762Y560934D02*
Y555858D01*
X414763Y555857D01*
G01X398029Y560934D02*
Y555842D01*
G01X404722Y542824D02*
Y547921D01*
X404723Y547922D01*
G01X414762Y542824D02*
Y547921D01*
X414763Y547922D01*
G01X408069Y560934D02*
Y555842D01*
G01X394683Y542824D02*
Y550591D01*
X394682Y550592D01*
G01X401376Y580624D02*
Y585721D01*
X401377Y585722D01*
G01X364565Y580624D02*
Y585414D01*
X364265Y585714D01*
G01X361218Y580624D02*
Y585414D01*
X361518Y585714D01*
G01X404722Y580624D02*
Y585721D01*
X404723Y585722D01*
G01X414762Y580624D02*
Y585721D01*
X414763Y585722D01*
G01X394683Y580624D02*
X394682D01*
Y588392D01*
G01X404722Y598734D02*
Y593658D01*
X404723Y593657D01*
G01X364565Y598734D02*
Y594388D01*
X365311Y593642D01*
G01X361218Y598734D02*
Y594388D01*
X361964Y593642D01*
G01X414762Y598734D02*
Y593658D01*
X414763Y593657D01*
G01X398029Y598734D02*
Y593642D01*
G01X408069Y598734D02*
Y593642D01*
G01X438187Y9120D02*
Y4023D01*
G01X431494Y22133D02*
Y17042D01*
G01X444880Y22133D02*
Y17059D01*
G01Y9122D02*
Y4023D01*
G01X458266Y22133D02*
Y17157D01*
G01X461612Y4023D02*
Y9433D01*
X460912Y10133D01*
Y12114D01*
G01X451573Y22133D02*
Y17157D01*
G01X454919Y4023D02*
Y8973D01*
X454619Y9273D01*
Y12114D01*
G01X474998Y22133D02*
Y17157D01*
G01X468305Y22133D02*
Y19548D01*
X466558Y17801D01*
Y16400D01*
X467258Y15700D01*
Y14400D01*
X466392Y13534D01*
X465498D01*
X464732Y14300D01*
G01X468305Y4023D02*
Y7554D01*
X467308Y8551D01*
Y11990D01*
X469832Y14514D01*
G01X464958Y22133D02*
Y19701D01*
X463162Y17905D01*
X462858Y17384D01*
Y13858D01*
X463202Y13230D01*
X464732Y11700D01*
G01X471651Y4023D02*
X471650D01*
Y9992D01*
X472358Y10700D01*
Y12470D01*
X471808Y13020D01*
X470938D01*
X469832Y11914D01*
G01X428147Y4023D02*
Y9120D01*
G01X434840D02*
Y4023D01*
G01X424801Y22133D02*
Y17042D01*
G01X438187Y22133D02*
Y17059D01*
G01Y79623D02*
Y84714D01*
G01X431494Y89964D02*
Y97733D01*
G01X444880Y89964D02*
Y97733D01*
G01Y84714D02*
Y79623D01*
G01X458266Y92757D02*
Y97733D01*
G01X461612Y79623D02*
Y85033D01*
X460912Y85733D01*
Y87714D01*
G01X451573Y92757D02*
Y97733D01*
G01X454919Y79623D02*
Y87414D01*
X454619Y87714D01*
G01X474998Y92757D02*
Y97733D01*
G01X468305D02*
Y95148D01*
X466558Y93401D01*
Y92000D01*
X467258Y91300D01*
Y90000D01*
X466392Y89134D01*
X465498D01*
X464732Y89900D01*
G01X468305Y79623D02*
Y83194D01*
X467800Y83699D01*
Y84699D01*
X466800Y85699D01*
Y87000D01*
X468200Y88400D01*
X468946D01*
X469832Y87514D01*
G01X464958Y97733D02*
Y95301D01*
X463162Y93505D01*
X462858Y92984D01*
Y89458D01*
X463202Y88830D01*
X464732Y87300D01*
G01X471651Y79623D02*
Y84151D01*
X471800Y84300D01*
Y89100D01*
X470786Y90114D01*
X469832D01*
G01X428147Y87392D02*
Y79623D01*
G01X421455Y97733D02*
Y92758D01*
X421454Y92757D01*
G01X434840Y87392D02*
Y79623D01*
G01X424801Y89964D02*
Y97733D01*
G01X438187Y89964D02*
Y97733D01*
G01X431494Y59933D02*
Y54842D01*
G01X444880Y59933D02*
Y54859D01*
G01Y46922D02*
Y41823D01*
G01X458266Y59933D02*
Y54957D01*
G01X461612Y41823D02*
Y47233D01*
X460912Y47933D01*
Y49914D01*
G01X451573Y59933D02*
Y54957D01*
G01X454919Y41823D02*
Y49264D01*
X454619Y49564D01*
G01X474998Y59933D02*
Y54957D01*
G01X468305Y59933D02*
Y57348D01*
X466558Y55601D01*
Y54200D01*
X467258Y53500D01*
Y52200D01*
X466392Y51334D01*
X465498D01*
X464732Y52100D01*
G01X468305Y41823D02*
Y45394D01*
X467800Y45899D01*
Y46899D01*
X466800Y47899D01*
Y49200D01*
X468200Y50600D01*
X468946D01*
X469832Y49714D01*
G01X464958Y59933D02*
Y57501D01*
X463162Y55705D01*
X462858Y55184D01*
Y51658D01*
X463202Y51030D01*
X464732Y49500D01*
G01X471651Y41823D02*
Y46351D01*
X471800Y46500D01*
Y51300D01*
X470786Y52314D01*
X469832D01*
G01X428147Y41823D02*
Y46920D01*
X428149Y46922D01*
G01X434840Y41823D02*
Y46920D01*
X434842Y46922D01*
G01X424801Y59933D02*
Y54842D01*
G01X438187Y59933D02*
Y54859D01*
G01Y505024D02*
Y510114D01*
G01X431494Y523134D02*
Y515364D01*
G01X444880Y523134D02*
Y515364D01*
G01Y510114D02*
Y505024D01*
G01X458266Y523134D02*
Y518157D01*
G01X461612Y505024D02*
Y510433D01*
X460912Y511133D01*
Y513114D01*
G01X451573Y523134D02*
Y518157D01*
G01X454919Y505024D02*
Y512814D01*
X454619Y513114D01*
G01X474998Y523134D02*
Y518157D01*
G01X468305Y523134D02*
Y520548D01*
X466558Y518801D01*
Y517400D01*
X467258Y516700D01*
Y515400D01*
X466392Y514534D01*
X465498D01*
X464732Y515300D01*
G01X468305Y505024D02*
Y508594D01*
X467800Y509099D01*
Y510099D01*
X466800Y511099D01*
Y512400D01*
X468200Y513800D01*
X468946D01*
X469832Y512914D01*
G01X464958Y523134D02*
Y520701D01*
X463162Y518905D01*
X462858Y518384D01*
Y514858D01*
X463202Y514230D01*
X464732Y512700D01*
G01X471651Y505024D02*
Y509551D01*
X471800Y509700D01*
Y514500D01*
X470786Y515514D01*
X469832D01*
G01X428147Y505024D02*
Y512792D01*
G01X421455Y523134D02*
Y518158D01*
X421454Y518157D01*
G01X434840Y505024D02*
Y512792D01*
G01X424801Y523134D02*
Y515364D01*
G01X438187Y523134D02*
Y515364D01*
G01Y542824D02*
Y547920D01*
X438189Y547922D01*
G01X431494Y560934D02*
Y555842D01*
G01X444880Y560934D02*
Y555859D01*
G01Y542824D02*
Y547922D01*
G01X458266Y560934D02*
Y555957D01*
G01X461612Y542824D02*
Y548233D01*
X460912Y548933D01*
Y550914D01*
G01X451573Y560934D02*
Y555957D01*
G01X454919Y542824D02*
Y550614D01*
X454619Y550914D01*
G01X474998Y560934D02*
Y555957D01*
G01X468305Y560934D02*
Y558348D01*
X466558Y556601D01*
Y555200D01*
X467258Y554500D01*
Y553200D01*
X466392Y552334D01*
X465498D01*
X464732Y553100D01*
G01X468305Y542824D02*
Y546394D01*
X467800Y546899D01*
Y547899D01*
X466800Y548899D01*
Y550200D01*
X468200Y551600D01*
X468946D01*
X469832Y550714D01*
G01X464958Y560934D02*
Y558501D01*
X463162Y556705D01*
X462858Y556184D01*
Y552658D01*
X463202Y552030D01*
X464732Y550500D01*
G01X471651Y542824D02*
Y547351D01*
X471800Y547500D01*
Y552300D01*
X470786Y553314D01*
X469832D01*
G01X428147Y542824D02*
Y547920D01*
X428149Y547922D01*
G01X434840Y542824D02*
Y547920D01*
X434842Y547922D01*
G01X424801Y560934D02*
Y555842D01*
G01X438187Y560934D02*
Y555859D01*
G01X444880Y580624D02*
Y585722D01*
G01X461612Y580624D02*
Y586033D01*
X460912Y586733D01*
Y588714D01*
G01X454919Y580624D02*
Y588414D01*
X454619Y588714D01*
G01X468305Y580624D02*
Y584194D01*
X467800Y584699D01*
Y585699D01*
X466800Y586699D01*
Y588000D01*
X468200Y589400D01*
X468946D01*
X469832Y588514D01*
G01X464958Y598734D02*
Y596301D01*
X463162Y594505D01*
X462858Y593984D01*
Y590458D01*
X463202Y589830D01*
X464732Y588300D01*
G01X471651Y580624D02*
Y585151D01*
X471800Y585300D01*
Y590100D01*
X470786Y591114D01*
X469832D01*
G01X428147Y580624D02*
Y585720D01*
X428149Y585722D01*
G01X434840Y580624D02*
Y585720D01*
X434842Y585722D01*
G01X431494Y598734D02*
Y593642D01*
G01X444880Y598734D02*
Y593659D01*
G01X458266Y598734D02*
Y593757D01*
G01X451573Y598734D02*
Y593757D01*
G01X474998Y598734D02*
Y593757D01*
G01X468305Y598734D02*
Y596148D01*
X466558Y594401D01*
Y593000D01*
X467258Y592300D01*
Y591000D01*
X466392Y590134D01*
X465498D01*
X464732Y590900D01*
G01X424801Y598734D02*
Y593642D01*
G01X438187Y598734D02*
Y593659D01*
G01X481691Y22133D02*
Y17157D01*
G01X485037Y4023D02*
Y12114D01*
G01X478344Y4023D02*
Y12114D01*
G01X495077Y22133D02*
Y17157D01*
G01X498423Y4023D02*
Y9433D01*
X497723Y10133D01*
Y12114D01*
G01X518502Y22133D02*
Y17157D01*
G01X521848Y4023D02*
Y12114D01*
G01X488384Y22133D02*
Y17157D01*
G01X491730Y4023D02*
Y11814D01*
X491430Y12114D01*
G01X511809Y22133D02*
Y17157D01*
G01X515155Y4023D02*
Y12114D01*
G01X531888Y22133D02*
Y17157D01*
G01X535234Y4023D02*
Y9433D01*
X534534Y10133D01*
Y12114D01*
G01X525195Y22133D02*
Y17157D01*
G01X528541Y4023D02*
Y11814D01*
X528241Y12114D01*
G01X505116Y22133D02*
Y19547D01*
X503370Y17801D01*
Y16400D01*
X504070Y15700D01*
Y14400D01*
X503204Y13534D01*
X502310D01*
X501544Y14300D01*
G01X541927Y22133D02*
Y19547D01*
X540181Y17801D01*
Y16400D01*
X540881Y15700D01*
Y14400D01*
X540015Y13534D01*
X539121D01*
X538355Y14300D01*
G01X505116Y4023D02*
Y7555D01*
X504120Y8551D01*
Y11990D01*
X506644Y14514D01*
G01X501770Y22133D02*
Y19701D01*
X499974Y17905D01*
X499670Y17384D01*
Y13858D01*
X500014Y13230D01*
X501544Y11700D01*
G01X538581Y22133D02*
Y19701D01*
X536785Y17905D01*
X536481Y17384D01*
Y13858D01*
X536825Y13230D01*
X538355Y11700D01*
G01X508462Y4023D02*
Y9992D01*
X509170Y10700D01*
Y12470D01*
X508620Y13020D01*
X507750D01*
X506644Y11914D01*
G01X481691Y92757D02*
Y97733D01*
G01X485037Y87714D02*
Y79623D01*
G01X478344Y87714D02*
Y79623D01*
G01X495077Y92757D02*
Y97733D01*
G01X498423Y79623D02*
Y85033D01*
X497723Y85733D01*
Y87714D01*
G01X518502Y92757D02*
Y97733D01*
G01X521848Y87714D02*
Y79623D01*
G01X488384Y92757D02*
Y97733D01*
G01X491730Y79623D02*
Y87414D01*
X491430Y87714D01*
G01X511809Y92757D02*
Y97733D01*
G01X515155Y87714D02*
Y79623D01*
G01X531888Y92757D02*
Y97733D01*
G01X535234Y79623D02*
Y85033D01*
X534534Y85733D01*
Y87714D01*
G01X525195Y92757D02*
Y97733D01*
G01X528541Y79623D02*
Y87414D01*
X528241Y87714D01*
G01X505116Y97733D02*
X505117Y97732D01*
Y95148D01*
X503370Y93401D01*
Y92000D01*
X504070Y91300D01*
Y90000D01*
X503204Y89134D01*
X502310D01*
X501544Y89900D01*
G01X541927Y97733D02*
X541928Y97732D01*
Y95148D01*
X540181Y93401D01*
Y92000D01*
X540881Y91300D01*
Y90000D01*
X540015Y89134D01*
X539121D01*
X538355Y89900D01*
G01X505116Y79623D02*
Y83195D01*
X504612Y83699D01*
Y84699D01*
X503612Y85699D01*
Y87000D01*
X505012Y88400D01*
X505758D01*
X506644Y87514D01*
G01X501770Y97733D02*
Y95301D01*
X499974Y93505D01*
X499670Y92984D01*
Y89458D01*
X500014Y88830D01*
X501544Y87300D01*
G01X538581Y97733D02*
Y95301D01*
X536785Y93505D01*
X536481Y92984D01*
Y89458D01*
X536825Y88830D01*
X538174Y87482D01*
X538355Y87300D01*
G01X508462Y79623D02*
X508463Y79624D01*
Y84151D01*
X508612Y84300D01*
Y89100D01*
X507598Y90114D01*
X506644D01*
G01X481691Y59933D02*
Y54957D01*
G01X485037Y41823D02*
Y49914D01*
G01X478344Y41823D02*
Y49914D01*
G01X495077Y59933D02*
Y54957D01*
G01X498423Y41823D02*
Y47233D01*
X497723Y47933D01*
Y49914D01*
G01X518502Y59933D02*
Y54957D01*
G01X521848Y41823D02*
Y49914D01*
G01X488384Y59933D02*
Y54957D01*
G01X491730Y41823D02*
Y49614D01*
X491430Y49914D01*
G01X511809Y59933D02*
Y54957D01*
G01X515155Y41823D02*
Y49914D01*
G01X531888Y59933D02*
Y54957D01*
G01X535234Y41823D02*
Y47233D01*
X534534Y47933D01*
Y49914D01*
G01X525195Y59933D02*
Y54957D01*
G01X528541Y41823D02*
Y49614D01*
X528241Y49914D01*
G01X505116Y59933D02*
Y57348D01*
X503369Y55601D01*
Y54200D01*
X504069Y53500D01*
Y52200D01*
X503203Y51334D01*
X502309D01*
X501543Y52100D01*
G01X541927Y59933D02*
X541928Y59932D01*
Y57348D01*
X540181Y55601D01*
Y54200D01*
X540881Y53500D01*
Y52200D01*
X540015Y51334D01*
X539121D01*
X538355Y52100D01*
G01X505116Y41823D02*
Y45394D01*
X504611Y45899D01*
Y46899D01*
X503611Y47899D01*
Y49200D01*
X505011Y50600D01*
X505757D01*
X506643Y49714D01*
G01X501770Y59933D02*
Y57501D01*
X499974Y55705D01*
X499670Y55184D01*
Y51658D01*
X500014Y51030D01*
X501543Y49501D01*
Y49500D01*
G01X538581Y59933D02*
Y57501D01*
X536785Y55705D01*
X536481Y55184D01*
Y51658D01*
X536825Y51030D01*
X538355Y49500D01*
G01X508462Y41823D02*
Y46351D01*
X508611Y46500D01*
Y51300D01*
X507597Y52314D01*
X506643D01*
G01X481691Y523134D02*
Y518157D01*
G01X485037Y505024D02*
Y513114D01*
G01X478344Y505024D02*
Y513114D01*
G01X495077Y523134D02*
Y518157D01*
G01X498423Y505024D02*
Y510433D01*
X497723Y511133D01*
Y513114D01*
G01X518502Y523134D02*
Y518157D01*
G01X521848Y505024D02*
Y513114D01*
G01X488384Y523134D02*
Y518157D01*
G01X491730Y505024D02*
Y512814D01*
X491430Y513114D01*
G01X511809Y523134D02*
Y518157D01*
G01X515155Y505024D02*
Y513114D01*
G01X531888Y523134D02*
Y518157D01*
G01X535234Y505024D02*
Y510433D01*
X534534Y511133D01*
Y513114D01*
G01X525195Y523134D02*
Y518157D01*
G01X528541Y505024D02*
Y512814D01*
X528241Y513114D01*
G01X505116Y523134D02*
X505117Y523132D01*
Y520548D01*
X503370Y518801D01*
Y517400D01*
X504070Y516700D01*
Y515400D01*
X503204Y514534D01*
X502310D01*
X501544Y515300D01*
G01X541927Y523134D02*
Y520549D01*
X541928Y520548D01*
X540181Y518801D01*
Y517400D01*
X540881Y516700D01*
Y515400D01*
X540015Y514534D01*
X539121D01*
X538355Y515300D01*
G01X505116Y505024D02*
Y508595D01*
X504612Y509099D01*
Y510099D01*
X503612Y511099D01*
Y512400D01*
X505012Y513800D01*
X505758D01*
X506644Y512914D01*
G01X501770Y523134D02*
Y520701D01*
X499974Y518905D01*
X499670Y518384D01*
Y514858D01*
X500014Y514230D01*
X501544Y512700D01*
G01X538581Y523134D02*
Y520701D01*
X536785Y518905D01*
X536481Y518384D01*
Y514858D01*
X536825Y514230D01*
X538355Y512700D01*
G01X508462Y505024D02*
X508463D01*
Y509551D01*
X508612Y509700D01*
Y514500D01*
X507598Y515514D01*
X506644D01*
G01X481691Y560934D02*
Y555957D01*
G01X485037Y542824D02*
Y550914D01*
G01X478344Y542824D02*
Y550914D01*
G01X495077Y560934D02*
Y555957D01*
G01X498423Y542824D02*
Y548233D01*
X497723Y548933D01*
Y550914D01*
G01X518502Y560934D02*
Y555957D01*
G01X521848Y542824D02*
Y550914D01*
G01X488384Y560934D02*
Y555957D01*
G01X491730Y542824D02*
Y550614D01*
X491430Y550914D01*
G01X511809Y560934D02*
Y555957D01*
G01X515155Y542824D02*
Y550914D01*
G01X531888Y560934D02*
Y555957D01*
G01X535234Y542824D02*
Y548233D01*
X534534Y548933D01*
Y550914D01*
G01X525195Y560934D02*
Y555957D01*
G01X528541Y542824D02*
Y550614D01*
X528241Y550914D01*
G01X505116Y560934D02*
X505117Y560932D01*
Y558348D01*
X503370Y556601D01*
Y555200D01*
X504070Y554500D01*
Y553200D01*
X503204Y552334D01*
X502310D01*
X501544Y553100D01*
G01X541927Y560934D02*
Y558347D01*
X540181Y556601D01*
Y555200D01*
X540881Y554500D01*
Y553200D01*
X540015Y552334D01*
X539121D01*
X538355Y553100D01*
G01X505116Y542824D02*
Y546395D01*
X504612Y546899D01*
Y547899D01*
X503612Y548899D01*
Y550200D01*
X505012Y551600D01*
X505758D01*
X506644Y550714D01*
G01X501770Y560934D02*
Y558501D01*
X499974Y556705D01*
X499670Y556184D01*
Y552658D01*
X500014Y552030D01*
X501544Y550500D01*
G01X538581Y560934D02*
Y558501D01*
X536785Y556705D01*
X536481Y556184D01*
Y552658D01*
X536825Y552030D01*
X538355Y550500D01*
G01X508462Y542824D02*
X508463D01*
Y547351D01*
X508612Y547500D01*
Y552300D01*
X507598Y553314D01*
X506644D01*
G01X485037Y580624D02*
Y588714D01*
G01X478344Y580624D02*
Y588714D01*
G01X498423Y580624D02*
Y586033D01*
X497723Y586733D01*
Y588714D01*
G01X521848Y580624D02*
Y588714D01*
G01X491730Y580624D02*
Y588414D01*
X491430Y588714D01*
G01X515155Y580624D02*
Y588714D01*
G01X535234Y580624D02*
Y586033D01*
X534534Y586733D01*
Y588714D01*
G01X528541Y580624D02*
Y588414D01*
X528241Y588714D01*
G01X505116Y580624D02*
Y584195D01*
X504612Y584699D01*
Y585699D01*
X503612Y586699D01*
Y588000D01*
X505012Y589400D01*
X505758D01*
X506644Y588514D01*
G01X501770Y598734D02*
Y596301D01*
X499974Y594505D01*
X499670Y593984D01*
Y590458D01*
X500014Y589830D01*
X501544Y588300D01*
G01X538581Y598734D02*
Y596301D01*
X536785Y594505D01*
X536481Y593984D01*
Y590458D01*
X536825Y589830D01*
X538355Y588300D01*
G01X508462Y580624D02*
X508463D01*
Y585151D01*
X508612Y585300D01*
Y590100D01*
X507598Y591114D01*
X506644D01*
G01X481691Y598734D02*
Y593757D01*
G01X495077Y598734D02*
Y593757D01*
G01X518502Y598734D02*
Y593757D01*
G01X488384Y598734D02*
Y593757D01*
G01X511809Y598734D02*
Y593757D01*
G01X531888Y598734D02*
Y593757D01*
G01X525195Y598734D02*
Y593757D01*
G01X505116Y598734D02*
X505117Y598732D01*
Y596148D01*
X503370Y594401D01*
Y593000D01*
X504070Y592300D01*
Y591000D01*
X503204Y590134D01*
X502310D01*
X501544Y590900D01*
G01X541927Y598734D02*
Y596147D01*
X540181Y594401D01*
Y593000D01*
X540881Y592300D01*
Y591000D01*
X540015Y590134D01*
X539121D01*
X538355Y590900D01*
G01X770462Y-41875D02*
X581982D01*
G03Y-45825I0J-1975D01*
G01X770577D01*
G02Y-52075I0J-3125D01*
G01X578027D01*
X573828Y-47876D01*
X571671D01*
X567246Y-52301D01*
G01X770462Y-40725D02*
X581982D01*
G03Y-46975I0J-3125D01*
G01X770577D01*
G02Y-50925I0J-1975D01*
G01X578504D01*
X574305Y-46726D01*
X571671D01*
X567246Y-42301D01*
G01X555313Y22133D02*
Y17157D01*
G01X558659Y4023D02*
Y12114D01*
G01X548620Y22133D02*
Y17157D01*
G01X551966Y4023D02*
Y12114D01*
G01X568699Y22133D02*
Y17157D01*
G01X572045Y4023D02*
Y9433D01*
X571345Y10133D01*
Y12114D01*
G01X592124Y22133D02*
Y17157D01*
G01X595470Y4023D02*
Y12114D01*
G01X562006Y22133D02*
Y17157D01*
X561868Y17019D01*
G01X565352Y4023D02*
Y11814D01*
X565052Y12114D01*
G01X585431Y22133D02*
Y17157D01*
G01X588777Y4023D02*
Y12114D01*
G01X578738Y22133D02*
Y19547D01*
X576992Y17801D01*
Y16400D01*
X577692Y15700D01*
Y14400D01*
X576826Y13534D01*
X575932D01*
X575166Y14300D01*
G01X541927Y4023D02*
Y7555D01*
X540931Y8551D01*
Y11990D01*
X543455Y14514D01*
G01X578738Y4023D02*
Y7555D01*
X577742Y8551D01*
Y11990D01*
X580266Y14514D01*
G01X575392Y22133D02*
Y19701D01*
X573596Y17905D01*
X573292Y17384D01*
Y13858D01*
X573636Y13230D01*
X575166Y11700D01*
G01X545273Y4023D02*
Y9992D01*
X545981Y10700D01*
Y12470D01*
X545431Y13020D01*
X544561D01*
X543455Y11914D01*
G01X582084Y4023D02*
Y9992D01*
X582792Y10700D01*
Y12470D01*
X582242Y13020D01*
X581372D01*
X580266Y11914D01*
G01X598817Y22133D02*
Y17057D01*
G01X555313Y92757D02*
Y97733D01*
G01X558659Y87714D02*
Y79623D01*
G01X548620Y97733D02*
Y92757D01*
G01X551966Y87714D02*
Y79623D01*
G01X568699Y92757D02*
Y97733D01*
G01X572045Y79623D02*
Y85033D01*
X571345Y85733D01*
Y87714D01*
G01X592124Y92757D02*
Y97733D01*
G01X595470Y87714D02*
Y79623D01*
G01X562006Y92757D02*
Y97733D01*
G01X565352Y79623D02*
Y87288D01*
X565266Y87374D01*
G01X585431Y92757D02*
Y97733D01*
G01X588777Y87714D02*
Y79623D01*
G01X578738Y97733D02*
X578739Y97732D01*
Y95148D01*
X576992Y93401D01*
Y92000D01*
X577692Y91300D01*
Y90000D01*
X576826Y89134D01*
X575932D01*
X575166Y89900D01*
G01X541927Y79623D02*
Y83195D01*
X541423Y83699D01*
Y84699D01*
X540423Y85699D01*
Y87000D01*
X541823Y88400D01*
X542569D01*
X543230Y87738D01*
X543455Y87514D01*
G01X578738Y79623D02*
Y83195D01*
X578234Y83699D01*
Y84699D01*
X577234Y85699D01*
Y87000D01*
X578634Y88400D01*
X579380D01*
X580266Y87514D01*
G01X575392Y97733D02*
Y95301D01*
X573596Y93505D01*
X573292Y92984D01*
Y89458D01*
X573636Y88830D01*
X575166Y87300D01*
G01X545273Y79623D02*
X545274Y79624D01*
Y84151D01*
X545423Y84300D01*
Y89100D01*
X545008Y89516D01*
X544409Y90114D01*
X543455D01*
G01X582084Y79623D02*
X582085Y79624D01*
Y84151D01*
X582234Y84300D01*
Y89100D01*
X581220Y90114D01*
X580266D01*
G01X555313Y59933D02*
Y54957D01*
G01X558659Y41823D02*
Y49914D01*
G01X548620Y59933D02*
Y54957D01*
G01X551966Y41823D02*
Y49914D01*
G01X568699Y59933D02*
Y54957D01*
G01X572045Y41823D02*
Y47233D01*
X571345Y47933D01*
Y49914D01*
G01X592124Y59933D02*
Y54957D01*
G01X595470Y41823D02*
Y49914D01*
G01X562006Y59933D02*
Y54957D01*
G01X565352Y41823D02*
Y49614D01*
X565052Y49914D01*
G01X585431Y59933D02*
Y54957D01*
G01X588777Y41823D02*
Y49914D01*
G01X578738Y59933D02*
Y57347D01*
X576992Y55601D01*
Y54200D01*
X577692Y53500D01*
Y52200D01*
X576826Y51334D01*
X575932D01*
X575166Y52100D01*
G01X541927Y41823D02*
Y45395D01*
X541423Y45899D01*
Y46899D01*
X540423Y47899D01*
Y49200D01*
X541823Y50600D01*
X542569D01*
X543455Y49714D01*
G01X578738Y41823D02*
Y45355D01*
X577742Y46351D01*
Y49790D01*
X580266Y52314D01*
G01X575392Y59933D02*
Y57501D01*
X573596Y55705D01*
X573292Y55184D01*
Y51658D01*
X573636Y51030D01*
X575166Y49500D01*
G01X545273Y41823D02*
X545274Y41824D01*
Y46351D01*
X545423Y46500D01*
Y51300D01*
X544409Y52314D01*
X543455D01*
G01X582084Y41823D02*
Y47792D01*
X582792Y48500D01*
Y50270D01*
X582242Y50820D01*
X581372D01*
X580266Y49714D01*
G01X598817Y97733D02*
Y92657D01*
G01X555313Y523134D02*
Y518157D01*
G01X558659Y505024D02*
Y513114D01*
G01X548620Y523134D02*
Y518157D01*
G01X551966Y505024D02*
Y513114D01*
G01X568699Y523134D02*
Y518157D01*
G01X572045Y505024D02*
Y510433D01*
X571345Y511133D01*
Y513114D01*
G01X592124Y523134D02*
Y518157D01*
G01X595470Y505024D02*
Y513114D01*
G01X562006Y523134D02*
Y518157D01*
G01X565352Y505024D02*
Y512688D01*
X565266Y512774D01*
G01X585431Y523134D02*
Y518157D01*
G01X588777Y505024D02*
Y513114D01*
G01X578738Y523134D02*
X578739Y523132D01*
Y520548D01*
X576992Y518801D01*
Y517400D01*
X577692Y516700D01*
Y515400D01*
X576826Y514534D01*
X575932D01*
X575166Y515300D01*
G01X541927Y505024D02*
Y508595D01*
X541423Y509099D01*
Y510099D01*
X540423Y511099D01*
Y512400D01*
X541823Y513800D01*
X542569D01*
X543455Y512914D01*
G01X578738Y505024D02*
Y508595D01*
X578234Y509099D01*
Y510099D01*
X577234Y511099D01*
Y512400D01*
X578634Y513800D01*
X579380D01*
X580266Y512914D01*
G01X575392Y523134D02*
Y520701D01*
X573596Y518905D01*
X573292Y518384D01*
Y514858D01*
X573636Y514230D01*
X575166Y512700D01*
G01X545273Y505024D02*
X545274D01*
Y509551D01*
X545423Y509700D01*
Y514500D01*
X544409Y515514D01*
X543455D01*
G01X582084Y505024D02*
X582085D01*
Y509551D01*
X582234Y509700D01*
Y514500D01*
X581220Y515514D01*
X580266D01*
G01X555313Y560934D02*
Y555957D01*
G01X558659Y542824D02*
Y550914D01*
G01X548620Y560934D02*
Y555957D01*
G01X551966Y542824D02*
Y550914D01*
G01X568699Y560934D02*
Y555957D01*
G01X572045Y542824D02*
Y548233D01*
X571345Y548933D01*
Y550914D01*
G01X592124Y560934D02*
Y555957D01*
G01X595470Y542824D02*
Y550914D01*
G01X562006Y560934D02*
Y555957D01*
G01X565352Y542824D02*
Y550488D01*
X565266Y550574D01*
G01X585431Y560934D02*
Y555957D01*
G01X588777Y542824D02*
Y550914D01*
G01X578738Y560934D02*
X578739Y560932D01*
Y558348D01*
X576992Y556601D01*
Y555200D01*
X577692Y554500D01*
Y553200D01*
X576826Y552334D01*
X575932D01*
X575166Y553100D01*
G01X541927Y542824D02*
Y546395D01*
X541423Y546899D01*
Y547899D01*
X540423Y548899D01*
Y550200D01*
X541823Y551600D01*
X542569D01*
X543455Y550714D01*
G01X578738Y542824D02*
Y546395D01*
X578234Y546899D01*
Y547899D01*
X577234Y548899D01*
Y550200D01*
X578634Y551600D01*
X579380D01*
X580266Y550714D01*
G01X575392Y560934D02*
Y558501D01*
X573596Y556705D01*
X573292Y556184D01*
Y552658D01*
X573636Y552030D01*
X575166Y550500D01*
G01X545273Y542824D02*
X545274D01*
Y547351D01*
X545423Y547500D01*
Y552300D01*
X544409Y553314D01*
X543455D01*
G01X582084Y542824D02*
X582085D01*
Y547351D01*
X582234Y547500D01*
Y552300D01*
X581220Y553314D01*
X580266D01*
G01X558659Y580624D02*
Y588714D01*
G01X551966Y580624D02*
Y588714D01*
G01X572045Y580624D02*
Y586033D01*
X571345Y586733D01*
Y588714D01*
G01X595470Y580624D02*
Y588714D01*
G01X565352Y580624D02*
Y588288D01*
X565052Y588588D01*
Y588714D01*
G01X588777Y580624D02*
Y588714D01*
G01X541927Y580624D02*
Y584195D01*
X541423Y584699D01*
Y585699D01*
X540423Y586699D01*
Y588000D01*
X541823Y589400D01*
X542569D01*
X543455Y588514D01*
G01X578738Y580624D02*
Y584195D01*
X578234Y584699D01*
Y585699D01*
X577234Y586699D01*
Y588000D01*
X578634Y589400D01*
X579380D01*
X580266Y588514D01*
G01X575392Y598734D02*
Y596301D01*
X573596Y594505D01*
X573292Y593984D01*
Y590458D01*
X573636Y589830D01*
X575166Y588300D01*
G01X545273Y580624D02*
X545274D01*
Y585151D01*
X545423Y585300D01*
Y590100D01*
X544409Y591114D01*
X543455D01*
G01X582084Y580624D02*
X582085D01*
Y585151D01*
X582234Y585300D01*
Y590100D01*
X581220Y591114D01*
X580266D01*
G01X555313Y598734D02*
Y593757D01*
G01X548620Y598734D02*
Y593757D01*
G01X568699Y598734D02*
Y593757D01*
G01X592124Y598734D02*
Y593757D01*
G01X562006Y598734D02*
Y593757D01*
G01X585431Y598734D02*
Y593757D01*
G01X578738Y598734D02*
X578739Y598732D01*
Y596148D01*
X576992Y594401D01*
Y593000D01*
X577692Y592300D01*
Y591000D01*
X576826Y590134D01*
X575932D01*
X575166Y590900D01*
G01X779923Y22133D02*
X779921D01*
Y17157D01*
G01X783269Y4023D02*
X783267D01*
Y9433D01*
X782567Y10133D01*
Y12114D01*
G01X773230Y22133D02*
X773228D01*
Y17157D01*
G01X776576Y4023D02*
X776574D01*
Y11814D01*
X776274Y12114D01*
G01X789962Y22133D02*
X789960D01*
Y19547D01*
X788214Y17801D01*
Y16400D01*
X788914Y15700D01*
Y14400D01*
X788048Y13534D01*
X787154D01*
X786388Y14300D01*
G01X786616Y22133D02*
X786614D01*
Y19701D01*
X784818Y17905D01*
X784514Y17384D01*
Y13858D01*
X784858Y13230D01*
X786388Y11700D01*
G01X779923Y97733D02*
X779921D01*
Y92757D01*
G01X783269Y79623D02*
X783267D01*
Y85033D01*
X782567Y85733D01*
Y87714D01*
G01X773230Y97733D02*
X773228D01*
Y92757D01*
G01X776576Y79623D02*
X776574D01*
Y87414D01*
X776274Y87714D01*
G01X786388Y89900D02*
X787154Y89134D01*
X788048D01*
X788914Y90000D01*
Y91300D01*
X788214Y92000D01*
Y93401D01*
X789961Y95148D01*
Y97732D01*
X789962Y97733D01*
G01X786616D02*
X786614D01*
Y95301D01*
X784818Y93505D01*
X784514Y92984D01*
Y89458D01*
X784858Y88830D01*
X786388Y87300D01*
G01X779923Y59933D02*
X779921D01*
Y54957D01*
G01X783269Y41823D02*
X783267D01*
Y47233D01*
X782567Y47933D01*
Y49914D01*
G01X773230Y59933D02*
X773228D01*
Y54957D01*
G01X776576Y41823D02*
X776574D01*
Y47527D01*
X776274Y47827D01*
Y49914D01*
G01X789962Y59933D02*
X789960D01*
Y57347D01*
X788214Y55601D01*
Y54200D01*
X788914Y53500D01*
Y52200D01*
X788048Y51334D01*
X787154D01*
X786388Y52100D01*
G01X786616Y59933D02*
X786614D01*
Y57501D01*
X784818Y55705D01*
X784514Y55184D01*
Y51658D01*
X784858Y51030D01*
X786388Y49500D01*
G01X779923Y523134D02*
X779921Y523133D01*
Y518157D01*
G01X783269Y505024D02*
X783267D01*
Y510433D01*
X782567Y511133D01*
Y513114D01*
G01X773230Y523134D02*
X773228Y523133D01*
Y518157D01*
G01X776576Y505024D02*
X776574D01*
Y512814D01*
X776274Y513114D01*
G01X789962Y523134D02*
X789961Y523132D01*
Y520548D01*
X788214Y518801D01*
Y517400D01*
X788914Y516700D01*
Y515400D01*
X788048Y514534D01*
X787154D01*
X786388Y515300D01*
G01X786616Y523134D02*
X786614Y523133D01*
Y520701D01*
X784818Y518905D01*
X784514Y518384D01*
Y514858D01*
X784858Y514230D01*
X786388Y512700D01*
G01X779923Y560934D02*
X779921Y560933D01*
Y555957D01*
G01X783269Y542824D02*
X783267D01*
Y548233D01*
X782567Y548933D01*
Y550914D01*
G01X773230Y560934D02*
X773228Y560933D01*
Y555957D01*
G01X776576Y542824D02*
X776574D01*
Y550614D01*
X776274Y550914D01*
G01X786388Y553100D02*
X787154Y552334D01*
X788048D01*
X788914Y553200D01*
Y554500D01*
X788214Y555200D01*
Y556601D01*
X789961Y558348D01*
Y560932D01*
X789962Y560934D01*
G01X786616D02*
X786614Y560933D01*
Y558501D01*
X784818Y556705D01*
X784514Y556184D01*
Y552658D01*
X784858Y552030D01*
X786388Y550500D01*
G01X783269Y580624D02*
X783267D01*
Y586033D01*
X782567Y586733D01*
Y588714D01*
G01X776576Y580624D02*
X776574D01*
Y588414D01*
X776274Y588714D01*
G01X786616Y598734D02*
X786614Y598733D01*
Y596301D01*
X784818Y594505D01*
X784514Y593984D01*
Y590458D01*
X784858Y589830D01*
X786388Y588300D01*
G01X779923Y598734D02*
X779921Y598733D01*
Y593757D01*
G01X773230Y598734D02*
X773228Y598733D01*
Y593757D01*
G01X789962Y598734D02*
X789961Y598732D01*
Y596148D01*
X788214Y594401D01*
Y593000D01*
X788914Y592300D01*
Y591000D01*
X788048Y590134D01*
X787154D01*
X786388Y590900D01*
G01X840159Y22133D02*
X840157D01*
Y17157D01*
G01X843506Y4023D02*
Y12111D01*
X843503Y12114D01*
G01X810041Y22133D02*
X810039D01*
Y17157D01*
G01X813387Y4023D02*
X813385D01*
Y11814D01*
X813085Y12114D01*
G01X833466Y22133D02*
X833464D01*
Y17157D01*
G01X836813Y4023D02*
Y12111D01*
X836810Y12114D01*
G01X846852Y22133D02*
X846850D01*
Y17157D01*
G01X803348Y22133D02*
X803346D01*
Y17157D01*
G01X806694Y4023D02*
X806692D01*
Y12114D01*
G01X796655Y22133D02*
X796653D01*
Y17157D01*
G01X800002Y4023D02*
Y12111D01*
X799999Y12114D01*
G01X816734Y22133D02*
X816732D01*
Y17157D01*
G01X820080Y4023D02*
X820078D01*
Y9433D01*
X819378Y10133D01*
Y12114D01*
G01X789962Y4023D02*
X789960D01*
Y7555D01*
X788964Y8551D01*
Y11990D01*
X791488Y14514D01*
G01X826773Y22133D02*
X826771D01*
Y19547D01*
X825025Y17801D01*
Y16400D01*
X825725Y15700D01*
Y14400D01*
X824859Y13534D01*
X823965D01*
X823199Y14300D01*
G01X826773Y4023D02*
X826771D01*
Y7555D01*
X825775Y8551D01*
Y11990D01*
X828299Y14514D01*
G01X793309Y4023D02*
X793307D01*
Y9993D01*
X794014Y10700D01*
Y12470D01*
X793464Y13020D01*
X792594D01*
X791488Y11914D01*
G01X823427Y22133D02*
X823425D01*
Y19701D01*
X821629Y17905D01*
X821325Y17384D01*
Y13858D01*
X821669Y13230D01*
X823199Y11700D01*
G01X830120Y4023D02*
X830118D01*
Y9993D01*
X830825Y10700D01*
Y12470D01*
X830275Y13020D01*
X829405D01*
X828299Y11914D01*
G01X840159Y97733D02*
X840157D01*
Y92757D01*
G01X843506Y79623D02*
Y87711D01*
X843503Y87714D01*
G01X810041Y97733D02*
X810039D01*
Y92757D01*
G01X813387Y79623D02*
X813385D01*
Y87414D01*
X813085Y87714D01*
G01X833466Y97733D02*
X833464D01*
Y92757D01*
G01X836813Y79623D02*
Y87711D01*
X836810Y87714D01*
G01X846852Y97733D02*
X846850D01*
Y92757D01*
G01X803348Y97733D02*
X803346D01*
Y92757D01*
G01X806694Y79623D02*
X806692D01*
Y87714D01*
G01X796655Y97733D02*
X796653D01*
Y92757D01*
G01X800002Y79623D02*
Y87711D01*
X799999Y87714D01*
G01X816734Y97733D02*
X816732D01*
Y92757D01*
G01X820080Y79623D02*
X820078D01*
Y85033D01*
X819378Y85733D01*
Y87714D01*
G01X789962Y79623D02*
X789960D01*
Y83195D01*
X789456Y83699D01*
Y84699D01*
X788456Y85699D01*
Y87000D01*
X789856Y88400D01*
X790602D01*
X791488Y87514D01*
G01X823199Y89900D02*
X823965Y89134D01*
X824859D01*
X825725Y90000D01*
Y91300D01*
X825025Y92000D01*
Y93401D01*
X826772Y95148D01*
Y97732D01*
X826773Y97733D01*
G01Y79623D02*
X826771D01*
Y83195D01*
X826267Y83699D01*
Y84699D01*
X825267Y85699D01*
Y87000D01*
X826667Y88400D01*
X827413D01*
X828299Y87514D01*
G01X793309Y79623D02*
X793307D01*
Y84151D01*
X793456Y84300D01*
Y89100D01*
X792442Y90114D01*
X791488D01*
G01X823427Y97733D02*
X823425D01*
Y95301D01*
X821629Y93505D01*
X821325Y92984D01*
Y89458D01*
X821669Y88830D01*
X823199Y87300D01*
G01X830120Y79623D02*
X830118D01*
Y84151D01*
X830267Y84300D01*
Y89100D01*
X829253Y90114D01*
X828299D01*
G01X840159Y59933D02*
X840157D01*
Y54957D01*
G01X843506Y41823D02*
X843504D01*
Y42543D01*
X843503Y42544D01*
Y49914D01*
G01X810041Y59933D02*
X810039D01*
Y54957D01*
G01X813387Y41823D02*
X813385D01*
Y49614D01*
X813085Y49914D01*
G01X833466Y59933D02*
X833464D01*
Y54957D01*
G01X836813Y41823D02*
X836811D01*
Y42443D01*
X836810Y42444D01*
Y49914D01*
G01X846852Y59933D02*
X846850D01*
Y54957D01*
G01X803348Y59933D02*
X803346D01*
Y54957D01*
G01X806694Y41823D02*
X806692D01*
Y49914D01*
G01X796655Y59933D02*
X796653D01*
Y54957D01*
G01X800002Y41823D02*
X800000D01*
Y43743D01*
X799999Y43744D01*
Y49914D01*
G01X816734Y59933D02*
X816732D01*
Y54957D01*
G01X820080Y41823D02*
X820078D01*
Y47123D01*
X819378Y47823D01*
Y49914D01*
G01X789962Y41823D02*
X789960D01*
Y45355D01*
X788964Y46351D01*
Y49790D01*
X791488Y52314D01*
G01X826773Y59933D02*
X826771D01*
Y57347D01*
X825025Y55601D01*
Y54200D01*
X825725Y53500D01*
Y52200D01*
X824859Y51334D01*
X823965D01*
X823199Y52100D01*
G01X826773Y41823D02*
X826771D01*
Y45355D01*
X825775Y46351D01*
Y49790D01*
X828299Y52314D01*
G01X793309Y41823D02*
X793307D01*
Y43199D01*
X793306Y43200D01*
Y47792D01*
X794014Y48500D01*
Y50270D01*
X793464Y50820D01*
X792594D01*
X791488Y49714D01*
G01X823427Y59933D02*
X823425D01*
Y57501D01*
X821629Y55705D01*
X821325Y55184D01*
Y51658D01*
X821669Y51030D01*
X823199Y49500D01*
G01X830120Y41823D02*
X830118D01*
Y43199D01*
X830117Y43200D01*
Y47016D01*
X830825Y47724D01*
Y50270D01*
X830275Y50820D01*
X829405D01*
X828299Y49714D01*
G01X840159Y523134D02*
X840157Y523133D01*
Y518157D01*
G01X843503Y513114D02*
Y505024D01*
X843506D01*
G01X810041Y523134D02*
X810039Y523133D01*
Y518157D01*
G01X813085Y513114D02*
X813385Y512814D01*
Y505024D01*
X813387D01*
G01X833466Y523134D02*
X833464Y523133D01*
Y518157D01*
G01X836813Y505024D02*
Y513111D01*
X836810Y513114D01*
G01X846852Y523134D02*
X846850Y523133D01*
Y518157D01*
G01X803348Y523134D02*
X803346Y523133D01*
Y518157D01*
G01X806694Y505024D02*
X806692D01*
Y513114D01*
G01X796655Y523134D02*
X796653Y523133D01*
Y518157D01*
G01X800002Y505024D02*
X799999D01*
Y513114D01*
G01X816734Y523134D02*
X816732Y523133D01*
Y518157D01*
G01X820080Y505024D02*
X820078D01*
Y510433D01*
X819378Y511133D01*
Y513114D01*
G01X789962Y505024D02*
X789960D01*
Y508595D01*
X789456Y509099D01*
Y510099D01*
X788456Y511099D01*
Y512400D01*
X789856Y513800D01*
X790602D01*
X791488Y512914D01*
G01X826773Y523134D02*
X826772Y523132D01*
Y520548D01*
X825025Y518801D01*
Y517400D01*
X825725Y516700D01*
Y515400D01*
X824859Y514534D01*
X823965D01*
X823199Y515300D01*
G01X828299Y512914D02*
X827413Y513800D01*
X826667D01*
X825267Y512400D01*
Y511099D01*
X826267Y510099D01*
Y509099D01*
X826771Y508595D01*
Y505024D01*
X826773D01*
G01X793309D02*
X793307D01*
Y509551D01*
X793456Y509700D01*
Y514500D01*
X792442Y515514D01*
X791488D01*
G01X823427Y523134D02*
X823425Y523133D01*
Y520701D01*
X821629Y518905D01*
X821325Y518384D01*
Y514858D01*
X821669Y514230D01*
X823199Y512700D01*
G01X830120Y505024D02*
X830118D01*
Y509551D01*
X830267Y509700D01*
Y514500D01*
X829253Y515514D01*
X828299D01*
G01X840159Y560934D02*
X840157Y560933D01*
Y555957D01*
G01X843506Y542824D02*
X843503D01*
Y550914D01*
G01X810041Y560934D02*
X810039Y560933D01*
Y555957D01*
G01X813387Y542824D02*
X813385D01*
Y550614D01*
X813085Y550914D01*
G01X833466Y560934D02*
X833464Y560933D01*
Y555957D01*
G01X836813Y542824D02*
Y550911D01*
X836810Y550914D01*
G01X846852Y560934D02*
X846850Y560933D01*
Y555957D01*
G01X803348Y560934D02*
X803346Y560933D01*
Y555957D01*
G01X806694Y542824D02*
X806692D01*
Y550914D01*
G01X796655Y560934D02*
X796653Y560933D01*
Y555957D01*
G01X800002Y542824D02*
X799999D01*
Y550914D01*
G01X816734Y560934D02*
X816732Y560933D01*
Y555957D01*
G01X820080Y542824D02*
X820078D01*
Y548233D01*
X819378Y548933D01*
Y550914D01*
G01X789962Y542824D02*
X789960D01*
Y546395D01*
X789456Y546899D01*
Y547899D01*
X788456Y548899D01*
Y550200D01*
X789856Y551600D01*
X790602D01*
X791488Y550714D01*
G01X823199Y553100D02*
X823965Y552334D01*
X824859D01*
X825725Y553200D01*
Y554500D01*
X825025Y555200D01*
Y556601D01*
X826772Y558348D01*
Y560932D01*
X826773Y560934D01*
G01Y542824D02*
X826771D01*
Y546395D01*
X826267Y546899D01*
Y547899D01*
X825267Y548899D01*
Y550200D01*
X826667Y551600D01*
X827413D01*
X828299Y550714D01*
G01X793309Y542824D02*
X793307D01*
Y547351D01*
X793456Y547500D01*
Y552300D01*
X792442Y553314D01*
X791488D01*
G01X823427Y560934D02*
X823425Y560933D01*
Y558501D01*
X821629Y556705D01*
X821325Y556184D01*
Y552658D01*
X821669Y552030D01*
X823199Y550500D01*
G01X830120Y542824D02*
X830118D01*
Y547351D01*
X830267Y547500D01*
Y552300D01*
X829253Y553314D01*
X828299D01*
G01X843506Y580624D02*
X843503D01*
Y588714D01*
G01X813387Y580624D02*
X813385D01*
Y588414D01*
X813085Y588714D01*
G01X836813Y580624D02*
Y588711D01*
X836810Y588714D01*
G01X806694Y580624D02*
X806692D01*
Y588714D01*
G01X800002Y580624D02*
X799999D01*
Y588714D01*
G01X820080Y580624D02*
X820078D01*
Y586033D01*
X819378Y586733D01*
Y588714D01*
G01X789962Y580624D02*
X789960D01*
Y584195D01*
X789456Y584699D01*
Y585699D01*
X788456Y586699D01*
Y588000D01*
X789856Y589400D01*
X790602D01*
X791488Y588514D01*
G01X826773Y580624D02*
X826771D01*
Y584195D01*
X826267Y584699D01*
Y585699D01*
X825267Y586699D01*
Y588000D01*
X826667Y589400D01*
X827413D01*
X828299Y588514D01*
G01X793309Y580624D02*
X793307D01*
Y585151D01*
X793456Y585300D01*
Y590100D01*
X792442Y591114D01*
X791488D01*
G01X823427Y598734D02*
X823425Y598733D01*
Y596301D01*
X821629Y594505D01*
X821325Y593984D01*
Y590458D01*
X821669Y589830D01*
X823199Y588300D01*
G01X830120Y580624D02*
X830118D01*
Y585151D01*
X830267Y585300D01*
Y590100D01*
X829253Y591114D01*
X828299D01*
G01X840159Y598734D02*
X840157Y598733D01*
Y593757D01*
G01X810041Y598734D02*
X810039Y598733D01*
Y593757D01*
G01X833466Y598734D02*
X833464Y598733D01*
Y593757D01*
G01X846852Y598734D02*
X846850Y598733D01*
Y593757D01*
G01X803348Y598734D02*
X803346Y598733D01*
Y593757D01*
G01X796655Y598734D02*
X796653Y598733D01*
Y593757D01*
G01X816734Y598734D02*
X816732Y598733D01*
Y593757D01*
G01X826773Y598734D02*
X826772Y598732D01*
Y596148D01*
X825025Y594401D01*
Y593000D01*
X825725Y592300D01*
Y591000D01*
X824859Y590134D01*
X823965D01*
X823199Y590900D01*
G01X853545Y22133D02*
X853543D01*
Y17157D01*
G01X856891Y4023D02*
X856889D01*
Y9433D01*
X856189Y10133D01*
Y12114D01*
G01X876970Y22133D02*
X876968D01*
Y17157D01*
G01X880317Y4023D02*
Y12111D01*
X880314Y12114D01*
G01X850198Y4023D02*
X850196D01*
Y11814D01*
X849896Y12114D01*
G01X870277Y22133D02*
X870275D01*
Y17157D01*
G01X873624Y4023D02*
Y12111D01*
X873621Y12114D01*
G01X890356Y22133D02*
X890354D01*
Y17157D01*
G01X893702Y4023D02*
X893700D01*
Y9433D01*
X893000Y10133D01*
Y12114D01*
G01X883663Y22133D02*
X883661D01*
Y17157D01*
G01X887009Y4023D02*
X887007D01*
Y11814D01*
X886707Y12114D01*
G01X907088Y22133D02*
X907086D01*
Y17157D01*
G01X863584Y22133D02*
X863582D01*
Y19547D01*
X861836Y17801D01*
Y16400D01*
X862536Y15700D01*
Y14400D01*
X861670Y13534D01*
X860776D01*
X860010Y14300D01*
G01X900395Y22133D02*
X900393D01*
Y19547D01*
X898647Y17801D01*
Y16400D01*
X899347Y15700D01*
Y14400D01*
X898481Y13534D01*
X897587D01*
X896821Y14300D01*
G01X863584Y4023D02*
X863582D01*
Y7555D01*
X862586Y8551D01*
Y11990D01*
X865110Y14514D01*
G01X900395Y4023D02*
X900393D01*
Y7555D01*
X899397Y8551D01*
Y11990D01*
X901921Y14514D01*
G01X860238Y22133D02*
X860236D01*
Y19701D01*
X858440Y17905D01*
X858136Y17384D01*
Y13858D01*
X858480Y13230D01*
X860010Y11700D01*
G01X897049Y22133D02*
X897047D01*
Y19701D01*
X895251Y17905D01*
X894947Y17384D01*
Y13858D01*
X895291Y13230D01*
X896821Y11700D01*
G01X866931Y4023D02*
X866929D01*
Y9993D01*
X867636Y10700D01*
Y12470D01*
X867086Y13020D01*
X866216D01*
X865110Y11914D01*
G01X903742Y4023D02*
X903740D01*
Y9993D01*
X904447Y10700D01*
Y12470D01*
X903897Y13020D01*
X903027D01*
X901921Y11914D01*
G01X853545Y97733D02*
X853543D01*
Y92757D01*
G01X856891Y79623D02*
X856889D01*
Y85033D01*
X856189Y85733D01*
Y87714D01*
G01X876970Y97733D02*
X876968D01*
Y92757D01*
G01X880317Y79623D02*
Y87711D01*
X880314Y87714D01*
G01X850198Y79623D02*
X850196D01*
Y87414D01*
X849896Y87714D01*
G01X870277Y97733D02*
X870275D01*
Y92761D01*
G01X873621Y87714D02*
Y79626D01*
X873624Y79623D01*
G01X890356Y97733D02*
X890354D01*
Y92757D01*
G01X893702Y79623D02*
X893700D01*
Y85033D01*
X893000Y85733D01*
Y87714D01*
G01X883663Y97733D02*
X883661D01*
Y92757D01*
G01X887009Y79623D02*
X887007D01*
Y87414D01*
X886707Y87714D01*
G01X907088Y97733D02*
X907086D01*
Y92757D01*
G01X863584Y97733D02*
X863583Y97732D01*
Y95148D01*
X861836Y93401D01*
Y92000D01*
X862536Y91300D01*
Y90000D01*
X861670Y89134D01*
X860776D01*
X860010Y89900D01*
G01X896821D02*
X897587Y89134D01*
X898481D01*
X899347Y90000D01*
Y91300D01*
X898647Y92000D01*
Y93401D01*
X900394Y95148D01*
Y97732D01*
X900395Y97733D01*
G01X863584Y79623D02*
X863582D01*
Y83195D01*
X863078Y83699D01*
Y84699D01*
X862078Y85699D01*
Y87000D01*
X863478Y88400D01*
X864224D01*
X865110Y87514D01*
G01X900395Y79623D02*
X900393D01*
Y83195D01*
X899889Y83699D01*
Y84699D01*
X898889Y85699D01*
Y87000D01*
X900289Y88400D01*
X901035D01*
X901921Y87514D01*
G01X860238Y97733D02*
X860236D01*
Y95301D01*
X858440Y93505D01*
X858136Y92984D01*
Y89458D01*
X858480Y88830D01*
X860010Y87300D01*
G01X897049Y97733D02*
X897047D01*
Y95301D01*
X895251Y93505D01*
X894947Y92984D01*
Y89458D01*
X895291Y88830D01*
X896821Y87300D01*
G01X866931Y79623D02*
X866929D01*
Y84151D01*
X867078Y84300D01*
Y89100D01*
X866064Y90114D01*
X865110D01*
G01X903742Y79623D02*
X903740D01*
Y84151D01*
X903889Y84300D01*
Y89100D01*
X902875Y90114D01*
X901921D01*
G01X853545Y59933D02*
X853543D01*
Y54957D01*
G01X856891Y41823D02*
X856889D01*
Y47233D01*
X856189Y47933D01*
Y49914D01*
G01X876970Y59933D02*
Y54959D01*
X876968Y54957D01*
G01X880317Y41823D02*
X880315D01*
Y42843D01*
X880314Y42844D01*
Y49914D01*
G01X850198Y41823D02*
X850196D01*
Y49614D01*
X849896Y49914D01*
G01X870277Y59933D02*
X870275D01*
Y54957D01*
G01X873624Y41823D02*
X873622D01*
Y43743D01*
X873621Y43744D01*
Y49914D01*
G01X890356Y59933D02*
X890354D01*
Y54957D01*
G01X893702Y41823D02*
X893700D01*
Y47233D01*
X893000Y47933D01*
Y49914D01*
G01X883663Y59933D02*
X883661D01*
Y54957D01*
G01X887009Y41823D02*
X887007D01*
Y49614D01*
X886707Y49914D01*
G01X907088Y59933D02*
X907086D01*
Y54957D01*
G01X863584Y59933D02*
X863582D01*
Y57347D01*
X861836Y55601D01*
Y54200D01*
X862536Y53500D01*
Y52200D01*
X861670Y51334D01*
X860776D01*
X860010Y52100D01*
G01X896821D02*
X897587Y51334D01*
X898481D01*
X899347Y52200D01*
Y53500D01*
X898647Y54200D01*
Y55601D01*
X900394Y57348D01*
Y59932D01*
X900395Y59933D01*
G01X863584Y41823D02*
X863582D01*
Y45355D01*
X862586Y46351D01*
Y49790D01*
X865110Y52314D01*
G01X900395Y41823D02*
X900393D01*
Y45395D01*
X899889Y45899D01*
Y46899D01*
X898889Y47899D01*
Y49200D01*
X900289Y50600D01*
X901035D01*
X901921Y49714D01*
G01X860238Y59933D02*
X860236D01*
Y57501D01*
X858440Y55705D01*
X858136Y55184D01*
Y51658D01*
X858480Y51030D01*
X860010Y49500D01*
G01X897049Y59933D02*
X897047D01*
Y57501D01*
X895251Y55705D01*
X894947Y55184D01*
Y51658D01*
X895291Y51030D01*
X896821Y49500D01*
G01X866931Y41823D02*
X866929D01*
Y43199D01*
X866928Y43200D01*
Y47792D01*
X867636Y48500D01*
Y50270D01*
X867086Y50820D01*
X866216D01*
X865110Y49714D01*
G01X903742Y41823D02*
X903740D01*
Y46351D01*
X903889Y46500D01*
Y51300D01*
X902875Y52314D01*
X901921D01*
G01X853545Y523134D02*
X853543Y523133D01*
Y518157D01*
G01X856891Y505024D02*
X856889D01*
Y510433D01*
X856189Y511133D01*
Y513114D01*
G01X876970Y523134D02*
X876968Y523133D01*
Y518157D01*
G01X880317Y505024D02*
Y513111D01*
X880314Y513114D01*
G01X850198Y505024D02*
X850196D01*
Y512814D01*
X849896Y513114D01*
G01X870277Y523134D02*
X870275Y523133D01*
Y518161D01*
G01X873624Y505024D02*
X873621D01*
Y513114D01*
G01X890356Y523134D02*
X890354Y523133D01*
Y518157D01*
G01X893702Y505024D02*
X893700D01*
Y510433D01*
X893000Y511133D01*
Y513114D01*
G01X883663Y523134D02*
X883661Y523133D01*
Y518157D01*
G01X887009Y505024D02*
X887007D01*
Y512814D01*
X886707Y513114D01*
G01X907088Y523134D02*
X907086Y523133D01*
Y518157D01*
G01X863584Y523134D02*
X863583Y523132D01*
Y520548D01*
X861836Y518801D01*
Y517400D01*
X862536Y516700D01*
Y515400D01*
X861670Y514534D01*
X860776D01*
X860010Y515300D01*
G01X900395Y523134D02*
X900394Y523132D01*
Y520548D01*
X898647Y518801D01*
Y517400D01*
X899347Y516700D01*
Y515400D01*
X898481Y514534D01*
X897587D01*
X896821Y515300D01*
G01X863584Y505024D02*
X863582D01*
Y508595D01*
X863078Y509099D01*
Y510099D01*
X862078Y511099D01*
Y512400D01*
X863478Y513800D01*
X864224D01*
X865110Y512914D01*
G01X900395Y505024D02*
X900393D01*
Y508595D01*
X899889Y509099D01*
Y510099D01*
X898889Y511099D01*
Y512400D01*
X900289Y513800D01*
X901035D01*
X901921Y512914D01*
G01X860238Y523134D02*
X860236Y523133D01*
Y520701D01*
X858440Y518905D01*
X858136Y518384D01*
Y514858D01*
X858480Y514230D01*
X860010Y512700D01*
G01X897049Y523134D02*
X897047Y523133D01*
Y520701D01*
X895251Y518905D01*
X894947Y518384D01*
Y514858D01*
X895291Y514230D01*
X896821Y512700D01*
G01X865110Y515514D02*
X866064D01*
X867078Y514500D01*
Y509700D01*
X866929Y509551D01*
Y505024D01*
X866931D01*
G01X903742D02*
X903740D01*
Y509551D01*
X903889Y509700D01*
Y514500D01*
X902875Y515514D01*
X901921D01*
G01X853545Y560934D02*
X853543Y560933D01*
Y555957D01*
G01X856891Y542824D02*
X856889D01*
Y548233D01*
X856189Y548933D01*
Y550914D01*
G01X876970Y560934D02*
X876968Y560933D01*
Y555957D01*
G01X880317Y542824D02*
Y550911D01*
X880314Y550914D01*
G01X850198Y542824D02*
X850196D01*
Y550614D01*
X849896Y550914D01*
G01X870277Y560934D02*
X870275Y560933D01*
Y555961D01*
G01X873624Y542824D02*
X873621D01*
Y550914D01*
G01X890356Y560934D02*
X890354Y560933D01*
Y555957D01*
G01X893702Y542824D02*
X893700D01*
Y548233D01*
X893000Y548933D01*
Y550914D01*
G01X883663Y560934D02*
X883661Y560933D01*
Y555957D01*
G01X887009Y542824D02*
X887007D01*
Y550614D01*
X886707Y550914D01*
G01X907088Y560934D02*
X907086Y560933D01*
Y555957D01*
G01X860010Y553100D02*
X860776Y552334D01*
X861670D01*
X862536Y553200D01*
Y554500D01*
X861836Y555200D01*
Y556601D01*
X863583Y558348D01*
Y560932D01*
X863584Y560934D01*
G01X896821Y553100D02*
X897587Y552334D01*
X898481D01*
X899347Y553200D01*
Y554500D01*
X898647Y555200D01*
Y556601D01*
X900394Y558348D01*
Y560932D01*
X900395Y560934D01*
G01X863584Y542824D02*
X863582D01*
Y546395D01*
X863078Y546899D01*
Y547899D01*
X862078Y548899D01*
Y550200D01*
X863478Y551600D01*
X864224D01*
X865110Y550714D01*
G01X900395Y542824D02*
X900393D01*
Y546395D01*
X899889Y546899D01*
Y547899D01*
X898889Y548899D01*
Y550200D01*
X900289Y551600D01*
X901035D01*
X901921Y550714D01*
G01X860238Y560934D02*
X860236Y560933D01*
Y558501D01*
X858440Y556705D01*
X858136Y556184D01*
Y552658D01*
X858480Y552030D01*
X860010Y550500D01*
G01X897049Y560934D02*
X897047Y560933D01*
Y558501D01*
X895251Y556705D01*
X894947Y556184D01*
Y552658D01*
X895291Y552030D01*
X896821Y550500D01*
G01X866931Y542824D02*
X866929D01*
Y547351D01*
X867078Y547500D01*
Y552300D01*
X866064Y553314D01*
X865110D01*
G01X903742Y542824D02*
X903740D01*
Y547351D01*
X903889Y547500D01*
Y552300D01*
X902875Y553314D01*
X901921D01*
G01X856891Y580624D02*
X856889D01*
Y586033D01*
X856189Y586733D01*
Y588714D01*
G01X880317Y580624D02*
Y588711D01*
X880314Y588714D01*
G01X849896D02*
X850196Y588414D01*
Y580624D01*
X850198D01*
G01X873624D02*
X873621D01*
Y588714D01*
G01X893702Y580624D02*
X893700D01*
Y586033D01*
X893000Y586733D01*
Y588714D01*
G01X887009Y580624D02*
X887007D01*
Y588414D01*
X886707Y588714D01*
G01X863584Y580624D02*
X863582D01*
Y584195D01*
X863078Y584699D01*
Y585699D01*
X862078Y586699D01*
Y588000D01*
X863478Y589400D01*
X864224D01*
X865110Y588514D01*
G01X901921D02*
X901035Y589400D01*
X900289D01*
X898889Y588000D01*
Y586699D01*
X899889Y585699D01*
Y584699D01*
X900393Y584195D01*
Y580624D01*
X900395D01*
G01X860238Y598734D02*
X860236Y598733D01*
Y596301D01*
X858440Y594505D01*
X858136Y593984D01*
Y590458D01*
X858480Y589830D01*
X860010Y588300D01*
G01X897049Y598734D02*
X897047Y598733D01*
Y596301D01*
X895251Y594505D01*
X894947Y593984D01*
Y590458D01*
X895291Y589830D01*
X896821Y588300D01*
G01X866931Y580624D02*
X866929D01*
Y585151D01*
X867078Y585300D01*
Y590100D01*
X866064Y591114D01*
X865110D01*
G01X903742Y580624D02*
X903740D01*
Y585151D01*
X903889Y585300D01*
Y590100D01*
X902875Y591114D01*
X901921D01*
G01X853545Y598734D02*
X853543Y598733D01*
Y593757D01*
G01X876970Y598734D02*
X876968Y598733D01*
Y593757D01*
G01X870277Y598734D02*
X870275Y598733D01*
Y593761D01*
G01X890356Y598734D02*
X890354Y598733D01*
Y593757D01*
G01X883663Y598734D02*
X883661Y598733D01*
Y593757D01*
G01X907088Y598734D02*
X907086Y598733D01*
Y593757D01*
G01X863584Y598734D02*
X863583Y598732D01*
Y596148D01*
X861836Y594401D01*
Y593000D01*
X862536Y592300D01*
Y591000D01*
X861670Y590134D01*
X860776D01*
X860010Y590900D01*
G01X900395Y598734D02*
X900394Y598732D01*
Y596148D01*
X898647Y594401D01*
Y593000D01*
X899347Y592300D01*
Y591000D01*
X898481Y590134D01*
X897587D01*
X896821Y590900D01*
G01X970671Y22133D02*
X970669D01*
Y17057D01*
G01X963978Y22133D02*
X963976D01*
Y17057D01*
G01X960631Y4023D02*
X960629D01*
Y9114D01*
G01X913781Y22133D02*
X913779D01*
Y17157D01*
G01X917128Y4023D02*
Y12111D01*
X917125Y12114D01*
G01X910435Y4023D02*
Y12111D01*
X910432Y12114D01*
G01X937206Y22133D02*
X937204D01*
Y19547D01*
X935458Y17801D01*
Y16400D01*
X936158Y15700D01*
Y14400D01*
X935292Y13534D01*
X934398D01*
X933632Y14300D01*
G01X937206Y4023D02*
X937204D01*
Y7555D01*
X936208Y8551D01*
Y11990D01*
X938732Y14514D01*
G01X933860Y22133D02*
X933858D01*
Y19701D01*
X932062Y17905D01*
X931758Y17384D01*
Y13858D01*
X932102Y13230D01*
X933632Y11700D01*
G01X940553Y4023D02*
X940551D01*
Y9991D01*
X940550Y9992D01*
X941258Y10700D01*
Y12470D01*
X940708Y13020D01*
X939838D01*
X938732Y11914D01*
G01X927167Y22133D02*
X927165D01*
Y17157D01*
G01X930513Y4023D02*
X930511D01*
Y9433D01*
X929811Y10133D01*
Y12114D01*
G01X950592Y22133D02*
X950590D01*
Y17157D01*
G01X953939Y4023D02*
Y12111D01*
X953936Y12114D01*
G01X920474Y22133D02*
X920472D01*
Y17157D01*
G01X923820Y4023D02*
X923818D01*
Y11814D01*
X923518Y12114D01*
G01X943899Y22133D02*
X943897D01*
Y17157D01*
G01X947246Y4023D02*
Y12111D01*
X947243Y12114D01*
G01X970671Y97733D02*
X970669D01*
Y92757D01*
G01X963978Y97733D02*
X963976D01*
Y92657D01*
G01X960631Y79623D02*
X960629D01*
Y84714D01*
G01X913781Y97733D02*
X913779D01*
Y92757D01*
G01X917128Y79623D02*
Y87711D01*
X917125Y87714D01*
G01X910435Y79623D02*
Y87711D01*
X910432Y87714D01*
G01X933632Y89900D02*
X934398Y89134D01*
X935292D01*
X936158Y90000D01*
Y91300D01*
X935458Y92000D01*
Y93401D01*
X937205Y95148D01*
Y97732D01*
X937206Y97733D01*
G01Y79623D02*
X937204D01*
Y83195D01*
X936700Y83699D01*
Y84699D01*
X935700Y85699D01*
Y87000D01*
X937100Y88400D01*
X937846D01*
X938732Y87514D01*
G01X933860Y97733D02*
X933858D01*
Y95301D01*
X932062Y93505D01*
X931758Y92984D01*
Y89458D01*
X932102Y88830D01*
X933632Y87300D01*
G01X940553Y79623D02*
X940551D01*
Y84151D01*
X940700Y84300D01*
Y89100D01*
X939686Y90114D01*
X938732D01*
G01X927167Y97733D02*
X927165D01*
Y92757D01*
G01X930513Y79623D02*
X930511D01*
Y85033D01*
X929811Y85733D01*
Y87714D01*
G01X950592Y97733D02*
X950590D01*
Y92757D01*
G01X953939Y79623D02*
X953937D01*
Y82573D01*
X953936Y82574D01*
Y87714D01*
G01X920474Y97733D02*
X920472D01*
Y92757D01*
G01X923820Y79623D02*
X923818D01*
Y87414D01*
X923518Y87714D01*
G01X943899Y97733D02*
X943897D01*
Y92757D01*
G01X947246Y79623D02*
Y87711D01*
X947243Y87714D01*
G01X970671Y59933D02*
X970669D01*
Y54857D01*
G01X963978Y59933D02*
X963976D01*
Y54857D01*
G01X960631Y41823D02*
X960629D01*
Y46914D01*
G01X913781Y59933D02*
X913779D01*
Y54957D01*
G01X917128Y41823D02*
X917126D01*
Y42343D01*
X917125Y42344D01*
Y49914D01*
G01X910435Y41823D02*
X910432D01*
Y49914D01*
G01X933632Y52100D02*
X934398Y51334D01*
X935292D01*
X936158Y52200D01*
Y53500D01*
X935458Y54200D01*
Y55601D01*
X937205Y57348D01*
Y59932D01*
X937206Y59933D01*
G01Y41823D02*
X937204D01*
Y45395D01*
X936700Y45899D01*
Y46899D01*
X935700Y47899D01*
Y49200D01*
X937100Y50600D01*
X937846D01*
X938732Y49714D01*
G01X933860Y59933D02*
X933858D01*
Y57501D01*
X932062Y55705D01*
X931758Y55184D01*
Y51658D01*
X932102Y51030D01*
X933632Y49500D01*
G01X940553Y41823D02*
X940551D01*
Y46351D01*
X940700Y46500D01*
Y51300D01*
X939686Y52314D01*
X938732D01*
G01X927167Y59933D02*
X927165D01*
Y54957D01*
G01X930513Y41823D02*
X930511D01*
Y47233D01*
X929811Y47933D01*
Y49914D01*
G01X950592Y59933D02*
Y54959D01*
X950590Y54957D01*
G01X953939Y41823D02*
Y49911D01*
X953936Y49914D01*
G01X920474Y59933D02*
X920472D01*
Y54957D01*
G01X923820Y41823D02*
X923818D01*
Y49614D01*
X923518Y49914D01*
G01X943899Y59933D02*
X943897D01*
Y54957D01*
G01X947246Y41823D02*
X947244D01*
Y43743D01*
X947243Y43744D01*
Y49914D01*
G01X968218Y254594D02*
X966724Y253100D01*
X964639D01*
G01X967589Y260093D02*
X966328D01*
X964639Y258404D01*
Y256600D01*
G01X970671Y523134D02*
X970669Y523133D01*
Y518157D01*
G01X963978Y523134D02*
X963976Y523133D01*
Y518057D01*
G01X960631Y505024D02*
X960629D01*
Y510114D01*
G01X913781Y523134D02*
X913779Y523133D01*
Y518157D01*
G01X917128Y505024D02*
X917125D01*
Y513114D01*
G01X910435Y505024D02*
Y513111D01*
X910432Y513114D01*
G01X937206Y523134D02*
X937205Y523132D01*
Y520548D01*
X935458Y518801D01*
Y517400D01*
X936158Y516700D01*
Y515400D01*
X935292Y514534D01*
X934398D01*
X933632Y515300D01*
G01X937206Y505024D02*
X937204D01*
Y508595D01*
X936700Y509099D01*
Y510099D01*
X935700Y511099D01*
Y512400D01*
X937100Y513800D01*
X937846D01*
X938732Y512914D01*
G01X933860Y523134D02*
X933858Y523133D01*
Y520701D01*
X932062Y518905D01*
X931758Y518384D01*
Y514858D01*
X932102Y514230D01*
X933632Y512700D01*
G01X938732Y515514D02*
X939686D01*
X940700Y514500D01*
Y509700D01*
X940551Y509551D01*
Y505024D01*
X940553D01*
G01X927167Y523134D02*
X927165Y523133D01*
Y518157D01*
G01X930513Y505024D02*
X930511D01*
Y510433D01*
X929811Y511133D01*
Y513114D01*
G01X950592Y523134D02*
X950590Y523133D01*
Y518157D01*
G01X953936Y513114D02*
Y507974D01*
X953937Y507973D01*
Y505024D01*
X953939D01*
G01X920474Y523134D02*
X920472Y523133D01*
Y518157D01*
G01X923820Y505024D02*
X923818D01*
Y512814D01*
X923518Y513114D01*
G01X943899Y523134D02*
X943897Y523133D01*
Y518157D01*
G01X947246Y505024D02*
X947243D01*
Y513114D01*
G01X970671Y560934D02*
X970669Y560933D01*
Y555857D01*
G01X963978Y560934D02*
X963976Y560933D01*
Y555857D01*
G01X960631Y542824D02*
X960629D01*
Y547914D01*
G01X913781Y560934D02*
X913779Y560933D01*
Y555957D01*
G01X917125Y550914D02*
Y542824D01*
X917128D01*
G01X910435D02*
Y550911D01*
X910432Y550914D01*
G01X933632Y553100D02*
X934398Y552334D01*
X935292D01*
X936158Y553200D01*
Y554500D01*
X935458Y555200D01*
Y556601D01*
X937205Y558348D01*
Y560932D01*
X937206Y560934D01*
G01Y542824D02*
X937204D01*
Y546395D01*
X936700Y546899D01*
Y547899D01*
X935700Y548899D01*
Y550200D01*
X937100Y551600D01*
X937846D01*
X938732Y550714D01*
G01X933860Y560934D02*
X933858Y560933D01*
Y558501D01*
X932062Y556705D01*
X931758Y556184D01*
Y552658D01*
X932102Y552030D01*
X933632Y550500D01*
G01X940553Y542824D02*
X940551D01*
Y547351D01*
X940700Y547500D01*
Y552300D01*
X939686Y553314D01*
X938732D01*
G01X927167Y560934D02*
X927165Y560933D01*
Y555957D01*
G01X930513Y542824D02*
X930511D01*
Y548233D01*
X929811Y548933D01*
Y550914D01*
G01X950592Y560934D02*
X950590Y560933D01*
Y555957D01*
G01X953939Y542824D02*
X953937D01*
Y545773D01*
X953936Y545774D01*
Y550914D01*
G01X920474Y560934D02*
X920472Y560933D01*
Y555957D01*
G01X923820Y542824D02*
X923818D01*
Y550614D01*
X923518Y550914D01*
G01X943899Y560934D02*
X943897Y560933D01*
Y555957D01*
G01X947243Y550914D02*
Y542824D01*
X947246D01*
G01X960631Y580624D02*
X960629D01*
Y585714D01*
G01X917128Y580624D02*
X917125D01*
Y588714D01*
G01X910435Y580624D02*
Y588711D01*
X910432Y588714D01*
G01X937206Y580624D02*
X937204D01*
Y584195D01*
X936700Y584699D01*
Y585699D01*
X935700Y586699D01*
Y588000D01*
X937100Y589400D01*
X937846D01*
X938732Y588514D01*
G01X933860Y598734D02*
X933858Y598733D01*
Y596301D01*
X932062Y594505D01*
X931758Y593984D01*
Y590458D01*
X932102Y589830D01*
X933632Y588300D01*
G01X938732Y591114D02*
X939686D01*
X940700Y590100D01*
Y585300D01*
X940551Y585151D01*
Y580624D01*
X940553D01*
G01X929811Y588714D02*
Y586733D01*
X930511Y586033D01*
Y580624D01*
X930513D01*
G01X953939D02*
X953937D01*
Y583573D01*
X953936Y583574D01*
Y588714D01*
G01X923518D02*
X923818Y588414D01*
Y580624D01*
X923820D01*
G01X947246D02*
X947243D01*
Y588714D01*
G01X970671Y598734D02*
X970669Y598733D01*
Y593657D01*
G01X963978Y598734D02*
X963976Y598733D01*
Y593657D01*
G01X913781Y598734D02*
X913779Y598733D01*
Y593757D01*
G01X937206Y598734D02*
X937205Y598732D01*
Y596148D01*
X935458Y594401D01*
Y593000D01*
X936158Y592300D01*
Y591000D01*
X935292Y590134D01*
X934398D01*
X933632Y590900D01*
G01X927167Y598734D02*
X927165Y598733D01*
Y593757D01*
G01X950592Y598734D02*
X950590Y598733D01*
Y593757D01*
G01X920474Y598734D02*
X920472Y598733D01*
Y593757D01*
G01X943899Y598734D02*
X943897Y598733D01*
Y593757D01*
G01X977364Y4023D02*
X977362D01*
Y9114D01*
G01X974017Y22133D02*
X974015D01*
Y17057D01*
G01X974017Y4023D02*
X974015D01*
Y9114D01*
G01X1014175Y22133D02*
X1014173D01*
Y17788D01*
X1014919Y17042D01*
G01X1014175Y4023D02*
X1014173D01*
Y9114D01*
G01X1010828Y22133D02*
X1010826D01*
Y20502D01*
X1012270Y17014D01*
G01X1010828Y4023D02*
X1010826D01*
Y9114D01*
G01X984057Y4023D02*
X984055D01*
Y9113D01*
X984054Y9114D01*
G01X980710Y22133D02*
X980708D01*
Y17057D01*
G01X1004135Y22133D02*
X1004133D01*
Y17158D01*
X1004134Y17157D01*
Y17057D01*
G01X1004135Y4023D02*
X1004133D01*
Y9122D01*
G01X1000789Y22133D02*
X1000787D01*
Y17057D01*
G01X997443Y4023D02*
X997441D01*
Y9122D01*
G01X994096Y4023D02*
X994094D01*
Y9122D01*
G01X994096Y22133D02*
X994094D01*
Y17057D01*
G01X987403Y4023D02*
X987401D01*
Y9114D01*
G01X990750Y22133D02*
X990748D01*
Y17057D01*
G01X984057Y22133D02*
X984055D01*
Y17057D01*
G01X977364Y79623D02*
X977362D01*
Y87392D01*
G01X974017Y97733D02*
X974015D01*
Y89964D01*
G01X974017Y79623D02*
X974015D01*
Y84599D01*
G01X1014175Y97733D02*
X1014173D01*
Y93542D01*
X1015215Y92500D01*
G01X1014175Y79623D02*
X1014173D01*
Y83528D01*
X1013687Y84014D01*
Y86345D01*
X1014842Y87500D01*
G01X1010828Y97733D02*
X1010826D01*
Y94074D01*
X1012400Y92500D01*
G01X1010828Y79623D02*
X1010826D01*
Y82325D01*
X1012537Y84036D01*
Y87006D01*
X1012043Y87500D01*
G01X984057Y79623D02*
X984055D01*
Y87392D01*
G01X980710Y97733D02*
X980708D01*
Y89964D01*
G01X1004135Y97733D02*
X1004133D01*
Y92867D01*
X1004023Y92757D01*
G01X1004135Y79623D02*
X1004133D01*
Y87282D01*
X1004023Y87392D01*
G01X1000789Y97733D02*
X1000787D01*
Y89964D01*
G01X997443Y79623D02*
X997441D01*
Y87392D01*
G01X994096Y79623D02*
X994094D01*
Y84714D01*
G01X994096Y97733D02*
X994094D01*
Y89964D01*
G01X987403Y79623D02*
X987401D01*
Y84599D01*
G01X990750Y97733D02*
X990748D01*
Y92757D01*
G01X984057Y97733D02*
X984055D01*
Y92757D01*
G01X977364Y41823D02*
X977362D01*
Y46914D01*
G01X974017Y59933D02*
X974015D01*
Y54857D01*
G01X974017Y41823D02*
X974015D01*
Y46914D01*
G01X1014175Y59933D02*
X1014173D01*
Y54842D01*
G01X1014175Y41823D02*
X1014173D01*
Y46614D01*
X1013873Y46914D01*
G01X1010828Y59933D02*
X1010826D01*
Y54842D01*
G01X1010828Y41823D02*
X1010826D01*
Y46614D01*
X1011126Y46914D01*
G01X984057Y41823D02*
X984055D01*
Y46913D01*
X984054Y46914D01*
G01X980710Y59933D02*
X980708D01*
Y54857D01*
G01X1004135Y59933D02*
X1004133D01*
Y54958D01*
X1004134Y54957D01*
Y54857D01*
G01X1004135Y41823D02*
X1004133D01*
Y46922D01*
G01X1000789Y59933D02*
X1000787D01*
Y54857D01*
G01X997443Y41823D02*
X997441D01*
Y46922D01*
G01X994096Y41823D02*
X994094D01*
Y46922D01*
G01X994096Y59933D02*
X994094D01*
Y54857D01*
G01X987403Y41823D02*
X987401D01*
Y46914D01*
G01X990750Y59933D02*
X990748D01*
Y54857D01*
G01X984057Y59933D02*
X984055D01*
Y54857D01*
G01X977364Y505024D02*
X977362D01*
Y512792D01*
G01X974017Y523134D02*
X974015Y523133D01*
Y515364D01*
G01X974017Y505024D02*
X974015D01*
Y509999D01*
G01X1014175Y523134D02*
X1014173Y523133D01*
Y515452D01*
X1013873Y515152D01*
G01X1014175Y505024D02*
X1014173D01*
Y509814D01*
X1013873Y510114D01*
G01X1010828Y523134D02*
X1010826Y523133D01*
Y515624D01*
X1011250Y515200D01*
G01X1010828Y505024D02*
X1010826D01*
Y509814D01*
X1011126Y510114D01*
G01X984057Y505024D02*
X984055D01*
Y512792D01*
G01X980710Y523134D02*
X980708Y523133D01*
Y515364D01*
G01X1004135Y523134D02*
X1004133Y523133D01*
Y518158D01*
X1004134Y518157D01*
G01X1004135Y505024D02*
X1004133D01*
Y512574D01*
X1003915Y512792D01*
G01X1000789Y523134D02*
X1000787Y523133D01*
Y515364D01*
G01X997443Y505024D02*
X997441D01*
Y512792D01*
G01X994096Y505024D02*
X994094D01*
Y510114D01*
G01X994096Y523134D02*
X994094Y523133D01*
Y515364D01*
G01X987403Y505024D02*
X987401D01*
Y509999D01*
G01X990750Y523134D02*
X990748Y523133D01*
Y518157D01*
G01X984057Y523134D02*
X984055Y523133D01*
Y518157D01*
G01X977364Y542824D02*
X977362D01*
Y547914D01*
G01X974017Y560934D02*
X974015Y560933D01*
Y555857D01*
G01X974017Y542824D02*
X974015D01*
Y547914D01*
G01X1014175Y560934D02*
X1014173Y560933D01*
Y555842D01*
G01X1013873Y547914D02*
X1014173Y547614D01*
Y542824D01*
X1014175D01*
G01X1010828Y560934D02*
X1010826Y560933D01*
Y555944D01*
X1010928Y555842D01*
G01X1010828Y542824D02*
X1010826D01*
Y547614D01*
X1011126Y547914D01*
G01X984057Y542824D02*
X984055D01*
Y547913D01*
X984054Y547914D01*
G01X980710Y560934D02*
X980708Y560933D01*
Y555857D01*
G01X1004135Y560934D02*
X1004133Y560933D01*
Y555958D01*
X1004134Y555957D01*
Y555857D01*
G01X1004135Y542824D02*
X1004133D01*
Y547922D01*
G01X1000789Y560934D02*
X1000787Y560933D01*
Y555857D01*
G01X997443Y542824D02*
X997441D01*
Y547922D01*
G01X994094D02*
Y542824D01*
X994096D01*
G01Y560934D02*
X994094Y560933D01*
Y555857D01*
G01X987403Y542824D02*
X987401D01*
Y547914D01*
G01X990750Y560934D02*
X990748Y560933D01*
Y555857D01*
G01X984057Y560934D02*
X984055Y560933D01*
Y555857D01*
G01X977364Y580624D02*
X977362D01*
Y585714D01*
G01X974017Y580624D02*
X974015D01*
Y585714D01*
G01X1014175Y580624D02*
X1014173D01*
Y585414D01*
X1013873Y585714D01*
G01X1011126D02*
X1010826Y585414D01*
Y580624D01*
X1010828D01*
G01X984057D02*
X984055D01*
Y585713D01*
X984054Y585714D01*
G01X1004135Y580624D02*
X1004133D01*
Y585722D01*
G01X997443Y580624D02*
X997441D01*
Y585722D01*
G01X994096Y580624D02*
X994094D01*
Y585722D01*
G01X987403Y580624D02*
X987401D01*
Y585714D01*
G01X974017Y598734D02*
X974015Y598733D01*
Y593657D01*
G01X1014175Y598734D02*
X1014173Y598733D01*
Y594388D01*
X1014919Y593642D01*
G01X1010828Y598734D02*
X1010826Y598733D01*
Y594388D01*
X1011572Y593642D01*
G01X980710Y598734D02*
X980708Y598733D01*
Y593657D01*
G01X1004135Y598734D02*
X1004133Y598733D01*
Y593758D01*
X1004134Y593757D01*
Y593657D01*
G01X1000789Y598734D02*
X1000787Y598733D01*
Y593657D01*
G01X994096Y598734D02*
X994094Y598733D01*
Y593657D01*
G01X990750Y598734D02*
X990748Y598733D01*
Y593657D01*
G01X984057Y598734D02*
X984055Y598733D01*
Y593657D01*
G01X1054332Y22133D02*
X1054330D01*
Y17058D01*
X1054331Y17057D01*
G01X1050986Y4023D02*
X1050984D01*
Y9121D01*
X1050985Y9122D01*
G01X1087797Y4023D02*
X1087795D01*
Y9120D01*
X1087797Y9122D01*
G01X1064372Y22133D02*
X1064370D01*
Y17058D01*
X1064371Y17057D01*
G01X1081104Y22133D02*
X1081102D01*
Y17042D01*
G01X1094490Y22133D02*
X1094488D01*
Y17059D01*
G01X1094490Y4023D02*
X1094488D01*
Y9122D01*
G01X1047639Y22133D02*
X1047637D01*
Y17042D01*
G01X1054332Y4023D02*
X1054330D01*
Y9121D01*
X1054331Y9122D01*
G01X1077757Y4023D02*
X1077755D01*
Y9120D01*
X1077757Y9122D01*
G01X1064372Y4023D02*
X1064370D01*
Y9121D01*
X1064371Y9122D01*
G01X1071065Y22133D02*
Y17058D01*
X1071064Y17057D01*
G01X1057679Y22133D02*
X1057677D01*
Y17042D01*
G01X1084450Y4023D02*
X1084448D01*
Y9120D01*
X1084450Y9122D01*
G01X1074411Y22133D02*
X1074409D01*
Y17042D01*
G01X1087797Y22133D02*
X1087795D01*
Y17059D01*
G01X1044293Y4023D02*
Y11789D01*
X1044290Y11792D01*
G01X1054332Y97733D02*
X1054330D01*
Y89964D01*
G01X1050986Y79623D02*
X1050984D01*
Y87391D01*
X1050983Y87392D01*
G01X1087797Y79623D02*
X1087795D01*
Y84714D01*
G01X1064372Y97733D02*
X1064370D01*
Y92758D01*
X1064369Y92757D01*
G01X1081104Y97733D02*
X1081102D01*
Y89964D01*
G01X1094490Y97733D02*
X1094488D01*
Y89964D01*
G01X1094490Y79623D02*
X1094488D01*
Y84714D01*
G01X1047639Y97733D02*
X1047637D01*
Y89964D01*
G01X1054332Y79623D02*
X1054330D01*
Y84599D01*
G01X1077757Y79623D02*
X1077755D01*
Y87392D01*
G01X1064372Y79623D02*
Y87389D01*
X1064369Y87392D01*
G01X1071065Y97733D02*
X1071063D01*
Y92758D01*
X1071062Y92757D01*
G01X1057679Y97733D02*
X1057677D01*
Y92758D01*
X1057676Y92757D01*
G01X1084450Y79623D02*
X1084448D01*
Y87392D01*
G01X1074411Y97733D02*
X1074409D01*
Y89964D01*
G01X1087797Y97733D02*
X1087795D01*
Y89964D01*
G01X1044293Y79623D02*
X1044291D01*
Y87391D01*
X1044290Y87392D01*
G01X1054332Y59933D02*
X1054330D01*
Y54858D01*
X1054331Y54857D01*
G01X1050986Y41823D02*
X1050984D01*
Y46921D01*
X1050985Y46922D01*
G01X1064372Y59933D02*
X1064370D01*
Y54858D01*
X1064371Y54857D01*
G01X1081104Y59933D02*
X1081102D01*
Y54842D01*
G01X1094490Y59933D02*
X1094488D01*
Y54859D01*
G01X1094490Y41823D02*
X1094488D01*
Y46922D01*
G01X1047639Y59933D02*
X1047637D01*
Y54842D01*
G01X1054332Y41823D02*
X1054330D01*
Y46921D01*
X1054331Y46922D01*
G01X1077757Y41823D02*
X1077755D01*
Y46920D01*
X1077757Y46922D01*
G01X1064372Y41823D02*
X1064370D01*
Y46921D01*
X1064371Y46922D01*
G01X1057679Y59933D02*
X1057677D01*
Y54842D01*
G01X1084450Y41823D02*
X1084448D01*
Y46920D01*
X1084450Y46922D01*
G01X1074411Y59933D02*
X1074409D01*
Y54842D01*
G01X1087797Y59933D02*
X1087795D01*
Y54859D01*
G01X1044290Y49592D02*
Y41826D01*
X1044293Y41823D01*
G01X1054332Y523134D02*
X1054330Y523133D01*
Y515364D01*
G01X1050986Y505024D02*
X1050984D01*
Y512791D01*
X1050983Y512792D01*
G01X1087797Y505024D02*
X1087795D01*
Y510114D01*
G01X1064372Y523134D02*
X1064370Y523133D01*
Y518158D01*
X1064369Y518157D01*
G01X1081104Y523134D02*
X1081102Y523133D01*
Y515364D01*
G01X1094490Y523134D02*
X1094488Y523133D01*
Y515364D01*
G01X1094490Y505024D02*
X1094488D01*
Y510114D01*
G01X1047639Y523134D02*
X1047637Y523133D01*
Y515364D01*
G01X1054332Y505024D02*
X1054330D01*
Y509999D01*
G01X1077755Y512792D02*
Y505024D01*
X1077757D01*
G01X1064369Y512792D02*
Y505024D01*
X1064372D01*
G01X1071065Y523134D02*
X1071063Y523133D01*
Y518158D01*
X1071062Y518157D01*
G01X1057679Y523134D02*
X1057677Y523133D01*
Y518158D01*
X1057676Y518157D01*
G01X1084450Y505024D02*
X1084448D01*
Y512792D01*
G01X1074411Y523134D02*
X1074409Y523133D01*
Y515364D01*
G01X1087797Y523134D02*
X1087795Y523133D01*
Y515364D01*
G01X1044293Y505024D02*
X1044291D01*
Y512791D01*
X1044290Y512792D01*
G01X1054332Y560934D02*
X1054330Y560933D01*
Y555858D01*
X1054331Y555857D01*
G01X1050986Y542824D02*
X1050984D01*
Y547922D01*
G01X1087797Y542824D02*
X1087795D01*
Y547920D01*
X1087797Y547922D01*
G01X1064372Y560934D02*
X1064370Y560933D01*
Y555858D01*
X1064371Y555857D01*
G01X1081104Y560934D02*
X1081102Y560933D01*
Y555842D01*
G01X1094490Y560934D02*
X1094488Y560933D01*
Y555859D01*
G01X1094490Y542824D02*
X1094488D01*
Y547922D01*
G01X1047639Y560934D02*
X1047637Y560933D01*
Y555842D01*
G01X1054332Y542824D02*
X1054330D01*
Y547921D01*
X1054331Y547922D01*
G01X1077757Y542824D02*
X1077755D01*
Y547920D01*
X1077757Y547922D01*
G01X1064372Y542824D02*
X1064370D01*
Y547921D01*
X1064371Y547922D01*
G01X1057679Y560934D02*
X1057677Y560933D01*
Y555842D01*
G01X1084450Y542824D02*
X1084448D01*
Y547920D01*
X1084450Y547922D01*
G01X1074411Y560934D02*
X1074409Y560933D01*
Y555842D01*
G01X1087797Y560934D02*
X1087795Y560933D01*
Y555859D01*
G01X1044293Y542824D02*
X1044291D01*
Y550591D01*
X1044290Y550592D01*
G01X1050986Y580624D02*
X1050984D01*
Y585721D01*
X1050985Y585722D01*
G01X1094490Y580624D02*
X1094488D01*
Y585722D01*
G01X1054332Y580624D02*
X1054330D01*
Y585721D01*
X1054331Y585722D01*
G01X1077757D02*
X1077755Y585720D01*
Y580624D01*
X1077757D01*
G01X1064372D02*
X1064370D01*
Y585721D01*
X1064371Y585722D01*
G01X1084450Y580624D02*
X1084448D01*
Y585720D01*
X1084450Y585722D01*
G01X1044293Y580624D02*
Y588389D01*
X1044290Y588392D01*
G01X1054332Y598734D02*
X1054330Y598733D01*
Y593658D01*
X1054331Y593657D01*
G01X1064372Y598734D02*
X1064370Y598733D01*
Y593658D01*
X1064371Y593657D01*
G01X1081104Y598734D02*
X1081102Y598733D01*
Y593642D01*
G01X1094490Y598734D02*
X1094488Y598733D01*
Y593659D01*
G01X1047639Y598734D02*
X1047637Y598733D01*
Y593642D01*
G01X1057679Y598734D02*
X1057677Y598733D01*
Y593642D01*
G01X1074411Y598734D02*
X1074409Y598733D01*
Y593642D01*
G01X1087797Y598734D02*
X1087795Y598733D01*
Y593659D01*
G01X1107876Y22133D02*
X1107874D01*
Y17157D01*
G01X1111222Y4023D02*
X1111220D01*
Y9433D01*
X1110520Y10133D01*
Y12114D01*
G01X1131301Y22133D02*
X1131299D01*
Y17157D01*
G01X1134647Y4023D02*
X1134645D01*
Y12114D01*
G01X1101183Y22133D02*
X1101181D01*
Y17157D01*
G01X1104529Y4023D02*
X1104527D01*
Y8973D01*
X1104227Y9273D01*
Y12114D01*
G01X1124608Y22133D02*
X1124606D01*
Y17157D01*
G01X1127954Y4023D02*
X1127952D01*
Y12114D01*
G01X1144687Y22133D02*
X1144685D01*
Y17157D01*
G01X1148033Y4023D02*
X1148031D01*
Y9433D01*
X1147331Y10133D01*
Y12114D01*
G01X1137994Y22133D02*
X1137992D01*
Y17157D01*
G01X1141340Y4023D02*
X1141338D01*
Y11814D01*
X1141038Y12114D01*
G01X1117915Y22133D02*
X1117913D01*
Y19548D01*
X1116166Y17801D01*
Y16400D01*
X1116866Y15700D01*
Y14400D01*
X1116000Y13534D01*
X1115106D01*
X1114340Y14300D01*
G01X1154726Y22133D02*
X1154724D01*
Y19547D01*
X1152978Y17801D01*
Y16400D01*
X1153678Y15700D01*
Y14400D01*
X1152812Y13534D01*
X1151918D01*
X1151152Y14300D01*
G01X1117915Y4023D02*
X1117913D01*
Y7554D01*
X1116916Y8551D01*
Y11990D01*
X1119440Y14514D01*
G01X1154726Y4023D02*
X1154724D01*
Y7555D01*
X1153728Y8551D01*
Y11990D01*
X1156252Y14514D01*
G01X1114568Y22133D02*
X1114566D01*
Y19701D01*
X1112770Y17905D01*
X1112466Y17384D01*
Y13858D01*
X1112810Y13230D01*
X1114340Y11700D01*
G01X1151380Y22133D02*
X1151378D01*
Y19701D01*
X1149582Y17905D01*
X1149278Y17384D01*
Y13858D01*
X1149622Y13230D01*
X1151152Y11700D01*
G01X1121261Y4023D02*
X1121258D01*
Y9992D01*
X1121966Y10700D01*
Y12470D01*
X1121416Y13020D01*
X1120546D01*
X1119440Y11914D01*
G01X1158072Y4023D02*
X1158070D01*
Y9992D01*
X1158778Y10700D01*
Y12470D01*
X1158228Y13020D01*
X1157358D01*
X1156252Y11914D01*
G01X1107876Y97733D02*
X1107874D01*
Y92757D01*
G01X1111222Y79623D02*
X1111220D01*
Y85033D01*
X1110520Y85733D01*
Y87714D01*
G01X1131301Y97733D02*
X1131299D01*
Y92757D01*
G01X1134647Y79623D02*
X1134645D01*
Y87714D01*
G01X1101183Y97733D02*
X1101181D01*
Y92757D01*
G01X1104529Y79623D02*
X1104527D01*
Y87414D01*
X1104227Y87714D01*
G01X1124608Y97733D02*
X1124606D01*
Y92757D01*
G01X1127954Y79623D02*
X1127952D01*
Y87714D01*
G01X1144687Y97733D02*
X1144685D01*
Y92757D01*
G01X1148033Y79623D02*
X1148031D01*
Y85033D01*
X1147331Y85733D01*
Y87714D01*
G01X1137994Y97733D02*
X1137992D01*
Y92757D01*
G01X1141340Y79623D02*
X1141338D01*
Y87414D01*
X1141038Y87714D01*
G01X1117915Y97733D02*
X1117913D01*
Y95148D01*
X1116166Y93401D01*
Y92000D01*
X1116866Y91300D01*
Y90000D01*
X1116000Y89134D01*
X1115106D01*
X1114340Y89900D01*
G01X1151152D02*
X1151918Y89134D01*
X1152812D01*
X1153678Y90000D01*
Y91300D01*
X1152978Y92000D01*
Y93401D01*
X1154725Y95148D01*
Y97732D01*
X1154726Y97733D01*
G01X1117915Y79623D02*
X1117913D01*
Y83194D01*
X1117408Y83699D01*
Y84699D01*
X1116408Y85699D01*
Y87000D01*
X1117808Y88400D01*
X1118554D01*
X1119440Y87514D01*
G01X1154726Y79623D02*
X1154724D01*
Y83195D01*
X1154220Y83699D01*
Y84699D01*
X1153220Y85699D01*
Y87000D01*
X1154620Y88400D01*
X1155366D01*
X1156252Y87514D01*
G01X1114568Y97733D02*
X1114566D01*
Y95301D01*
X1112770Y93505D01*
X1112466Y92984D01*
Y89458D01*
X1112810Y88830D01*
X1114340Y87300D01*
G01X1151380Y97733D02*
X1151378D01*
Y95301D01*
X1149582Y93505D01*
X1149278Y92984D01*
Y89458D01*
X1149622Y88830D01*
X1151152Y87300D01*
G01X1121261Y79623D02*
X1121259D01*
Y84151D01*
X1121408Y84300D01*
Y89100D01*
X1120394Y90114D01*
X1119440D01*
G01X1158072Y79623D02*
X1158071Y79624D01*
Y84151D01*
X1158220Y84300D01*
Y89100D01*
X1157206Y90114D01*
X1156252D01*
G01X1107876Y59933D02*
X1107874D01*
Y54957D01*
G01X1111222Y41823D02*
X1111220D01*
Y47233D01*
X1110520Y47933D01*
Y49914D01*
G01X1131301Y59933D02*
X1131299D01*
Y54957D01*
G01X1134647Y41823D02*
X1134645D01*
Y49914D01*
G01X1101183Y59933D02*
X1101181D01*
Y54957D01*
G01X1104529Y41823D02*
X1104527D01*
Y49264D01*
X1104227Y49564D01*
G01X1124608Y59933D02*
X1124606D01*
Y54957D01*
G01X1127954Y41823D02*
X1127952D01*
Y49914D01*
G01X1144687Y59933D02*
X1144685D01*
Y54957D01*
G01X1148033Y41823D02*
X1148031D01*
Y47233D01*
X1147331Y47933D01*
Y49914D01*
G01X1137994Y59933D02*
X1137992D01*
Y54957D01*
G01X1141340Y41823D02*
X1141338D01*
Y49614D01*
X1141038Y49914D01*
G01X1117915Y59933D02*
X1117913D01*
Y57348D01*
X1116166Y55601D01*
Y54200D01*
X1116866Y53500D01*
Y52200D01*
X1116000Y51334D01*
X1115106D01*
X1114340Y52100D01*
G01X1154726Y59933D02*
X1154724D01*
Y57348D01*
X1152977Y55601D01*
Y54200D01*
X1153677Y53500D01*
Y52200D01*
X1152811Y51334D01*
X1151917D01*
X1151151Y52100D01*
G01X1117915Y41823D02*
X1117913D01*
Y45394D01*
X1117408Y45899D01*
Y46899D01*
X1116408Y47899D01*
Y49200D01*
X1117808Y50600D01*
X1118554D01*
X1119440Y49714D01*
G01X1154726Y41823D02*
X1154724D01*
Y45394D01*
X1154219Y45899D01*
Y46899D01*
X1153219Y47899D01*
Y49200D01*
X1154619Y50600D01*
X1155365D01*
X1156251Y49714D01*
G01X1114568Y59933D02*
X1114566D01*
Y57501D01*
X1112770Y55705D01*
X1112466Y55184D01*
Y51658D01*
X1112810Y51030D01*
X1114340Y49500D01*
G01X1151151D02*
Y49501D01*
X1149622Y51030D01*
X1149278Y51658D01*
Y55184D01*
X1149582Y55705D01*
X1151378Y57501D01*
Y59933D01*
X1151380D01*
G01X1121261Y41823D02*
X1121259D01*
Y46351D01*
X1121408Y46500D01*
Y51300D01*
X1120394Y52314D01*
X1119440D01*
G01X1158072Y41823D02*
X1158070D01*
Y46351D01*
X1158219Y46500D01*
Y51300D01*
X1157205Y52314D01*
X1156251D01*
G01X1107876Y523134D02*
X1107874Y523133D01*
Y518157D01*
G01X1111222Y505024D02*
X1111220D01*
Y510433D01*
X1110520Y511133D01*
Y513114D01*
G01X1131301Y523134D02*
X1131299Y523133D01*
Y518157D01*
G01X1134645Y513114D02*
Y505024D01*
X1134647D01*
G01X1101183Y523134D02*
X1101181Y523133D01*
Y518157D01*
G01X1104529Y505024D02*
X1104527D01*
Y512814D01*
X1104227Y513114D01*
G01X1124608Y523134D02*
X1124606Y523133D01*
Y518157D01*
G01X1127954Y505024D02*
X1127952D01*
Y513114D01*
G01X1144687Y523134D02*
X1144685Y523133D01*
Y518157D01*
G01X1147331Y513114D02*
Y511133D01*
X1148031Y510433D01*
Y505024D01*
X1148033D01*
G01X1137994Y523134D02*
X1137992Y523133D01*
Y518157D01*
G01X1141340Y505024D02*
X1141338D01*
Y512814D01*
X1141038Y513114D01*
G01X1117915Y523134D02*
X1117913Y523133D01*
Y520548D01*
X1116166Y518801D01*
Y517400D01*
X1116866Y516700D01*
Y515400D01*
X1116000Y514534D01*
X1115106D01*
X1114340Y515300D01*
G01X1151152D02*
X1151918Y514534D01*
X1152812D01*
X1153678Y515400D01*
Y516700D01*
X1152978Y517400D01*
Y518801D01*
X1154725Y520548D01*
Y523132D01*
X1154726Y523134D01*
G01X1119440Y512914D02*
X1118554Y513800D01*
X1117808D01*
X1116408Y512400D01*
Y511099D01*
X1117408Y510099D01*
Y509099D01*
X1117913Y508594D01*
Y505024D01*
X1117915D01*
G01X1154726D02*
X1154724D01*
Y508595D01*
X1154220Y509099D01*
Y510099D01*
X1153220Y511099D01*
Y512400D01*
X1154620Y513800D01*
X1155366D01*
X1156252Y512914D01*
G01X1114568Y523134D02*
X1114566Y523133D01*
Y520701D01*
X1112770Y518905D01*
X1112466Y518384D01*
Y514858D01*
X1112810Y514230D01*
X1114340Y512700D01*
G01X1151380Y523134D02*
X1151378Y523133D01*
Y520701D01*
X1149582Y518905D01*
X1149278Y518384D01*
Y514858D01*
X1149622Y514230D01*
X1151152Y512700D01*
G01X1119440Y515514D02*
X1120394D01*
X1121408Y514500D01*
Y509700D01*
X1121259Y509551D01*
Y505024D01*
X1121261D01*
G01X1156252Y515514D02*
X1157206D01*
X1158220Y514500D01*
Y509700D01*
X1158071Y509551D01*
Y505024D01*
X1158072D01*
G01X1107876Y560934D02*
X1107874Y560933D01*
Y555957D01*
G01X1111222Y542824D02*
X1111220D01*
Y548233D01*
X1110520Y548933D01*
Y550914D01*
G01X1131301Y560934D02*
X1131299Y560933D01*
Y555957D01*
G01X1134647Y542824D02*
X1134645D01*
Y550914D01*
G01X1101183Y560934D02*
X1101181Y560933D01*
Y555957D01*
G01X1104529Y542824D02*
X1104527D01*
Y550614D01*
X1104227Y550914D01*
G01X1124608Y560934D02*
X1124606Y560933D01*
Y555957D01*
G01X1127952Y550914D02*
Y542824D01*
X1127954D01*
G01X1144687Y560934D02*
X1144685Y560933D01*
Y555957D01*
G01X1148033Y542824D02*
X1148031D01*
Y548233D01*
X1147331Y548933D01*
Y550914D01*
G01X1137994Y560934D02*
X1137992Y560933D01*
Y555957D01*
G01X1141340Y542824D02*
X1141338D01*
Y550614D01*
X1141038Y550914D01*
G01X1117915Y560934D02*
X1117913Y560933D01*
Y558348D01*
X1116166Y556601D01*
Y555200D01*
X1116866Y554500D01*
Y553200D01*
X1116000Y552334D01*
X1115106D01*
X1114340Y553100D01*
G01X1151152D02*
X1151918Y552334D01*
X1152812D01*
X1153678Y553200D01*
Y554500D01*
X1152978Y555200D01*
Y556601D01*
X1154725Y558348D01*
Y560932D01*
X1154726Y560934D01*
G01X1119440Y550714D02*
X1118554Y551600D01*
X1117808D01*
X1116408Y550200D01*
Y548899D01*
X1117408Y547899D01*
Y546899D01*
X1117913Y546394D01*
Y542824D01*
X1117915D01*
G01X1156252Y550714D02*
X1155366Y551600D01*
X1154620D01*
X1153220Y550200D01*
Y548899D01*
X1154220Y547899D01*
Y546899D01*
X1154724Y546395D01*
Y542824D01*
X1154726D01*
G01X1114568Y560934D02*
X1114566Y560933D01*
Y558501D01*
X1112770Y556705D01*
X1112466Y556184D01*
Y552658D01*
X1112810Y552030D01*
X1114340Y550500D01*
G01X1151380Y560934D02*
X1151378Y560933D01*
Y558501D01*
X1149582Y556705D01*
X1149278Y556184D01*
Y552658D01*
X1149622Y552030D01*
X1151152Y550500D01*
G01X1119440Y553314D02*
X1120394D01*
X1121408Y552300D01*
Y547500D01*
X1121259Y547351D01*
Y542824D01*
X1121261D01*
G01X1156252Y553314D02*
X1157206D01*
X1158220Y552300D01*
Y547500D01*
X1158071Y547351D01*
Y542824D01*
X1158072D01*
G01X1111222Y580624D02*
X1111220D01*
Y586033D01*
X1110520Y586733D01*
Y588714D01*
G01X1134647Y580624D02*
X1134645D01*
Y588714D01*
G01X1104529Y580624D02*
X1104527D01*
Y588414D01*
X1104227Y588714D01*
G01X1127952D02*
Y580624D01*
X1127954D01*
G01X1148033D02*
X1148031D01*
Y586033D01*
X1147331Y586733D01*
Y588714D01*
G01X1141340Y580624D02*
X1141338D01*
Y588414D01*
X1141038Y588714D01*
G01X1119440Y588514D02*
X1118554Y589400D01*
X1117808D01*
X1116408Y588000D01*
Y586699D01*
X1117408Y585699D01*
Y584699D01*
X1117913Y584194D01*
Y580624D01*
X1117915D01*
G01X1154726D02*
X1154724D01*
Y584195D01*
X1154220Y584699D01*
Y585699D01*
X1153220Y586699D01*
Y588000D01*
X1154620Y589400D01*
X1155366D01*
X1156252Y588514D01*
G01X1114568Y598734D02*
X1114566Y598733D01*
Y596301D01*
X1112770Y594505D01*
X1112466Y593984D01*
Y590458D01*
X1112810Y589830D01*
X1114340Y588300D01*
G01X1151380Y598734D02*
X1151378Y598733D01*
Y596301D01*
X1149582Y594505D01*
X1149278Y593984D01*
Y590458D01*
X1149622Y589830D01*
X1151152Y588300D01*
G01X1119440Y591114D02*
X1120394D01*
X1121408Y590100D01*
Y585300D01*
X1121259Y585151D01*
Y580624D01*
X1121261D01*
G01X1107876Y598734D02*
X1107874Y598733D01*
Y593757D01*
G01X1131301Y598734D02*
X1131299Y598733D01*
Y593757D01*
G01X1101183Y598734D02*
X1101181Y598733D01*
Y593757D01*
G01X1124608Y598734D02*
X1124606Y598733D01*
Y593757D01*
G01X1144687Y598734D02*
X1144685Y598733D01*
Y593757D01*
G01X1137994Y598734D02*
X1137992Y598733D01*
Y593757D01*
G01X1117915Y598734D02*
X1117913Y598733D01*
Y596148D01*
X1116166Y594401D01*
Y593000D01*
X1116866Y592300D01*
Y591000D01*
X1116000Y590134D01*
X1115106D01*
X1114340Y590900D01*
G01X1151152D02*
X1151918Y590134D01*
X1152812D01*
X1153678Y591000D01*
Y592300D01*
X1152978Y593000D01*
Y594401D01*
X1154725Y596148D01*
Y598732D01*
X1154726Y598734D01*
G01X1156252Y591114D02*
X1157206D01*
X1158220Y590100D01*
Y585300D01*
X1158071Y585151D01*
Y580624D01*
X1158072D01*
G01X1168112Y22133D02*
X1168110D01*
Y17157D01*
G01X1171458Y4023D02*
X1171456D01*
Y12114D01*
G01X1161419Y22133D02*
X1161417D01*
Y17157D01*
G01X1164765Y4023D02*
X1164763D01*
Y12114D01*
G01X1181498Y22133D02*
X1181496D01*
Y17157D01*
G01X1184844Y4023D02*
X1184842D01*
Y9433D01*
X1184142Y10133D01*
Y12114D01*
G01X1204923Y22133D02*
X1204921D01*
Y17157D01*
G01X1208269Y4023D02*
X1208267D01*
Y12114D01*
G01X1174805Y22133D02*
X1174803D01*
Y17157D01*
G01X1178151Y4023D02*
X1178149D01*
Y11814D01*
X1177849Y12114D01*
G01X1198230Y22133D02*
X1198228D01*
Y17157D01*
G01X1201576Y4023D02*
X1201574D01*
Y12114D01*
G01X1218309Y22133D02*
X1218307D01*
Y17157D01*
G01X1211616Y22133D02*
X1211614D01*
Y17157D01*
G01X1214962Y4023D02*
X1214960D01*
Y11814D01*
X1214660Y12114D01*
G01X1191537Y22133D02*
X1191535D01*
Y19547D01*
X1189789Y17801D01*
Y16400D01*
X1190489Y15700D01*
Y14400D01*
X1189623Y13534D01*
X1188729D01*
X1187963Y14300D01*
G01X1191537Y4023D02*
X1191535D01*
Y7555D01*
X1190539Y8551D01*
Y11990D01*
X1193063Y14514D01*
G01X1188191Y22133D02*
X1188189D01*
Y19701D01*
X1186393Y17905D01*
X1186089Y17384D01*
Y13858D01*
X1186433Y13230D01*
X1187963Y11700D01*
G01X1194883Y4023D02*
X1194881D01*
Y9992D01*
X1195589Y10700D01*
Y12470D01*
X1195039Y13020D01*
X1194169D01*
X1193063Y11914D01*
G01X1168112Y97733D02*
X1168110D01*
Y92757D01*
G01X1171458Y79623D02*
X1171456D01*
Y87714D01*
G01X1161419Y97733D02*
X1161417D01*
Y92757D01*
G01X1164765Y79623D02*
X1164763D01*
Y87714D01*
G01X1181498Y97733D02*
X1181496D01*
Y92757D01*
G01X1184844Y79623D02*
X1184842D01*
Y85033D01*
X1184142Y85733D01*
Y87714D01*
G01X1204923Y97733D02*
X1204921D01*
Y92757D01*
G01X1208269Y79623D02*
X1208267D01*
Y87714D01*
G01X1174805Y97733D02*
X1174803D01*
Y92757D01*
G01X1178151Y79623D02*
X1178149D01*
Y87414D01*
X1177849Y87714D01*
G01X1198230Y97733D02*
X1198228D01*
Y92757D01*
G01X1201576Y79623D02*
X1201574D01*
Y87714D01*
G01X1218309Y97733D02*
X1218307D01*
Y92757D01*
G01X1211616Y97733D02*
X1211614D01*
Y92757D01*
G01X1214962Y79623D02*
X1214960D01*
Y87288D01*
X1214874Y87374D01*
G01X1187963Y89900D02*
X1188729Y89134D01*
X1189623D01*
X1190489Y90000D01*
Y91300D01*
X1189789Y92000D01*
Y93401D01*
X1191536Y95148D01*
Y97732D01*
X1191537Y97733D01*
G01Y79623D02*
X1191535D01*
Y83195D01*
X1191031Y83699D01*
Y84699D01*
X1190031Y85699D01*
Y87000D01*
X1191431Y88400D01*
X1192177D01*
X1192838Y87738D01*
X1193063Y87514D01*
G01X1188191Y97733D02*
X1188189D01*
Y95301D01*
X1186393Y93505D01*
X1186089Y92984D01*
Y89458D01*
X1186433Y88830D01*
X1187782Y87482D01*
X1187963Y87300D01*
G01X1193063Y90114D02*
X1194017D01*
X1194616Y89516D01*
X1194630Y89502D01*
X1195031Y89100D01*
Y84300D01*
X1194882Y84151D01*
Y79624D01*
X1194883Y79623D01*
G01X1168112Y59933D02*
X1168110D01*
Y54957D01*
G01X1171458Y41823D02*
X1171456D01*
Y49914D01*
G01X1161419Y59933D02*
X1161417D01*
Y54957D01*
G01X1164765Y41823D02*
X1164763D01*
Y49914D01*
G01X1181498Y59933D02*
X1181496D01*
Y54957D01*
G01X1184844Y41823D02*
X1184842D01*
Y47233D01*
X1184142Y47933D01*
Y49914D01*
G01X1204923Y59933D02*
X1204921D01*
Y54957D01*
G01X1208269Y41823D02*
X1208267D01*
Y49914D01*
G01X1174805Y59933D02*
X1174803D01*
Y54957D01*
G01X1178151Y41823D02*
X1178149D01*
Y49614D01*
X1177849Y49914D01*
G01X1198230Y59933D02*
X1198228D01*
Y54957D01*
G01X1201576Y41823D02*
X1201574D01*
Y49914D01*
G01X1218309Y59933D02*
X1218307D01*
Y54957D01*
G01X1211616Y59933D02*
X1211614D01*
Y54957D01*
G01X1214962Y41823D02*
X1214960D01*
Y49614D01*
X1214660Y49914D01*
G01X1187963Y52100D02*
X1188729Y51334D01*
X1189623D01*
X1190489Y52200D01*
Y53500D01*
X1189789Y54200D01*
Y55601D01*
X1191536Y57348D01*
Y59932D01*
X1191537Y59933D01*
G01Y41823D02*
X1191535D01*
Y45395D01*
X1191031Y45899D01*
Y46899D01*
X1190031Y47899D01*
Y49200D01*
X1191431Y50600D01*
X1192177D01*
X1193063Y49714D01*
G01X1188191Y59933D02*
X1188189D01*
Y57501D01*
X1186393Y55705D01*
X1186089Y55184D01*
Y51658D01*
X1186433Y51030D01*
X1187963Y49500D01*
G01X1193063Y52314D02*
X1194017D01*
X1195031Y51300D01*
Y46500D01*
X1194882Y46351D01*
Y41824D01*
X1194883Y41823D01*
G01X1168112Y523134D02*
X1168110Y523133D01*
Y518157D01*
G01X1171458Y505024D02*
X1171456D01*
Y513114D01*
G01X1161419Y523134D02*
X1161417Y523133D01*
Y518157D01*
G01X1164765Y505024D02*
X1164763D01*
Y513114D01*
G01X1181498Y523134D02*
X1181496Y523133D01*
Y518157D01*
G01X1184142Y513114D02*
Y511133D01*
X1184842Y510433D01*
Y505024D01*
X1184844D01*
G01X1204923Y523134D02*
X1204921Y523133D01*
Y518157D01*
G01X1208269Y505024D02*
X1208267D01*
Y513114D01*
G01X1174805Y523134D02*
X1174803Y523133D01*
Y518157D01*
G01X1178151Y505024D02*
X1178149D01*
Y512814D01*
X1177849Y513114D01*
G01X1198230Y523134D02*
X1198228Y523133D01*
Y518157D01*
G01X1201576Y505024D02*
X1201574D01*
Y513114D01*
G01X1218309Y523134D02*
X1218307Y523133D01*
Y518157D01*
G01X1211616Y523134D02*
X1211614Y523133D01*
Y518157D01*
G01X1214962Y505024D02*
X1214960D01*
Y512688D01*
X1214874Y512774D01*
G01X1187963Y515300D02*
X1188729Y514534D01*
X1189623D01*
X1190489Y515400D01*
Y516700D01*
X1189789Y517400D01*
Y518801D01*
X1191536Y520548D01*
Y523132D01*
X1191537Y523134D01*
G01Y505024D02*
X1191535D01*
Y508595D01*
X1191031Y509099D01*
Y510099D01*
X1190031Y511099D01*
Y512400D01*
X1191431Y513800D01*
X1192177D01*
X1193063Y512914D01*
G01X1188191Y523134D02*
X1188189Y523133D01*
Y520701D01*
X1186393Y518905D01*
X1186089Y518384D01*
Y514858D01*
X1186433Y514230D01*
X1187963Y512700D01*
G01X1193063Y515514D02*
X1194017D01*
X1195031Y514500D01*
Y509700D01*
X1194882Y509551D01*
Y505024D01*
X1194883D01*
G01X1168112Y560934D02*
X1168110Y560933D01*
Y555957D01*
G01X1171458Y542824D02*
X1171456D01*
Y550914D01*
G01X1161419Y560934D02*
X1161417Y560933D01*
Y555957D01*
G01X1164765Y542824D02*
X1164763D01*
Y550914D01*
G01X1181498Y560934D02*
X1181496Y560933D01*
Y555957D01*
G01X1184844Y542824D02*
X1184842D01*
Y548233D01*
X1184142Y548933D01*
Y550914D01*
G01X1204923Y560934D02*
X1204921Y560933D01*
Y555957D01*
G01X1208269Y542824D02*
X1208267D01*
Y550914D01*
G01X1174805Y560934D02*
X1174803Y560933D01*
Y555957D01*
G01X1178151Y542824D02*
X1178149D01*
Y550614D01*
X1177849Y550914D01*
G01X1198230Y560934D02*
X1198228Y560933D01*
Y555957D01*
G01X1201576Y542824D02*
X1201574D01*
Y550914D01*
G01X1218309Y560934D02*
X1218307Y560933D01*
Y555957D01*
G01X1211616Y560934D02*
X1211614Y560933D01*
Y555957D01*
G01X1214962Y542824D02*
X1214960D01*
Y550488D01*
X1214874Y550574D01*
G01X1191537Y560934D02*
Y558349D01*
X1189789Y556601D01*
Y555200D01*
X1190489Y554500D01*
Y553200D01*
X1189623Y552334D01*
X1188729D01*
X1187963Y553100D01*
G01X1191537Y542824D02*
X1191535D01*
Y546395D01*
X1191031Y546899D01*
Y547899D01*
X1190031Y548899D01*
Y550200D01*
X1191431Y551600D01*
X1192177D01*
X1193063Y550714D01*
G01X1188191Y560934D02*
X1188189Y560933D01*
Y558501D01*
X1186393Y556705D01*
X1186089Y556184D01*
Y552658D01*
X1186433Y552030D01*
X1187963Y550500D01*
G01X1193063Y553314D02*
X1194017D01*
X1195031Y552300D01*
Y547500D01*
X1194882Y547351D01*
Y542824D01*
X1194883D01*
G01X1171458Y580624D02*
X1171456D01*
Y588714D01*
G01X1164765Y580624D02*
X1164763D01*
Y588714D01*
G01X1184142D02*
Y586733D01*
X1184842Y586033D01*
Y580624D01*
X1184844D01*
G01X1208269D02*
X1208267D01*
Y588714D01*
G01X1178151Y580624D02*
X1178149D01*
Y588414D01*
X1177849Y588714D01*
G01X1201576Y580624D02*
X1201574D01*
Y588714D01*
G01X1214962Y580624D02*
X1214960D01*
Y588288D01*
X1214660Y588588D01*
Y588714D01*
G01X1191537Y580624D02*
X1191535D01*
Y584195D01*
X1191031Y584699D01*
Y585699D01*
X1190031Y586699D01*
Y588000D01*
X1191431Y589400D01*
X1192177D01*
X1193063Y588514D01*
G01X1188191Y598734D02*
X1188189Y598733D01*
Y596301D01*
X1186393Y594505D01*
X1186089Y593984D01*
Y590458D01*
X1186433Y589830D01*
X1187963Y588300D01*
G01X1193063Y591114D02*
X1194017D01*
X1195031Y590100D01*
Y585300D01*
X1194882Y585151D01*
Y580624D01*
X1194883D01*
G01X1168112Y598734D02*
X1168110Y598733D01*
Y593757D01*
G01X1161419Y598734D02*
X1161417Y598733D01*
Y593757D01*
G01X1181498Y598734D02*
X1181496Y598733D01*
Y593757D01*
G01X1204923Y598734D02*
X1204921Y598733D01*
Y593757D01*
G01X1174805Y598734D02*
X1174803Y598733D01*
Y593757D01*
G01X1198230Y598734D02*
X1198228Y598733D01*
Y593757D01*
G01X1218309Y598734D02*
X1218307Y598733D01*
Y593757D01*
G01X1211616Y598734D02*
Y593759D01*
X1211614Y593757D01*
G01X1191537Y598734D02*
X1191536Y596148D01*
X1189789Y594401D01*
Y593000D01*
X1190489Y592300D01*
Y591000D01*
X1189623Y590134D01*
X1188729D01*
X1187963Y590900D01*
G01X1221655Y4023D02*
X1221653D01*
Y9433D01*
X1220953Y10133D01*
Y12114D01*
G01X1241734Y22133D02*
X1241732D01*
Y17157D01*
G01X1245080Y4023D02*
X1245078D01*
Y12114D01*
G01X1235041Y22133D02*
X1235039D01*
Y17157D01*
G01X1238387Y4023D02*
X1238385D01*
Y12114D01*
G01X1224774Y14300D02*
X1225540Y13534D01*
X1226434D01*
X1227300Y14400D01*
Y15700D01*
X1226600Y16400D01*
Y17801D01*
X1228346Y19547D01*
Y22133D01*
X1228348D01*
G01Y4023D02*
X1228346D01*
Y7555D01*
X1227350Y8551D01*
Y11990D01*
X1229874Y14514D01*
G01X1225002Y22133D02*
X1225000D01*
Y19701D01*
X1223204Y17905D01*
X1222900Y17384D01*
Y13858D01*
X1223244Y13230D01*
X1224774Y11700D01*
G01X1231694Y4023D02*
X1231692D01*
Y9992D01*
X1232400Y10700D01*
Y12470D01*
X1231850Y13020D01*
X1230980D01*
X1229874Y11914D01*
G01X1221655Y79623D02*
X1221653D01*
Y85033D01*
X1220953Y85733D01*
Y87714D01*
G01X1241734Y97733D02*
Y92759D01*
X1241732Y92757D01*
G01X1245080Y79623D02*
Y87712D01*
X1245078Y87714D01*
G01X1235041Y97733D02*
X1235039D01*
Y92757D01*
G01X1238387Y79623D02*
Y87712D01*
X1238385Y87714D01*
G01X1224774Y89900D02*
X1225540Y89134D01*
X1226434D01*
X1227300Y90000D01*
Y91300D01*
X1226600Y92000D01*
Y93401D01*
X1228347Y95148D01*
Y97732D01*
X1228348Y97733D01*
G01X1229874Y87514D02*
X1228988Y88400D01*
X1228242D01*
X1226842Y87000D01*
Y85699D01*
X1227842Y84699D01*
Y83699D01*
X1228346Y83195D01*
Y79623D01*
X1228348D01*
G01X1225002Y97733D02*
X1225000D01*
Y95301D01*
X1223204Y93505D01*
X1222900Y92984D01*
Y89458D01*
X1223244Y88830D01*
X1224774Y87300D01*
G01X1229874Y90114D02*
X1230828D01*
X1231842Y89100D01*
Y84300D01*
X1231693Y84151D01*
Y79624D01*
X1231694Y79623D01*
G01X1221655Y41823D02*
X1221653D01*
Y47233D01*
X1220953Y47933D01*
Y49914D01*
G01X1241734Y59933D02*
X1241732D01*
Y54957D01*
G01X1245080Y41823D02*
X1245078D01*
Y49914D01*
G01X1235041Y59933D02*
X1235039D01*
Y54957D01*
G01X1238387Y41823D02*
X1238385D01*
Y49914D01*
G01X1224774Y52100D02*
X1225540Y51334D01*
X1226434D01*
X1227300Y52200D01*
Y53500D01*
X1226600Y54200D01*
Y55601D01*
X1228346Y57347D01*
Y59933D01*
X1228348D01*
G01Y41823D02*
X1228346D01*
Y45355D01*
X1227350Y46351D01*
Y49790D01*
X1229874Y52314D01*
G01X1225002Y59933D02*
X1225000D01*
Y57501D01*
X1223204Y55705D01*
X1222900Y55184D01*
Y51658D01*
X1223244Y51030D01*
X1224774Y49500D01*
G01X1231694Y41823D02*
X1231692D01*
Y47792D01*
X1232400Y48500D01*
Y50270D01*
X1231850Y50820D01*
X1230980D01*
X1229874Y49714D01*
G01X1220953Y513114D02*
Y511133D01*
X1221653Y510433D01*
Y505024D01*
X1221655D01*
G01X1241734Y523134D02*
Y518159D01*
X1241732Y518157D01*
G01X1245080Y505024D02*
Y513112D01*
X1245078Y513114D01*
G01X1235041Y523134D02*
X1235039Y523133D01*
Y518157D01*
G01X1238387Y505024D02*
X1238385D01*
Y513114D01*
G01X1224774Y515300D02*
X1225540Y514534D01*
X1226434D01*
X1227300Y515400D01*
Y516700D01*
X1226600Y517400D01*
Y518801D01*
X1228347Y520548D01*
Y523132D01*
X1228348Y523134D01*
G01Y505024D02*
X1228346D01*
Y508595D01*
X1227842Y509099D01*
Y510099D01*
X1226842Y511099D01*
Y512400D01*
X1228242Y513800D01*
X1228988D01*
X1229874Y512914D01*
G01X1225002Y523134D02*
X1225000Y523133D01*
Y520701D01*
X1223204Y518905D01*
X1222900Y518384D01*
Y514858D01*
X1223244Y514230D01*
X1224774Y512700D01*
G01X1229874Y515514D02*
X1230828D01*
X1231842Y514500D01*
Y509700D01*
X1231693Y509551D01*
Y505024D01*
X1231694D01*
G01X1221655Y542824D02*
X1221653D01*
Y548233D01*
X1220953Y548933D01*
Y550914D01*
G01X1241734Y560934D02*
X1241732Y560933D01*
Y555957D01*
G01X1245080Y542824D02*
X1245078D01*
Y550914D01*
G01X1235041Y560934D02*
X1235039Y560933D01*
Y555957D01*
G01X1238385Y550914D02*
Y542824D01*
X1238387D01*
G01X1228348Y560934D02*
Y558349D01*
X1226600Y556601D01*
Y555200D01*
X1227300Y554500D01*
Y553200D01*
X1226434Y552334D01*
X1225540D01*
X1224774Y553100D01*
G01X1229874Y550714D02*
X1228988Y551600D01*
X1228242D01*
X1226842Y550200D01*
Y548899D01*
X1227842Y547899D01*
Y546899D01*
X1228346Y546395D01*
Y542824D01*
X1228348D01*
G01X1225002Y560934D02*
X1225000Y560933D01*
Y558501D01*
X1223204Y556705D01*
X1222900Y556184D01*
Y552658D01*
X1223244Y552030D01*
X1224774Y550500D01*
G01X1229874Y553314D02*
X1230828D01*
X1231842Y552300D01*
Y547500D01*
X1231693Y547351D01*
Y542824D01*
X1231694D01*
G01X1221655Y580624D02*
X1221653D01*
Y586033D01*
X1220953Y586733D01*
Y588714D01*
G01X1245080Y580624D02*
X1245078D01*
Y588714D01*
G01X1238387Y580624D02*
Y588712D01*
X1238385Y588714D01*
G01X1228348Y580624D02*
X1228346D01*
Y584195D01*
X1227842Y584699D01*
Y585699D01*
X1226842Y586699D01*
Y588000D01*
X1228242Y589400D01*
X1228988D01*
X1229874Y588514D01*
G01X1225002Y598734D02*
X1225000Y598733D01*
Y596301D01*
X1223204Y594505D01*
X1222900Y593984D01*
Y590458D01*
X1223244Y589830D01*
X1224774Y588300D01*
G01X1229874Y591114D02*
X1230828D01*
X1231842Y590100D01*
Y585300D01*
X1231693Y585151D01*
Y580624D01*
X1231694D01*
G01X1241734Y598734D02*
X1241732Y598733D01*
Y593757D01*
G01X1235041Y598734D02*
X1235039Y598733D01*
Y593757D01*
G01X1228348Y598734D02*
Y596149D01*
X1226600Y594401D01*
Y593000D01*
X1227300Y592300D01*
Y591000D01*
X1226434Y590134D01*
X1225540D01*
X1224774Y590900D01*
G54D229*
G01X548049Y-193422D02*
Y-210922D01*
G01X543027Y-193422D02*
X553071D01*
G01X565549Y-199256D02*
Y-210922D01*
G01Y-194589D02*
X565112Y-194297D01*
Y-193714D01*
X565549Y-193422D01*
X565986Y-193714D01*
Y-194297D01*
X565549Y-194589D01*
G01X583049Y-210922D02*
X581739Y-210630D01*
X580429Y-209464D01*
X579555Y-207422D01*
X579119Y-205089D01*
X579555Y-202755D01*
X580429Y-200714D01*
X581739Y-199547D01*
X583049Y-199256D01*
X584359Y-199547D01*
X585669Y-200714D01*
X586542Y-202755D01*
X586761Y-205089D01*
X586542Y-207422D01*
X585669Y-209464D01*
X584359Y-210630D01*
X583049Y-210922D01*
G01X597492Y-215297D02*
X599021Y-216464D01*
X600767Y-216755D01*
X602295Y-216464D01*
X603606Y-215006D01*
X604479Y-212964D01*
Y-199256D01*
G01Y-201589D02*
X603606Y-200422D01*
X602295Y-199547D01*
X600767Y-199256D01*
X599021Y-199839D01*
X597929Y-201005D01*
X597055Y-203047D01*
X596619Y-205089D01*
X596837Y-206839D01*
X597711Y-208881D01*
X599021Y-210339D01*
X600767Y-210922D01*
X602077Y-210630D01*
X603606Y-209464D01*
X604479Y-208298D01*
G01X621979Y-210922D02*
Y-199256D01*
G01Y-201297D02*
X621106Y-200131D01*
X619795Y-199547D01*
X618267Y-199256D01*
X616739Y-199839D01*
X615429Y-201005D01*
X614555Y-202755D01*
X614119Y-205089D01*
X614555Y-207422D01*
X615429Y-209172D01*
X616739Y-210339D01*
X618267Y-210922D01*
X619795Y-210630D01*
X621106Y-209756D01*
X621979Y-208589D01*
G01X648682Y-210922D02*
Y-193422D01*
X653922D01*
X655669Y-194297D01*
X656979Y-196339D01*
X657416Y-198672D01*
X656979Y-201005D01*
X655887Y-202755D01*
X653922Y-203631D01*
X648682D01*
G01X674479Y-210922D02*
Y-199256D01*
G01Y-201297D02*
X673606Y-200131D01*
X672295Y-199547D01*
X670767Y-199256D01*
X669239Y-199839D01*
X667929Y-201005D01*
X667055Y-202755D01*
X666619Y-205089D01*
X667055Y-207422D01*
X667929Y-209172D01*
X669239Y-210339D01*
X670767Y-210922D01*
X672295Y-210630D01*
X673606Y-209756D01*
X674479Y-208589D01*
G01X684774Y-208881D02*
X685866Y-210047D01*
X687394Y-210922D01*
X688704D01*
X690014Y-210339D01*
X690887Y-209464D01*
X691324Y-208298D01*
X691106Y-206547D01*
X690232Y-205672D01*
X686302Y-203922D01*
X685429Y-201880D01*
X685866Y-200422D01*
X686739Y-199547D01*
X688049Y-199256D01*
X689359Y-199547D01*
X690669Y-200422D01*
G01X702274Y-208881D02*
X703366Y-210047D01*
X704894Y-210922D01*
X706204D01*
X707514Y-210339D01*
X708387Y-209464D01*
X708824Y-208298D01*
X708606Y-206547D01*
X707732Y-205672D01*
X703802Y-203922D01*
X702929Y-201880D01*
X703366Y-200422D01*
X704239Y-199547D01*
X705549Y-199256D01*
X706859Y-199547D01*
X708169Y-200422D01*
G01X735746Y-210922D02*
Y-193422D01*
X740112D01*
X741859Y-194297D01*
X743169Y-195464D01*
X744261Y-197213D01*
X745134Y-199256D01*
X745352Y-202172D01*
X745134Y-205089D01*
X744261Y-207131D01*
X743169Y-208881D01*
X741859Y-210047D01*
X740112Y-210922D01*
X735746D01*
G01X752590Y-193422D02*
X758049Y-210922D01*
X763508Y-193422D01*
G01X775549D02*
Y-210922D01*
G01X770527Y-193422D02*
X780571D01*
G01X804872Y-210922D02*
Y-193422D01*
X810549Y-208005D01*
X816226Y-193422D01*
Y-210922D01*
G01X829795Y-201589D02*
X830669Y-200714D01*
X831324Y-199256D01*
X831761Y-197213D01*
X831324Y-195464D01*
X830451Y-194297D01*
X828922Y-193422D01*
X823027D01*
Y-210922D01*
X830232D01*
X831761Y-209756D01*
X832634Y-208005D01*
X833071Y-205964D01*
X832634Y-203922D01*
X831324Y-202172D01*
X829795Y-201589D01*
X823027D01*
G01X647372Y-165922D02*
Y-148422D01*
X653049Y-163005D01*
X658726Y-148422D01*
Y-165922D01*
G01X670549D02*
X669239Y-165630D01*
X667929Y-164464D01*
X667055Y-162422D01*
X666619Y-160089D01*
X667055Y-157755D01*
X667929Y-155714D01*
X669239Y-154547D01*
X670549Y-154256D01*
X671859Y-154547D01*
X673169Y-155714D01*
X674042Y-157755D01*
X674261Y-160089D01*
X674042Y-162422D01*
X673169Y-164464D01*
X671859Y-165630D01*
X670549Y-165922D01*
G01X691979Y-148422D02*
Y-165922D01*
G01Y-163298D02*
X691106Y-164756D01*
X689795Y-165630D01*
X688267Y-165922D01*
X686521Y-165339D01*
X685211Y-163881D01*
X684337Y-162131D01*
X684119Y-160089D01*
X684337Y-158047D01*
X685211Y-156297D01*
X686521Y-154839D01*
X688267Y-154256D01*
X689795Y-154547D01*
X690887Y-155131D01*
X691979Y-156297D01*
G01X702274Y-158047D02*
X709261D01*
X708606Y-156005D01*
X707514Y-154839D01*
X705986Y-154256D01*
X704457Y-154547D01*
X703147Y-155422D01*
X702274Y-157464D01*
X701837Y-159214D01*
Y-160964D01*
X702274Y-162714D01*
X703366Y-164464D01*
X704676Y-165630D01*
X706204Y-165922D01*
X707732Y-165339D01*
X709261Y-163589D01*
G01X723049Y-165922D02*
Y-148422D01*
G01X975549Y-210922D02*
Y-193422D01*
X972929Y-196922D01*
G01Y-210922D02*
X978169D01*
G01X988246Y-208298D02*
X989555Y-209756D01*
X991084Y-210630D01*
X993049Y-210922D01*
X995014Y-210339D01*
X996542Y-209172D01*
X997634Y-207131D01*
X997852Y-204797D01*
X997416Y-202464D01*
X996324Y-201005D01*
X994795Y-199839D01*
X993267Y-199547D01*
X991739Y-199839D01*
X989774Y-201005D01*
X990429Y-193422D01*
X996324D01*
G01X1010549Y-210922D02*
Y-193422D01*
X1007929Y-196922D01*
G01Y-210922D02*
X1013169D01*
G01X1023901Y-196339D02*
X1025211Y-194589D01*
X1026739Y-193714D01*
X1028486Y-193422D01*
X1030669Y-194005D01*
X1032197Y-195464D01*
X1032634Y-197213D01*
X1032416Y-198964D01*
X1031542Y-200422D01*
X1027176Y-203339D01*
X1025211Y-205380D01*
X1023901Y-208298D01*
X1023464Y-210922D01*
X1032634D01*
G01X1041401Y-203631D02*
X1042929Y-201589D01*
X1044239Y-200422D01*
X1045986Y-199839D01*
X1047514Y-200422D01*
X1048606Y-201589D01*
X1049479Y-203339D01*
X1049697Y-205380D01*
X1049479Y-207131D01*
X1048606Y-208881D01*
X1047295Y-210339D01*
X1045767Y-210922D01*
X1044021Y-210339D01*
X1042492Y-208589D01*
X1041619Y-205964D01*
X1041401Y-203047D01*
X1041837Y-199256D01*
X1042492Y-197213D01*
X1043584Y-195172D01*
X1045112Y-193714D01*
X1046641Y-193422D01*
X1048169Y-194005D01*
X1049261Y-195464D01*
G01X962432Y-165922D02*
Y-148422D01*
X967672D01*
X969419Y-149297D01*
X970729Y-151339D01*
X971166Y-153672D01*
X970729Y-156005D01*
X969637Y-157755D01*
X967672Y-158631D01*
X962432D01*
G01X989102Y-149881D02*
X987792Y-149005D01*
X986264Y-148422D01*
X984517D01*
X982552Y-149297D01*
X981024Y-150755D01*
X979932Y-152506D01*
X979059Y-155422D01*
X978840Y-158047D01*
X979277Y-160672D01*
X979932Y-162422D01*
X981242Y-164172D01*
X982771Y-165339D01*
X984299Y-165922D01*
X985827D01*
X987356Y-165339D01*
X988666Y-164464D01*
X989758Y-163298D01*
G01X1003545Y-156589D02*
X1004419Y-155714D01*
X1005074Y-154256D01*
X1005511Y-152213D01*
X1005074Y-150464D01*
X1004201Y-149297D01*
X1002672Y-148422D01*
X996777D01*
Y-165922D01*
X1003982D01*
X1005511Y-164756D01*
X1006384Y-163005D01*
X1006821Y-160964D01*
X1006384Y-158922D01*
X1005074Y-157172D01*
X1003545Y-156589D01*
X996777D01*
G01X1012749Y-171755D02*
X1025849D01*
G01X1031777Y-165922D02*
Y-148422D01*
X1041821Y-165922D01*
Y-148422D01*
G01X1054299Y-165922D02*
X1052552Y-165630D01*
X1051024Y-164464D01*
X1049714Y-162714D01*
X1048840Y-160672D01*
X1048404Y-158339D01*
Y-156005D01*
X1048840Y-153672D01*
X1049714Y-151630D01*
X1051024Y-149881D01*
X1052552Y-148714D01*
X1054299Y-148422D01*
X1056045Y-148714D01*
X1057574Y-149881D01*
X1058884Y-151630D01*
X1059758Y-153672D01*
X1060194Y-156005D01*
Y-158339D01*
X1059758Y-160672D01*
X1058884Y-162714D01*
X1057574Y-164464D01*
X1056045Y-165630D01*
X1054299Y-165922D01*
G01X1128099Y-210922D02*
Y-193422D01*
X1125479Y-196922D01*
G01Y-210922D02*
X1130719D01*
G01X1147345Y-201589D02*
X1148219Y-200714D01*
X1148874Y-199256D01*
X1149311Y-197213D01*
X1148874Y-195464D01*
X1148001Y-194297D01*
X1146472Y-193422D01*
X1140577D01*
Y-210922D01*
X1147782D01*
X1149311Y-209756D01*
X1150184Y-208005D01*
X1150621Y-205964D01*
X1150184Y-203922D01*
X1148874Y-202172D01*
X1147345Y-201589D01*
X1140577D01*
G01X1105140Y-148422D02*
X1110599Y-165922D01*
X1116058Y-148422D01*
G01X1132466Y-165922D02*
X1123732D01*
Y-148422D01*
X1132466D01*
G01X1128972Y-156880D02*
X1123732D01*
G01X1141232Y-165922D02*
Y-148422D01*
X1146691D01*
X1148437Y-149297D01*
X1149529Y-150464D01*
X1149966Y-152797D01*
X1149529Y-155131D01*
X1148219Y-156589D01*
X1146691Y-157464D01*
X1141232D01*
G01X1146691D02*
X1149966Y-165922D01*
G01X1163099Y-166505D02*
X1162662Y-166214D01*
Y-165630D01*
X1163099Y-165339D01*
X1163536Y-165630D01*
Y-166214D01*
X1163099Y-166505D01*
G01X1299916Y-193422D02*
Y-210922D01*
X1291182D01*
G01X1278049D02*
Y-193422D01*
X1280669Y-196922D01*
G01Y-210922D02*
X1275429D01*
G01X1257929D02*
Y-193422D01*
X1266008Y-205964D01*
X1255090D01*
G01X1238682Y-148422D02*
Y-165922D01*
X1247416D01*
G01X1264479D02*
Y-154256D01*
G01Y-156297D02*
X1263606Y-155131D01*
X1262295Y-154547D01*
X1260767Y-154256D01*
X1259239Y-154839D01*
X1257929Y-156005D01*
X1257055Y-157755D01*
X1256619Y-160089D01*
X1257055Y-162422D01*
X1257929Y-164172D01*
X1259239Y-165339D01*
X1260767Y-165922D01*
X1262295Y-165630D01*
X1263606Y-164756D01*
X1264479Y-163589D01*
G01X1273464Y-171172D02*
X1274774Y-171755D01*
X1276521Y-171172D01*
X1277612Y-170006D01*
X1278486Y-168547D01*
X1279795Y-163881D01*
X1282634Y-154256D01*
G01X1275647D02*
X1279795Y-163881D01*
G01X1292274Y-158047D02*
X1299261D01*
X1298606Y-156005D01*
X1297514Y-154839D01*
X1295986Y-154256D01*
X1294457Y-154547D01*
X1293147Y-155422D01*
X1292274Y-157464D01*
X1291837Y-159214D01*
Y-160964D01*
X1292274Y-162714D01*
X1293366Y-164464D01*
X1294676Y-165630D01*
X1296204Y-165922D01*
X1297732Y-165339D01*
X1299261Y-163589D01*
G01X1309992Y-165922D02*
Y-154256D01*
G01Y-156589D02*
X1311084Y-155422D01*
X1312176Y-154547D01*
X1313704Y-154256D01*
X1314795Y-154547D01*
X1316106Y-155422D01*
G01X1380796Y-165922D02*
Y-148422D01*
X1385162D01*
X1386909Y-149297D01*
X1388219Y-150464D01*
X1389311Y-152213D01*
X1390184Y-154256D01*
X1390402Y-157172D01*
X1390184Y-160089D01*
X1389311Y-162131D01*
X1388219Y-163881D01*
X1386909Y-165047D01*
X1385162Y-165922D01*
X1380796D01*
G01X1399824Y-158047D02*
X1406811D01*
X1406156Y-156005D01*
X1405064Y-154839D01*
X1403536Y-154256D01*
X1402007Y-154547D01*
X1400697Y-155422D01*
X1399824Y-157464D01*
X1399387Y-159214D01*
Y-160964D01*
X1399824Y-162714D01*
X1400916Y-164464D01*
X1402226Y-165630D01*
X1403754Y-165922D01*
X1405282Y-165339D01*
X1406811Y-163589D01*
G01X1417324Y-163881D02*
X1418416Y-165047D01*
X1419944Y-165922D01*
X1421254D01*
X1422564Y-165339D01*
X1423437Y-164464D01*
X1423874Y-163298D01*
X1423656Y-161547D01*
X1422782Y-160672D01*
X1418852Y-158922D01*
X1417979Y-156880D01*
X1418416Y-155422D01*
X1419289Y-154547D01*
X1420599Y-154256D01*
X1421909Y-154547D01*
X1423219Y-155422D01*
G01X1438099Y-154256D02*
Y-165922D01*
G01Y-149589D02*
X1437662Y-149297D01*
Y-148714D01*
X1438099Y-148422D01*
X1438536Y-148714D01*
Y-149297D01*
X1438099Y-149589D01*
G01X1452542Y-170297D02*
X1454071Y-171464D01*
X1455817Y-171755D01*
X1457345Y-171464D01*
X1458656Y-170006D01*
X1459529Y-167964D01*
Y-154256D01*
G01Y-156589D02*
X1458656Y-155422D01*
X1457345Y-154547D01*
X1455817Y-154256D01*
X1454071Y-154839D01*
X1452979Y-156005D01*
X1452105Y-158047D01*
X1451669Y-160089D01*
X1451887Y-161839D01*
X1452761Y-163881D01*
X1454071Y-165339D01*
X1455817Y-165922D01*
X1457127Y-165630D01*
X1458656Y-164464D01*
X1459529Y-163298D01*
G01X1469387Y-165922D02*
Y-154256D01*
G01Y-157172D02*
X1470261Y-155714D01*
X1471571Y-154547D01*
X1473317Y-154256D01*
X1474845Y-154547D01*
X1476156Y-155714D01*
X1476811Y-157755D01*
Y-165922D01*
G01X1487324Y-158047D02*
X1494311D01*
X1493656Y-156005D01*
X1492564Y-154839D01*
X1491036Y-154256D01*
X1489507Y-154547D01*
X1488197Y-155422D01*
X1487324Y-157464D01*
X1486887Y-159214D01*
Y-160964D01*
X1487324Y-162714D01*
X1488416Y-164464D01*
X1489726Y-165630D01*
X1491254Y-165922D01*
X1492782Y-165339D01*
X1494311Y-163589D01*
G01X1505042Y-165922D02*
Y-154256D01*
G01Y-156589D02*
X1506134Y-155422D01*
X1507226Y-154547D01*
X1508754Y-154256D01*
X1509845Y-154547D01*
X1511156Y-155422D01*
G01X1426729Y-193422D02*
X1431969D01*
G01X1429349D02*
Y-210922D01*
G01X1426729D02*
X1431969D01*
G01X1441390Y-193422D02*
X1446849Y-210922D01*
X1452308Y-193422D01*
G01X1464349Y-210922D02*
Y-203047D01*
X1459982Y-193422D01*
G01X1468716D02*
X1464349Y-203047D01*
G01X1551799Y-193422D02*
X1550052Y-194005D01*
X1548742Y-195464D01*
X1547869Y-197213D01*
X1547214Y-199547D01*
X1546996Y-202172D01*
X1547214Y-204797D01*
X1547869Y-207131D01*
X1548742Y-208881D01*
X1550052Y-210339D01*
X1551799Y-210922D01*
X1553545Y-210339D01*
X1554856Y-208881D01*
X1555729Y-207131D01*
X1556384Y-204797D01*
X1556602Y-202172D01*
X1556384Y-199547D01*
X1555729Y-197213D01*
X1554856Y-195464D01*
X1553545Y-194005D01*
X1551799Y-193422D01*
G01X1565151Y-196339D02*
X1566461Y-194589D01*
X1567989Y-193714D01*
X1569736Y-193422D01*
X1571919Y-194005D01*
X1573447Y-195464D01*
X1573884Y-197213D01*
X1573666Y-198964D01*
X1572792Y-200422D01*
X1568426Y-203339D01*
X1566461Y-205380D01*
X1565151Y-208298D01*
X1564714Y-210922D01*
X1573884D01*
G01X1582869Y-211505D02*
X1590729Y-193422D01*
G01X1604299Y-210922D02*
Y-193422D01*
X1601679Y-196922D01*
G01Y-210922D02*
X1606919D01*
G01X1621799Y-193422D02*
X1620052Y-194005D01*
X1618742Y-195464D01*
X1617869Y-197213D01*
X1617214Y-199547D01*
X1616996Y-202172D01*
X1617214Y-204797D01*
X1617869Y-207131D01*
X1618742Y-208881D01*
X1620052Y-210339D01*
X1621799Y-210922D01*
X1623545Y-210339D01*
X1624856Y-208881D01*
X1625729Y-207131D01*
X1626384Y-204797D01*
X1626602Y-202172D01*
X1626384Y-199547D01*
X1625729Y-197213D01*
X1624856Y-195464D01*
X1623545Y-194005D01*
X1621799Y-193422D01*
G01X1635369Y-211505D02*
X1643229Y-193422D01*
G01X1652651Y-196339D02*
X1653961Y-194589D01*
X1655489Y-193714D01*
X1657236Y-193422D01*
X1659419Y-194005D01*
X1660947Y-195464D01*
X1661384Y-197213D01*
X1661166Y-198964D01*
X1660292Y-200422D01*
X1655926Y-203339D01*
X1653961Y-205380D01*
X1652651Y-208298D01*
X1652214Y-210922D01*
X1661384D01*
G01X1674299Y-193422D02*
X1672552Y-194005D01*
X1671242Y-195464D01*
X1670369Y-197213D01*
X1669714Y-199547D01*
X1669496Y-202172D01*
X1669714Y-204797D01*
X1670369Y-207131D01*
X1671242Y-208881D01*
X1672552Y-210339D01*
X1674299Y-210922D01*
X1676045Y-210339D01*
X1677356Y-208881D01*
X1678229Y-207131D01*
X1678884Y-204797D01*
X1679102Y-202172D01*
X1678884Y-199547D01*
X1678229Y-197213D01*
X1677356Y-195464D01*
X1676045Y-194005D01*
X1674299Y-193422D01*
G01X1691799Y-210922D02*
Y-193422D01*
X1689179Y-196922D01*
G01Y-210922D02*
X1694419D01*
G01X1708862D02*
X1709299Y-207131D01*
X1709954Y-203922D01*
X1710827Y-201005D01*
X1711919Y-197797D01*
X1713666Y-193422D01*
X1704932D01*
G01X1599496Y-165922D02*
Y-148422D01*
X1603862D01*
X1605609Y-149297D01*
X1606919Y-150464D01*
X1608011Y-152213D01*
X1608884Y-154256D01*
X1609102Y-157172D01*
X1608884Y-160089D01*
X1608011Y-162131D01*
X1606919Y-163881D01*
X1605609Y-165047D01*
X1603862Y-165922D01*
X1599496D01*
G01X1625729D02*
Y-154256D01*
G01Y-156297D02*
X1624856Y-155131D01*
X1623545Y-154547D01*
X1622017Y-154256D01*
X1620489Y-154839D01*
X1619179Y-156005D01*
X1618305Y-157755D01*
X1617869Y-160089D01*
X1618305Y-162422D01*
X1619179Y-164172D01*
X1620489Y-165339D01*
X1622017Y-165922D01*
X1623545Y-165630D01*
X1624856Y-164756D01*
X1625729Y-163589D01*
G01X1639299Y-148422D02*
Y-165922D01*
G01X1636242Y-154256D02*
X1642356D01*
G01X1653524Y-158047D02*
X1660511D01*
X1659856Y-156005D01*
X1658764Y-154839D01*
X1657236Y-154256D01*
X1655707Y-154547D01*
X1654397Y-155422D01*
X1653524Y-157464D01*
X1653087Y-159214D01*
Y-160964D01*
X1653524Y-162714D01*
X1654616Y-164464D01*
X1655926Y-165630D01*
X1657454Y-165922D01*
X1658982Y-165339D01*
X1660511Y-163589D01*
G01X348978Y337809D02*
Y336844D01*
X345844Y333710D01*
X344700D01*
X343205Y332215D01*
X340995D01*
X339556Y333654D01*
X337824D01*
X336040Y331870D01*
X334664D01*
X333060Y330266D01*
X331376D01*
X329939Y331703D01*
X327996D01*
X326143Y329850D01*
X324712D01*
X323177Y328315D01*
X321236D01*
X319701Y329850D01*
X317750D01*
X315897Y331703D01*
X314453D01*
X312650Y329900D01*
X310960D01*
X309157Y331703D01*
X307178D01*
X305741Y330266D01*
X303944D01*
X302507Y331703D01*
X300443D01*
X299006Y330266D01*
X297577D01*
X295785Y332058D01*
X294050D01*
X292258Y330266D01*
X290817D01*
X289025Y332058D01*
X287290D01*
X285498Y330266D01*
X284020D01*
X282228Y332058D01*
X280530D01*
X278738Y330266D01*
X276758D01*
X275321Y331703D01*
X273456D01*
X271853Y330100D01*
X270410D01*
X268807Y331703D01*
X266733D01*
X265240Y330210D01*
X259820D01*
G01X260800Y334110D02*
X265510D01*
X267003Y335603D01*
X268717D01*
X270154Y334166D01*
X272076D01*
X273513Y335603D01*
X275321D01*
X277224Y333700D01*
X278737D01*
X280640Y335603D01*
X282118D01*
X284021Y333700D01*
X285497D01*
X287400Y335603D01*
X288841D01*
X290278Y334166D01*
X292446D01*
X293883Y335603D01*
X295601D01*
X297454Y333750D01*
X299104D01*
X300957Y335603D01*
X302361D01*
X304164Y333800D01*
X305877D01*
X307680Y335603D01*
X315880D01*
X317383Y334100D01*
X319316D01*
X321201Y332215D01*
X322640D01*
X324475Y334050D01*
X326330D01*
X327883Y335603D01*
X329417D01*
X331270Y333750D01*
X332866D01*
X335231Y336115D01*
X336160D01*
X338045Y338000D01*
X339596D01*
X341481Y336115D01*
X342920D01*
X344871Y338066D01*
X346300D01*
X347292Y339058D01*
Y340023D01*
X348978Y341709D01*
G01Y345609D02*
Y344644D01*
X345788Y341454D01*
X344896D01*
X343042Y339600D01*
X341394D01*
X339540Y341454D01*
X338136D01*
X336282Y339600D01*
X334314D01*
X332780Y338066D01*
X331376D01*
X329939Y339503D01*
X327457D01*
X326020Y338066D01*
X325128D01*
X323177Y336115D01*
X321236D01*
X319731Y337620D01*
X311003D01*
X309120Y339503D01*
X307716D01*
X306279Y338066D01*
X303864D01*
X302427Y339503D01*
X300957D01*
X299520Y338066D01*
X297094D01*
X295657Y339503D01*
X294197D01*
X292760Y338066D01*
X290294D01*
X288857Y339503D01*
X287053D01*
X285616Y338066D01*
X283518D01*
X282081Y339503D01*
X280263D01*
X278826Y338066D01*
X277297D01*
X275860Y339503D01*
X273917D01*
X272013Y337599D01*
X270502D01*
X268598Y339503D01*
X266513D01*
X265020Y338010D01*
X261519D01*
G01X261780Y345460D02*
X264854D01*
X266694Y343620D01*
X268720D01*
X270374Y341966D01*
X271946D01*
X273383Y343403D01*
X275860D01*
X277297Y341966D01*
X278701D01*
X280493Y343758D01*
X282265D01*
X284057Y341966D01*
X285461D01*
X286898Y343403D01*
X289380D01*
X290817Y341966D01*
X292258D01*
X294050Y343758D01*
X295748D01*
X297540Y341966D01*
X298981D01*
X300773Y343758D01*
X302508D01*
X304300Y341966D01*
X305926D01*
X307363Y343403D01*
X309120D01*
X310313Y342210D01*
Y340198D01*
X310752Y339759D01*
X322921D01*
X324616Y341454D01*
X325508D01*
X327812Y343758D01*
X329328D01*
X330924Y345354D01*
X333266D01*
X334705Y343915D01*
X336405D01*
X337844Y345354D01*
X339846D01*
X341285Y343915D01*
X342920D01*
X344505Y345500D01*
X346200D01*
X348003Y347303D01*
X349747D01*
X351250Y345800D01*
X353030D01*
X354888Y347658D01*
X356586D01*
X358444Y345800D01*
X359801D01*
X361659Y347658D01*
X363508D01*
X365170Y349320D01*
X369068D01*
X369257Y349509D01*
G01X912300Y334100D02*
X912600Y333800D01*
X917358D01*
X917467Y333909D01*
G01X1062680Y361604D02*
Y360389D01*
X1062933Y360136D01*
Y358566D01*
X1061824Y357457D01*
X1060254D01*
X1060051Y357254D01*
X1059909D01*
X1059445Y356790D01*
X1056570D01*
X1054900Y355120D01*
Y353490D01*
X1054358Y352948D01*
Y352707D01*
X1053366Y351715D01*
X1053125D01*
X1051176Y349766D01*
X1039670D01*
X1039265Y349361D01*
X1038420D01*
X1037901Y348842D01*
X1036553D01*
X1033431Y345720D01*
X1028449D01*
X1026759Y347410D01*
X1025090D01*
X1023200Y349300D01*
X1019074D01*
X1018865Y349509D01*
G54D157*
X1624249Y156438D03*
X1680200Y165650D03*
X1780103Y69879D03*
X1833650Y98250D03*
G54D148*
X1552100Y86000D03*
Y94000D03*
X1560900Y90000D03*
G54D175*
X1756750Y81060D03*
Y75940D03*
X1763250Y78500D03*
Y75940D03*
Y81060D03*
G54D193*
X1874940Y51300D03*
G54D55*
X75500Y279500D03*
Y274000D03*
X51200Y496250D03*
Y490750D03*
X194600Y242848D03*
Y248348D03*
Y238348D03*
Y232848D03*
Y274000D03*
Y279500D03*
Y303000D03*
Y308500D03*
Y335730D03*
Y341230D03*
Y363600D03*
Y369100D03*
X454148Y299091D03*
Y304591D03*
Y288341D03*
Y282841D03*
X714950Y12050D03*
Y17550D03*
X723135Y4952D03*
Y-548D03*
X680600Y42300D03*
Y47800D03*
X667500Y294800D03*
Y289300D03*
X679800Y528500D03*
Y534000D03*
X717203Y588502D03*
X712101Y588262D03*
X717203Y594002D03*
X712101Y593762D03*
X729335Y4952D03*
Y-548D03*
X729350Y506700D03*
Y501200D03*
X844500Y238480D03*
Y232980D03*
Y242980D03*
Y248480D03*
Y271500D03*
Y277000D03*
Y303200D03*
Y308700D03*
Y334750D03*
Y340250D03*
Y366300D03*
Y371800D03*
X1103756Y299091D03*
Y304591D03*
Y288341D03*
Y282841D03*
X1338500Y101500D03*
Y107000D03*
X1335900Y512800D03*
Y518300D03*
X1304500Y619000D03*
Y613500D03*
X1528100Y426600D03*
Y432100D03*
X1472500Y538250D03*
Y543750D03*
X1477500Y538250D03*
Y543750D03*
X1499400Y536000D03*
Y541500D03*
X1514600Y536000D03*
Y541500D03*
X1509600Y536000D03*
Y541500D03*
X1504300Y536000D03*
Y541500D03*
X1585064Y122049D03*
Y116549D03*
X1576187Y131439D03*
Y136939D03*
X1583500Y127000D03*
Y132500D03*
X1580364Y116549D03*
Y122049D03*
X1580000Y399350D03*
X1575300D03*
X1580000Y404850D03*
X1579814Y434014D03*
Y439514D03*
X1575300Y404850D03*
X1575500Y431000D03*
Y425500D03*
X1571584Y561509D03*
Y556009D03*
X1576520Y561500D03*
Y556000D03*
X1632849Y134888D03*
Y140388D03*
X1609300Y403200D03*
X1604000Y403250D03*
X1590700Y465250D03*
Y459750D03*
X1608000Y464546D03*
X1595500Y465250D03*
Y459750D03*
X1590600Y422250D03*
Y416750D03*
X1600000Y422250D03*
Y416750D03*
X1609300Y408700D03*
X1604000Y408750D03*
X1595300Y422250D03*
Y416750D03*
X1608000Y470046D03*
X1674031Y166649D03*
Y161149D03*
X1828090Y156630D03*
X1833650Y156830D03*
X1828090Y162130D03*
X1833650Y162330D03*
X1869490Y112980D03*
Y107480D03*
X1895137Y105252D03*
Y110752D03*
X1843600Y158200D03*
Y163700D03*
X1901400Y156850D03*
Y151350D03*
X1912100Y156400D03*
X1910500Y185750D03*
Y191250D03*
X1912100Y161900D03*
G54D64*
X68418Y325500D03*
X65859D03*
X68418Y332500D03*
X63300D03*
X65859D03*
X63300Y325500D03*
X663000Y507500D03*
Y500500D03*
X668118D03*
X665559Y507500D03*
X668118D03*
X1231394Y116162D03*
X1233953D03*
X1228835D03*
Y109162D03*
X1231394D03*
X1233953D03*
X1241772Y109188D03*
X1239213D03*
X1244331D03*
Y116188D03*
X1241772D03*
X1239213D03*
X1306320Y28900D03*
X1303760D03*
X1301200D03*
X1306320Y35900D03*
X1301200D03*
X1303760D03*
X1596082Y219000D03*
X1598641D03*
X1596082Y212000D03*
X1601200D03*
X1598641D03*
X1601200Y219000D03*
X1759067Y586743D03*
X1753949D03*
X1756508Y593743D03*
X1759067D03*
X1753949D03*
X1795436Y131481D03*
X1792877Y138481D03*
X1790318Y131481D03*
X1795436Y138481D03*
X1790318D03*
X1789300Y506600D03*
X1784182Y513600D03*
X1786741Y506600D03*
X1789300Y513600D03*
X1784182Y506600D03*
X1812800Y510600D03*
X1817918Y503600D03*
X1815359Y510600D03*
X1812800Y503600D03*
X1817918Y510600D03*
X1804541D03*
X1807100D03*
X1804541Y503600D03*
X1807100D03*
X1801982D03*
Y510600D03*
X1894968Y213827D03*
Y220827D03*
X1897527D03*
X1900086Y213827D03*
X1936369Y190204D03*
X1938928D03*
X1936369Y183204D03*
X1941487D03*
X1938928D03*
X1941487Y190204D03*
X1900086Y220827D03*
X1943518Y517500D03*
X1938400Y524500D03*
X1940959D03*
X1938400Y517500D03*
X1943518Y524500D03*
X1942722Y505100D03*
X1945281Y498100D03*
X1947840D03*
Y505100D03*
X1942722Y498100D03*
X1951439Y519250D03*
X1948880D03*
X1951439Y526250D03*
X1948880D03*
X1953998D03*
Y519250D03*
X1931059Y546500D03*
X1928500D03*
X1931059Y553500D03*
X1925941D03*
X1928500D03*
X1925941Y546500D03*
X1931059Y599000D03*
X1928500Y606000D03*
X1925941D03*
Y599000D03*
X1931059Y606000D03*
X1967040Y506010D03*
X1961922Y513010D03*
X1964481Y506010D03*
X1967040Y513010D03*
X1961922Y506010D03*
X1969500Y583300D03*
X1966941D03*
X1964382D03*
X1964882Y570000D03*
X1970000Y563000D03*
X1967441D03*
X1970000Y570000D03*
X1964882Y563000D03*
X1964382Y590300D03*
X1969500D03*
G54D184*
X1730814Y565314D03*
X1728254Y575914D03*
X1733369D03*
X1725694D03*
X1730814D03*
X1733369Y565314D03*
X1728254D03*
X1725694D03*
G54D91*
X594800Y366894D03*
G54D19*
X-17190Y471340D03*
Y474840D03*
X41542Y16578D03*
Y13078D03*
X44542Y16578D03*
Y13078D03*
X7600Y29800D03*
Y33300D03*
X41000Y271400D03*
Y267900D03*
X37000Y271400D03*
Y267900D03*
X46900Y298100D03*
Y294600D03*
X-8690Y460640D03*
Y464140D03*
X-13690Y460640D03*
Y464140D03*
X-5690Y473840D03*
Y470340D03*
X-8690Y473840D03*
Y470340D03*
X-500Y517500D03*
Y521000D03*
X-3500Y517500D03*
Y521000D03*
X31600Y517600D03*
Y521100D03*
X-12690Y481740D03*
Y478240D03*
X-9190Y481740D03*
Y478240D03*
X-12190Y471140D03*
Y467640D03*
X-2600Y538900D03*
Y542400D03*
X105700Y122000D03*
Y118500D03*
X102400D03*
Y122000D03*
X71500Y176500D03*
Y180000D03*
X75000Y176500D03*
Y180000D03*
X85500Y278500D03*
Y275000D03*
X80500Y278500D03*
Y275000D03*
X106600Y307000D03*
Y303500D03*
X69000Y341800D03*
X57000Y341500D03*
X91000Y317500D03*
Y321000D03*
X56000Y296200D03*
Y299700D03*
X94000Y307000D03*
Y303500D03*
X97500D03*
Y307000D03*
X89000Y309500D03*
Y306000D03*
X72000Y341800D03*
X101000Y303500D03*
Y307000D03*
X87500Y317500D03*
Y321000D03*
X69000Y292500D03*
Y289000D03*
X72500Y292500D03*
Y289000D03*
X69000Y345300D03*
X57000Y345000D03*
X75000Y372600D03*
Y376100D03*
X79500Y372600D03*
Y376100D03*
X72000Y345300D03*
X52601Y483087D03*
Y486587D03*
X106392Y534500D03*
Y531000D03*
X105392Y572300D03*
Y568800D03*
X105892Y612000D03*
Y608500D03*
X122000Y256500D03*
Y253000D03*
Y222900D03*
Y219400D03*
X122100Y287600D03*
Y284100D03*
Y320400D03*
Y316900D03*
X121800Y345800D03*
Y349300D03*
X121862Y377600D03*
Y381100D03*
X108892Y572300D03*
Y568800D03*
X112392Y572300D03*
Y568800D03*
X116892Y531000D03*
Y534500D03*
X115892Y568800D03*
Y572300D03*
X109892Y534500D03*
Y531000D03*
X113392Y534500D03*
Y531000D03*
X109392Y612000D03*
Y608500D03*
X112892Y612000D03*
Y608500D03*
X116392D03*
Y612000D03*
X195200Y382800D03*
Y386300D03*
X253000Y258600D03*
Y255100D03*
X249000Y258600D03*
Y255100D03*
X461000Y317303D03*
Y320803D03*
X510937Y262947D03*
Y266447D03*
X507400Y264496D03*
Y260996D03*
X514220Y263291D03*
Y266791D03*
X661800Y25500D03*
Y29000D03*
X656500Y-14000D03*
Y-17500D03*
X653150Y-14000D03*
Y-17500D03*
X650050Y-14300D03*
Y-17800D03*
X638500Y270500D03*
Y274000D03*
Y277000D03*
X663500Y254000D03*
Y257500D03*
X638488Y249513D03*
Y246013D03*
X646000Y261500D03*
Y265000D03*
X643823Y286894D03*
Y283394D03*
X639622Y286894D03*
Y283394D03*
X638500Y280500D03*
X654000Y342000D03*
X659000D03*
X649000D03*
X655500Y290000D03*
Y293500D03*
X658617Y288371D03*
Y291871D03*
X661767Y289974D03*
Y293474D03*
X654000Y345500D03*
X659000D03*
X649000D03*
X662000Y488500D03*
Y485000D03*
X636930Y488050D03*
Y484550D03*
X624700Y484100D03*
Y487600D03*
X632930Y484550D03*
Y488050D03*
X618430Y485050D03*
Y488550D03*
X614430Y485050D03*
Y488550D03*
X631600Y477600D03*
Y481100D03*
X614930Y481550D03*
Y478050D03*
X618430Y481550D03*
Y478050D03*
X713937Y-6048D03*
Y-9548D03*
X722937Y17452D03*
Y20952D03*
X719437Y17452D03*
Y20952D03*
X711233Y82298D03*
Y78798D03*
X707893Y82298D03*
Y78798D03*
X694000Y76000D03*
Y79500D03*
X716500Y53500D03*
Y50000D03*
X710500Y252500D03*
Y256000D03*
X673500Y291500D03*
Y295000D03*
X683000Y291300D03*
Y294800D03*
X684000Y342000D03*
X674000D03*
X679000D03*
X669000D03*
X722500Y283300D03*
Y286800D03*
X700500Y308000D03*
Y311500D03*
X664000Y342000D03*
X668500Y332500D03*
Y336000D03*
X684000Y345500D03*
X689000Y352500D03*
Y349000D03*
X693000Y352500D03*
Y349000D03*
X674000Y345500D03*
X679000D03*
X669000D03*
X664000D03*
X680500Y493000D03*
Y496500D03*
X673464Y503784D03*
Y507284D03*
X716000Y577500D03*
Y574000D03*
X722500Y577500D03*
Y574000D03*
X716400Y538800D03*
Y535300D03*
X728500Y283500D03*
Y287000D03*
X769600Y407600D03*
Y404100D03*
X766300Y407700D03*
Y404200D03*
X763200Y407700D03*
Y404200D03*
X765500Y568800D03*
Y572300D03*
X762000D03*
Y568800D03*
X759500Y534500D03*
Y531000D03*
X766500D03*
Y534500D03*
X763000D03*
Y531000D03*
X758500Y572300D03*
Y568800D03*
X755000Y572300D03*
Y568800D03*
X756000Y534500D03*
Y531000D03*
X759000Y612000D03*
Y608500D03*
X762500Y612000D03*
Y608500D03*
X766000D03*
Y612000D03*
X727000Y600500D03*
Y604000D03*
X755500Y612000D03*
Y608500D03*
X844808Y382800D03*
Y386300D03*
X899450Y258050D03*
Y254550D03*
X903050Y257950D03*
Y254450D03*
X1156980Y260920D03*
Y264420D03*
X1157013Y254048D03*
Y257548D03*
X1110300Y317800D03*
Y321300D03*
X1218254Y113956D03*
Y110456D03*
X1164900Y264826D03*
Y268326D03*
X1224924Y110448D03*
Y113948D03*
X1221682Y110456D03*
Y113956D03*
X1231442Y121275D03*
Y124775D03*
X1236600Y124877D03*
Y121377D03*
X1250890Y497310D03*
Y493810D03*
X1254390D03*
Y497310D03*
X1264700Y492143D03*
Y488643D03*
X1301500Y20000D03*
Y23500D03*
X1297000Y29500D03*
Y33000D03*
X1301100Y42600D03*
Y46100D03*
X1304500Y42600D03*
Y46100D03*
X1303697Y145379D03*
Y148879D03*
X1307197Y145379D03*
Y148879D03*
X1339889Y234171D03*
Y237671D03*
X1330800Y220450D03*
Y223950D03*
X1334389Y234171D03*
Y237671D03*
X1312389Y234171D03*
Y237671D03*
X1317889Y234171D03*
Y237671D03*
X1323389Y234171D03*
Y237671D03*
X1328889Y234171D03*
Y237671D03*
X1334389D03*
Y241171D03*
X1339889Y237671D03*
Y241171D03*
X1317889Y237671D03*
Y241171D03*
X1323389Y237671D03*
Y241171D03*
X1328889Y237671D03*
Y241171D03*
X1312389Y237671D03*
Y241171D03*
X1339800Y336800D03*
Y340300D03*
X1322430Y337460D03*
Y333960D03*
X1327400Y333930D03*
Y337430D03*
X1339240Y309384D03*
Y305884D03*
Y302384D03*
Y305884D03*
X1333740Y309384D03*
Y305884D03*
Y302384D03*
Y305884D03*
X1339800Y346800D03*
Y343300D03*
X1337600Y442100D03*
Y438600D03*
X1375500Y68500D03*
Y65000D03*
X1376500Y113600D03*
Y110100D03*
X1394889Y234171D03*
Y237671D03*
X1378389Y234171D03*
Y237671D03*
X1367389Y234171D03*
Y237671D03*
X1372889Y234171D03*
Y237671D03*
X1361889Y234171D03*
Y237671D03*
X1356389Y234171D03*
Y237671D03*
X1389389Y234171D03*
Y237671D03*
X1350889Y234171D03*
Y237671D03*
X1345389Y234171D03*
Y237671D03*
X1383889Y234171D03*
Y237671D03*
X1394889D03*
Y241171D03*
X1350889Y237671D03*
Y241171D03*
X1389389Y237671D03*
Y241171D03*
X1383889Y237671D03*
Y241171D03*
X1378389Y237671D03*
Y241171D03*
X1367389Y237671D03*
Y241171D03*
X1372889Y237671D03*
Y241171D03*
X1361889Y237671D03*
Y241171D03*
X1356389Y237671D03*
Y241171D03*
X1345389Y237671D03*
Y241171D03*
X1357000Y329000D03*
Y325500D03*
X1353500D03*
Y329000D03*
X1395135Y310254D03*
Y306754D03*
Y303254D03*
Y306754D03*
X1400537Y310254D03*
Y306754D03*
Y303254D03*
Y306754D03*
X1371000Y325400D03*
Y328900D03*
X1374500Y325400D03*
Y328900D03*
X1350000Y325500D03*
Y329000D03*
X1361544Y309384D03*
Y305884D03*
X1356044Y302384D03*
Y305884D03*
X1361544Y302384D03*
Y305884D03*
X1383548Y309934D03*
Y306434D03*
X1389635Y303254D03*
Y306754D03*
X1383548Y302934D03*
Y306434D03*
X1389635Y310254D03*
Y306754D03*
X1378048Y302934D03*
Y306434D03*
Y309934D03*
Y306434D03*
X1345142Y309384D03*
Y305884D03*
X1350642Y309384D03*
Y305884D03*
X1345142Y302384D03*
Y305884D03*
X1350642Y302384D03*
Y305884D03*
X1366840Y302754D03*
Y306254D03*
X1372340Y302754D03*
Y306254D03*
X1366840Y309754D03*
Y306254D03*
X1372340Y309754D03*
Y306254D03*
X1356044Y309384D03*
Y305884D03*
X1396052Y357720D03*
Y354220D03*
X1391212Y357760D03*
Y354260D03*
X1348988Y355077D03*
Y351577D03*
X1387500Y423600D03*
Y427100D03*
X1371500Y526000D03*
Y529500D03*
X1379100Y578000D03*
Y574500D03*
X1379200Y609300D03*
Y605800D03*
X1455100Y24550D03*
Y21050D03*
X1451600Y24550D03*
Y21050D03*
X1464500Y20750D03*
Y24250D03*
X1448600Y24550D03*
Y21050D03*
X1416800Y16700D03*
Y20200D03*
X1413800Y16700D03*
Y20200D03*
X1410800Y16700D03*
Y20200D03*
X1457000Y108500D03*
Y112000D03*
X1445500Y153300D03*
Y156800D03*
X1447391Y142729D03*
Y139229D03*
X1447428Y145543D03*
Y149043D03*
X1463900Y205550D03*
Y202050D03*
X1465234Y183258D03*
Y186758D03*
X1462059Y191683D03*
Y188183D03*
X1426261Y176309D03*
Y179809D03*
Y163309D03*
Y166809D03*
X1445500Y163300D03*
Y159800D03*
X1426261Y169809D03*
Y173309D03*
Y186309D03*
Y182809D03*
X1438500Y163300D03*
Y159800D03*
X1442000Y163300D03*
Y159800D03*
X1464500Y262100D03*
Y258600D03*
X1454500Y251250D03*
Y247750D03*
X1458500Y249000D03*
Y245500D03*
X1443000Y248750D03*
Y245250D03*
X1446000Y248750D03*
Y245250D03*
X1440000Y248750D03*
Y245250D03*
X1458011Y264408D03*
Y267908D03*
X1460835Y261026D03*
Y257526D03*
X1457835D03*
Y261026D03*
X1430900Y250350D03*
Y246850D03*
X1406037Y303254D03*
Y306754D03*
X1411220Y310284D03*
Y306784D03*
X1416720Y310284D03*
Y306784D03*
Y303284D03*
Y306784D03*
X1411220Y303284D03*
Y306784D03*
X1406037Y310254D03*
Y306754D03*
X1460868Y373393D03*
Y369893D03*
X1425600Y523700D03*
X1422000D03*
X1416600Y524500D03*
X1460600Y521100D03*
Y517600D03*
X1425600Y527200D03*
X1422000D03*
X1416600Y528000D03*
X1460500Y537500D03*
Y534000D03*
X1468000Y20750D03*
Y24250D03*
X1471500Y20750D03*
Y24250D03*
X1505500Y9641D03*
Y6141D03*
X1502300Y9641D03*
Y6141D03*
X1487000Y83500D03*
Y80000D03*
Y73500D03*
Y77000D03*
X1520904Y51355D03*
Y47855D03*
X1486193Y103797D03*
Y107297D03*
X1485150Y148500D03*
Y145000D03*
X1466188Y171277D03*
Y167777D03*
X1471988Y166677D03*
Y170177D03*
X1467992Y205635D03*
Y202135D03*
X1480988Y166677D03*
Y170177D03*
X1477988Y166677D03*
Y170177D03*
X1474988Y166677D03*
Y170177D03*
X1484100Y177700D03*
Y174200D03*
X1493700Y185400D03*
Y181900D03*
X1487230Y261150D03*
Y264650D03*
X1490310Y261140D03*
Y264640D03*
X1478000Y263500D03*
Y260000D03*
X1484000Y263500D03*
Y260000D03*
X1481000D03*
Y263500D03*
X1493450Y261140D03*
Y264640D03*
X1472000Y260000D03*
Y263500D03*
X1475000D03*
Y260000D03*
X1477500Y219350D03*
Y222850D03*
X1476800Y231000D03*
Y227500D03*
X1470554Y236923D03*
Y233423D03*
X1478424Y241688D03*
Y245188D03*
X1467054Y236923D03*
Y233423D03*
X1518952Y337082D03*
Y333582D03*
X1521952Y337082D03*
Y333582D03*
X1490500Y336000D03*
Y339500D03*
X1502850Y336900D03*
Y333400D03*
X1515952Y337082D03*
Y333582D03*
X1512952Y337082D03*
Y333582D03*
X1490000Y332100D03*
Y328600D03*
X1523000Y347250D03*
Y343750D03*
X1520000Y347250D03*
Y343750D03*
X1526000Y347250D03*
Y343750D03*
X1466967Y353465D03*
Y349965D03*
X1477500Y348750D03*
Y352250D03*
X1474049Y350889D03*
Y347389D03*
X1499000Y347250D03*
Y343750D03*
X1496000Y347250D03*
Y343750D03*
X1493000Y347250D03*
Y343750D03*
X1481000Y343250D03*
Y346750D03*
X1494023Y361853D03*
Y358353D03*
X1475500Y358750D03*
Y355250D03*
X1505000Y347250D03*
Y343750D03*
X1502000Y347250D03*
Y343750D03*
X1481164Y359387D03*
Y362887D03*
X1517000Y346650D03*
Y343150D03*
X1502800Y356420D03*
Y359920D03*
X1470467Y349965D03*
Y353465D03*
X1486572Y432791D03*
Y436291D03*
X1506800Y454500D03*
Y451000D03*
X1479150Y430678D03*
Y434178D03*
X1522870Y503200D03*
Y499700D03*
X1525700Y515310D03*
Y511810D03*
X1483700Y521700D03*
Y518200D03*
X1476600Y523100D03*
Y519600D03*
X1478000Y527250D03*
Y530750D03*
X1483200Y537200D03*
Y533700D03*
X1494800Y536700D03*
Y540200D03*
X1472300Y608439D03*
Y611939D03*
X1507952Y608439D03*
Y611939D03*
X1549000Y74450D03*
Y77950D03*
X1562909Y64718D03*
Y68218D03*
X1559909Y64718D03*
Y68218D03*
X1544814Y77485D03*
Y80985D03*
X1551050Y39445D03*
Y42945D03*
X1548050Y39445D03*
Y42945D03*
X1577431Y90987D03*
Y87487D03*
X1586149Y94288D03*
X1557277Y49563D03*
Y46063D03*
X1580531Y87500D03*
Y91000D03*
X1588000Y138500D03*
Y142000D03*
X1579167Y107718D03*
Y104218D03*
X1568000Y111500D03*
Y108000D03*
X1565500Y152500D03*
Y149000D03*
X1562500Y152500D03*
Y149000D03*
X1547400Y149700D03*
Y146200D03*
X1561709Y124081D03*
Y120581D03*
X1552171Y130471D03*
Y126971D03*
X1566481Y127454D03*
Y130954D03*
X1582649Y103288D03*
Y106788D03*
X1586149Y97788D03*
X1551858Y98991D03*
Y102491D03*
X1576414Y117787D03*
Y121287D03*
X1588156Y125638D03*
Y129138D03*
X1576040Y210090D03*
Y213590D03*
X1574500Y217000D03*
X1579540Y210090D03*
Y213590D03*
X1583190Y210070D03*
Y213570D03*
X1574500Y220500D03*
Y223500D03*
Y227000D03*
X1535966Y337018D03*
Y333518D03*
X1539000Y337000D03*
Y333500D03*
X1582000Y292500D03*
Y289000D03*
X1585000Y292500D03*
Y289000D03*
X1539000Y340750D03*
X1556500Y334750D03*
Y338250D03*
X1553500Y334750D03*
Y338250D03*
X1545000Y340750D03*
X1563000Y338250D03*
Y334750D03*
X1566000Y338250D03*
Y334750D03*
X1542000Y340750D03*
X1536000D03*
X1533000D03*
X1584000Y347250D03*
Y343750D03*
X1581000Y347250D03*
Y343750D03*
X1539000Y344250D03*
X1553500Y343750D03*
Y347250D03*
X1556500Y343750D03*
Y347250D03*
X1559500D03*
Y343750D03*
X1545000Y344250D03*
X1529000Y347250D03*
Y343750D03*
X1542000Y344250D03*
X1536000D03*
X1533000D03*
X1562500Y347300D03*
Y343800D03*
X1565500D03*
Y347300D03*
X1568600Y344050D03*
Y347550D03*
X1571800Y347800D03*
Y344300D03*
X1579000Y413250D03*
Y409750D03*
X1579500Y425250D03*
Y421750D03*
X1546596Y441697D03*
Y445197D03*
X1545271Y419162D03*
Y422662D03*
X1573877Y451641D03*
Y455141D03*
X1577782Y451536D03*
Y455036D03*
Y461336D03*
Y457836D03*
X1574377Y457941D03*
Y461441D03*
X1575500Y435000D03*
Y438500D03*
X1586670Y463250D03*
X1528100Y443350D03*
Y446850D03*
X1528500Y420500D03*
Y417000D03*
X1529000Y515310D03*
Y511810D03*
X1588300Y487500D03*
Y484000D03*
X1586670Y466750D03*
X1584500Y586600D03*
Y583100D03*
X1537700Y610897D03*
Y607397D03*
X1644000Y22250D03*
Y25750D03*
Y28750D03*
Y32250D03*
X1613000Y-14218D03*
Y-10718D03*
X1621500Y32750D03*
Y29250D03*
Y22250D03*
Y25750D03*
X1606500Y30750D03*
Y27250D03*
Y20750D03*
Y17250D03*
X1592453Y6002D03*
Y2502D03*
X1641600Y84000D03*
Y87500D03*
Y94000D03*
Y90500D03*
X1602000Y87250D03*
Y90750D03*
X1603800Y54950D03*
Y51450D03*
X1638500Y84000D03*
Y87500D03*
Y94000D03*
Y90500D03*
X1600300Y57950D03*
Y54450D03*
X1641600Y99000D03*
Y102500D03*
X1596865Y145871D03*
Y149371D03*
X1590949Y104288D03*
Y100788D03*
X1597349D03*
Y104288D03*
X1604400Y119300D03*
Y115800D03*
X1604939Y132088D03*
Y128588D03*
X1601400Y113100D03*
Y116600D03*
X1648500Y141750D03*
Y138250D03*
X1644930Y153700D03*
X1641274Y130773D03*
Y127273D03*
X1638500Y99000D03*
Y102500D03*
X1648500Y128750D03*
Y125250D03*
X1632050Y145170D03*
Y148670D03*
X1594149Y100788D03*
Y104288D03*
X1635000Y125750D03*
Y122250D03*
X1648500Y131750D03*
Y135250D03*
X1626900Y144300D03*
Y147800D03*
X1591356Y125638D03*
Y129138D03*
X1639649Y179288D03*
Y175788D03*
X1642649Y179288D03*
Y175788D03*
X1648349D03*
Y179288D03*
X1636649D03*
Y175788D03*
X1625000Y177808D03*
Y181308D03*
X1610500Y188500D03*
Y192000D03*
X1618940Y175780D03*
Y179280D03*
X1616500Y188500D03*
Y192000D03*
X1613500Y188500D03*
Y192000D03*
X1644930Y157200D03*
X1605760Y224590D03*
Y221090D03*
X1650473Y319500D03*
Y323000D03*
X1644300Y288050D03*
Y291550D03*
X1647300Y288050D03*
Y291550D03*
X1626217Y360391D03*
Y363891D03*
X1626100Y373700D03*
Y370200D03*
X1602700Y466900D03*
Y470400D03*
X1611175Y477667D03*
Y481167D03*
X1645256Y558000D03*
Y554500D03*
X1641756D03*
Y558000D03*
X1665000Y26250D03*
Y29750D03*
Y23250D03*
Y19750D03*
X1662600Y49000D03*
Y52500D03*
X1676400Y69500D03*
Y66000D03*
X1691800Y88700D03*
Y92200D03*
X1694800D03*
Y88700D03*
X1697800Y92200D03*
Y88700D03*
X1700800D03*
Y92200D03*
X1656000Y94500D03*
Y91000D03*
Y84500D03*
Y88000D03*
X1672500Y109800D03*
Y106300D03*
X1656000Y97500D03*
Y101000D03*
X1653849Y175788D03*
Y179288D03*
X1666701Y176011D03*
Y179511D03*
X1670081Y164849D03*
Y161349D03*
X1663681Y164849D03*
Y161349D03*
X1666881Y164849D03*
Y161349D03*
X1659500Y317250D03*
Y320750D03*
X1651500Y291650D03*
Y288150D03*
X1661248Y308711D03*
Y305211D03*
X1656000Y324250D03*
Y320750D03*
X1663280Y287691D03*
Y291191D03*
X1660080Y287691D03*
Y291191D03*
X1710101Y558628D03*
Y555128D03*
X1680000Y555900D03*
Y559400D03*
X1674000Y555500D03*
Y559000D03*
X1670000Y555500D03*
Y559000D03*
X1663000Y555400D03*
Y558900D03*
X1659500Y555400D03*
Y558900D03*
X1684000Y555900D03*
Y559400D03*
X1773100Y15200D03*
Y18700D03*
X1769250Y81070D03*
Y84570D03*
X1762300Y51600D03*
Y48100D03*
X1740300Y92100D03*
X1752060Y92110D03*
X1749810Y85620D03*
Y82120D03*
X1748550Y148138D03*
Y144638D03*
X1754825Y113100D03*
Y116600D03*
X1733403Y130212D03*
Y126712D03*
X1748425Y113100D03*
Y116600D03*
X1751625Y113100D03*
Y116600D03*
X1758025Y113100D03*
Y116600D03*
X1740300Y95600D03*
X1752060Y95610D03*
X1771525Y202827D03*
Y206327D03*
X1759497Y202827D03*
Y206327D03*
X1763497Y202827D03*
Y206327D03*
X1734100Y202400D03*
Y205900D03*
X1726000Y202750D03*
Y206250D03*
X1722500Y202750D03*
Y206250D03*
X1719000Y202750D03*
Y206250D03*
X1729500Y202750D03*
Y206250D03*
X1737600Y202400D03*
Y205900D03*
X1750589Y202571D03*
Y206071D03*
X1746589Y202571D03*
Y206071D03*
X1757220Y258433D03*
Y254933D03*
X1760420Y258433D03*
Y254933D03*
X1753900Y258400D03*
Y254900D03*
X1747500Y258400D03*
Y254900D03*
X1744300Y258400D03*
Y254900D03*
X1750700Y258400D03*
Y254900D03*
X1760000Y455130D03*
Y458630D03*
X1768500Y455130D03*
Y458630D03*
X1772500Y455130D03*
Y458630D03*
X1743500Y455130D03*
Y458630D03*
X1747500Y455130D03*
Y458630D03*
X1756000Y455130D03*
Y458630D03*
X1764900Y512800D03*
Y509300D03*
X1768400Y512800D03*
Y509300D03*
X1730950Y586000D03*
Y582500D03*
X1733950Y586004D03*
Y582504D03*
X1726850Y559000D03*
Y555500D03*
X1723000Y559000D03*
Y555500D03*
X1714101Y558628D03*
Y555128D03*
X1729950Y559000D03*
Y555500D03*
X1720550Y586250D03*
X1765000Y579000D03*
Y582500D03*
X1736097Y596859D03*
Y593359D03*
X1757057Y598292D03*
Y601792D03*
X1720550Y589750D03*
X1760157Y598243D03*
Y601743D03*
X1822400Y24700D03*
Y28200D03*
X1825500Y14250D03*
Y17750D03*
X1833236Y32980D03*
Y29480D03*
X1829236Y32980D03*
Y29480D03*
X1821250Y94500D03*
Y91000D03*
X1786700Y81450D03*
Y77950D03*
X1795377Y126231D03*
Y122731D03*
X1798377D03*
Y126231D03*
X1780623Y113769D03*
Y117269D03*
X1789300Y171000D03*
Y167500D03*
X1826100Y202927D03*
Y206427D03*
X1822100Y202927D03*
Y206427D03*
X1775525Y202827D03*
Y206327D03*
X1788300Y202527D03*
Y206027D03*
X1797200Y203127D03*
Y206627D03*
X1801200Y203127D03*
Y206627D03*
X1809600Y203027D03*
Y206527D03*
X1813600Y203027D03*
Y206527D03*
X1784300Y202527D03*
Y206027D03*
X1823000Y455130D03*
Y458630D03*
X1836000Y455130D03*
Y458630D03*
X1832000Y455130D03*
Y458630D03*
X1819000Y455130D03*
Y458630D03*
X1806500Y455130D03*
Y458630D03*
X1810500Y455130D03*
Y458630D03*
X1781500Y455130D03*
Y458630D03*
X1798000Y455130D03*
Y458630D03*
X1794000Y455130D03*
Y458630D03*
X1785500Y455130D03*
Y458630D03*
X1825000Y507200D03*
Y503700D03*
X1779300Y519100D03*
Y515600D03*
X1817900Y495600D03*
Y499100D03*
X1814400Y495600D03*
Y499100D03*
X1779300Y508100D03*
Y511600D03*
X1828600Y532500D03*
Y529000D03*
X1822052Y569001D03*
Y572501D03*
X1833052Y575501D03*
Y579001D03*
Y586001D03*
Y582501D03*
X1802400Y559100D03*
Y562600D03*
X1798400Y559100D03*
Y562600D03*
X1789188Y565224D03*
Y568724D03*
X1825552Y569001D03*
Y572501D03*
X1798250Y535300D03*
Y531800D03*
X1790500Y555600D03*
Y559100D03*
X1782700Y608400D03*
Y604900D03*
X1785700Y608400D03*
Y604900D03*
X1842000Y13750D03*
Y17250D03*
X1886465Y-15068D03*
Y-18568D03*
X1844835Y20168D03*
Y23668D03*
X1889575Y-15062D03*
Y-18562D03*
X1843236Y41480D03*
Y37980D03*
X1847236Y41480D03*
Y37980D03*
Y41480D03*
Y44980D03*
X1843236Y41480D03*
Y44980D03*
X1853600Y56800D03*
Y60300D03*
X1870817Y64594D03*
Y61094D03*
X1881290Y112580D03*
Y109080D03*
X1897500Y131500D03*
Y128000D03*
X1881000Y130750D03*
Y134250D03*
X1877500Y130750D03*
Y134250D03*
X1874939Y112567D03*
Y109067D03*
X1889790Y112580D03*
Y109080D03*
X1886290Y112580D03*
Y109080D03*
X1889913Y216937D03*
X1839000Y187250D03*
Y183750D03*
X1842000Y187250D03*
Y183750D03*
X1845000Y187250D03*
Y183750D03*
X1889913Y210437D03*
Y213937D03*
Y220437D03*
X1853000Y463500D03*
Y460000D03*
X1856000Y463500D03*
Y460000D03*
X1846000Y506000D03*
Y502500D03*
X1867500Y472200D03*
Y475700D03*
X1846000Y499500D03*
Y496000D03*
X1849000Y499500D03*
Y496000D03*
X1881293Y519486D03*
Y522986D03*
X1878272Y519465D03*
Y522965D03*
X1858090Y508600D03*
Y512100D03*
X1854890Y508600D03*
Y512100D03*
X1880704Y572718D03*
Y576218D03*
X1877704D03*
Y572718D03*
X1868704Y576218D03*
Y572718D03*
X1871704Y576218D03*
Y572718D03*
X1874704D03*
Y576218D03*
X1925135Y111900D03*
Y115400D03*
X1921620Y111900D03*
Y115400D03*
X1917953D03*
Y111900D03*
X1940900Y153400D03*
Y149900D03*
X1908100Y155900D03*
X1925535Y136078D03*
Y132578D03*
X1916300Y156300D03*
X1901000Y131500D03*
Y128000D03*
X1947686Y190522D03*
Y187022D03*
X1943482Y166512D03*
Y163012D03*
X1947646Y178328D03*
Y181828D03*
X1947662Y171828D03*
Y175328D03*
X1932700Y206835D03*
Y203335D03*
X1958902Y159545D03*
Y163045D03*
X1943776Y173012D03*
Y169512D03*
X1947686Y197022D03*
Y193522D03*
X1905800Y187550D03*
Y191050D03*
X1908100Y159400D03*
X1916300Y159800D03*
X1934800Y457700D03*
Y454200D03*
X1904000Y441630D03*
Y445130D03*
X1949940Y491950D03*
Y488450D03*
X1946350Y491950D03*
Y488450D03*
X1953440Y491950D03*
Y488450D03*
X1912800Y508250D03*
Y504750D03*
X1909800Y508250D03*
Y504750D03*
X1943100Y491920D03*
Y488420D03*
X1934720Y520400D03*
Y523900D03*
X1954120Y510380D03*
Y513880D03*
X1923260Y482920D03*
Y486420D03*
X1950620Y510380D03*
Y513880D03*
X1908859Y481161D03*
Y477661D03*
X1952970Y501030D03*
Y504530D03*
X1949800Y545850D03*
Y542350D03*
X1946800Y545900D03*
Y542400D03*
X1899550Y586365D03*
Y582865D03*
X1899700Y591100D03*
Y594600D03*
X1969100Y551100D03*
Y554600D03*
X1969800Y574600D03*
Y578100D03*
X1965700Y578200D03*
Y574700D03*
X1966100Y551000D03*
Y554500D03*
X1963200Y594600D03*
Y598100D03*
X1970000Y598200D03*
Y594700D03*
G36*
G01X24103Y622608D02*
G02Y598654I-10303J-11977D01*
G02X3767Y598425I-10304J11976D01*
G03X2702Y598731I-1068J-1710D01*
G01X-3D01*
G02X-11901Y610631I2J11900D01*
G02X-1Y622531I11901J-1D01*
G01X2709D01*
G03X3764Y622834I-1J1990D01*
G02X24103Y622608I10035J-12202D01*
G37*
G36*
G01X701268Y4104D02*
G02Y-19850I-10303J-11977D01*
G02X680932Y-20079I-10304J11976D01*
G03X679867Y-19773I-1068J-1710D01*
G01X677162D01*
G02X665264Y-7873I2J11900D01*
G02X677164Y4027I11901J-1D01*
G01X679874D01*
G03X680929Y4330I-1J1990D01*
G02X701268Y4104I10035J-12202D01*
G37*
G36*
G01Y622608D02*
G02Y598654I-10303J-11977D01*
G02X680932Y598425I-10304J11976D01*
G03X679867Y598731I-1068J-1710D01*
G01X677162D01*
G02X665264Y610631I2J11900D01*
G02X677164Y622531I11901J-1D01*
G01X679874D01*
G03X680929Y622834I-1J1990D01*
G02X701268Y622608I10035J-12202D01*
G37*
G36*
G01X1429615Y4104D02*
G02Y-19850I-10303J-11977D01*
G02X1409279Y-20079I-10304J11976D01*
G03X1408214Y-19773I-1068J-1710D01*
G01X1405509D01*
G02X1393611Y-7873I2J11900D01*
G02X1405511Y4027I11901J-1D01*
G01X1408221D01*
G03X1409276Y4330I-1J1990D01*
G02X1429615Y4104I10035J-12202D01*
G37*
G36*
G01Y622608D02*
G02Y598654I-10303J-11977D01*
G02X1409279Y598425I-10304J11976D01*
G03X1408214Y598731I-1068J-1710D01*
G01X1405509D01*
G02X1393611Y610631I2J11900D01*
G02X1405511Y622531I11901J-1D01*
G01X1408221D01*
G03X1409276Y622834I-1J1990D01*
G02X1429615Y622608I10035J-12202D01*
G37*
G36*
G01X1878434Y4104D02*
G02Y-19850I-10303J-11977D01*
G02X1858098Y-20079I-10304J11976D01*
G03X1857033Y-19773I-1068J-1710D01*
G01X1854328D01*
G02X1842430Y-7873I2J11900D01*
G02X1854330Y4027I11901J-1D01*
G01X1857040D01*
G03X1858095Y4330I-1J1990D01*
G02X1878434Y4104I10035J-12202D01*
G37*
G36*
G01Y622608D02*
G02Y598654I-10303J-11977D01*
G02X1858098Y598425I-10304J11976D01*
G03X1857033Y598731I-1068J-1710D01*
G01X1854328D01*
G02X1842430Y610631I2J11900D01*
G02X1854330Y622531I11901J-1D01*
G01X1857040D01*
G03X1858095Y622834I-1J1990D01*
G02X1878434Y622608I10035J-12202D01*
G37*
G54D28*
X23940Y24559D03*
X20320Y53240D03*
X10440Y564000D03*
X12130Y529080D03*
X134164Y209283D03*
X134374Y241333D03*
X133850Y273300D03*
X134174Y305323D03*
Y337533D03*
X134434Y369363D03*
X783752Y209163D03*
X783782Y241283D03*
Y273533D03*
X784492Y305563D03*
X784322Y337353D03*
X783712Y369433D03*
G54D139*
X1465100Y521800D03*
Y516100D03*
X1465000Y537850D03*
Y532150D03*
X1498000Y525200D03*
Y519500D03*
X1487700Y537900D03*
Y532200D03*
X1611300Y491500D03*
Y497200D03*
X1606800Y474700D03*
Y480400D03*
G54D166*
X1667012Y-14488D03*
G54D73*
X53953Y649635D03*
X242675Y649735D03*
X430143Y649465D03*
X617691Y649196D03*
X933345Y649185D03*
X1246843Y649215D03*
G54D82*
X476672Y220096D03*
Y235696D03*
X483432Y216196D03*
X480052Y210346D03*
X483432Y212296D03*
X531871Y202547D03*
X525111D03*
X483432Y231797D03*
X480052Y225947D03*
X483432Y239596D03*
X501452Y337096D03*
X538631Y331247D03*
Y327347D03*
X535251Y340996D03*
Y337096D03*
X528491Y340996D03*
X531871Y339047D03*
Y331247D03*
X538631Y323446D03*
X525111Y319547D03*
X518352Y335147D03*
X521731Y333196D03*
Y329296D03*
X525111Y331247D03*
X528491Y333196D03*
X521731Y340996D03*
X525111Y323446D03*
X528491Y325396D03*
Y329296D03*
Y321496D03*
X531871Y323446D03*
X525111Y327347D03*
X521731Y337096D03*
X487932Y356596D03*
X491312Y342947D03*
Y354647D03*
X511592Y389747D03*
Y401447D03*
X508212Y383896D03*
X504832Y401446D03*
X535251Y348796D03*
Y344896D03*
X538631Y346847D03*
Y342947D03*
X535251Y360496D03*
X531871Y358547D03*
X535251Y364396D03*
Y368296D03*
X525111Y346847D03*
X528491Y348796D03*
X531871Y342947D03*
X528491Y344896D03*
Y352696D03*
X538631Y354647D03*
Y358547D03*
Y362447D03*
X531871D03*
Y366347D03*
X535251Y372197D03*
X538631Y350747D03*
X535251Y379996D03*
X538631Y374146D03*
X531871Y378047D03*
X514972Y376096D03*
X528491Y387796D03*
X521731D03*
Y391696D03*
X518352Y393647D03*
X514972Y395597D03*
X528491Y379996D03*
Y383896D03*
X525111Y385847D03*
X521731Y383896D03*
X525111Y389747D03*
X521731Y395597D03*
X514972Y391696D03*
Y387796D03*
X528491Y376096D03*
X531871Y381947D03*
X494692Y387796D03*
X514972Y364396D03*
X518352Y350747D03*
X504832Y374146D03*
X508212Y368296D03*
X514972Y360496D03*
X508212Y372197D03*
X511592Y354647D03*
X498072Y378047D03*
Y381947D03*
X518352Y354647D03*
X511592Y366347D03*
X494692Y379996D03*
X501452Y376096D03*
X511592Y362447D03*
X508212Y364396D03*
X514972Y368296D03*
X511592Y358547D03*
X498072Y374146D03*
X521731Y352696D03*
X494692Y383896D03*
X518352Y346847D03*
X484552Y374146D03*
X487932Y383896D03*
X491312Y393647D03*
X494692Y399496D03*
X484552Y389747D03*
X552151Y331247D03*
Y335147D03*
X548771Y333196D03*
X552151Y339047D03*
X555531Y340996D03*
X542011D03*
Y337096D03*
X545391Y327347D03*
Y339047D03*
X542011Y333196D03*
Y329296D03*
Y325396D03*
X562591Y340996D03*
X558911Y339047D03*
X562591Y337096D03*
X555531D03*
X552151Y342947D03*
X548771Y344896D03*
X552151Y346847D03*
X542011Y344896D03*
Y356596D03*
X559211Y366347D03*
X558911Y354647D03*
X552151Y362447D03*
X545391Y350747D03*
X548771Y348796D03*
X555531Y352696D03*
Y348796D03*
X552151Y354647D03*
X558911Y350747D03*
X555531Y344896D03*
X548771Y387796D03*
X552151Y385847D03*
X555531Y379996D03*
X552151Y381947D03*
X937747Y322209D03*
X930987D03*
X947887Y324160D03*
X941127D03*
G54D37*
X17300Y455330D03*
X1839390Y64536D03*
G54D239*
G01X11811Y132717D02*
Y132718D01*
X7755Y136774D01*
X-18592D01*
X-19624Y137806D01*
Y158386D01*
X-19199Y158811D01*
X4311D01*
X4500Y159000D01*
X30272D01*
X32325Y156947D01*
X42347D01*
X44900Y159500D01*
X51500D01*
G01X-10236Y132717D02*
Y132718D01*
X-13003Y135485D01*
X-19269D01*
X-21073Y137289D01*
Y163476D01*
X-20289Y164260D01*
X-18106D01*
X-15768Y161922D01*
G01X-19210Y162529D02*
X-16728Y160047D01*
X4905D01*
X5128Y159824D01*
X31578D01*
X33155Y158247D01*
X41407D01*
X46160Y163000D01*
X51500D01*
G01X-15768Y161922D02*
X-15102Y161256D01*
X-10079D01*
X-8634Y162701D01*
X4299D01*
X6352Y160648D01*
X40148D01*
X46000Y166500D01*
X62400D01*
G01X-17302Y506798D02*
X-16804Y506300D01*
X-13400D01*
G01X-16700Y497400D02*
X-16601D01*
X-13400Y500601D01*
Y502800D01*
G01X-19802Y476738D02*
Y478878D01*
X-16940Y481740D01*
X-12690D01*
G01X-19783Y481286D02*
X-16841Y484228D01*
X-11678D01*
X-9190Y481740D01*
G01X-12210Y521200D02*
X-12454Y521444D01*
X-14046D01*
X-16186Y519304D01*
G01X-17392Y478512D02*
X-17357Y478477D01*
X-12927D01*
X-12690Y478240D01*
G01X43960Y20572D02*
Y19333D01*
X44542Y18751D01*
Y16578D01*
G01X40530Y20220D02*
Y19172D01*
X41542Y18160D01*
Y16578D01*
G01X38400Y164100D02*
X43600Y169300D01*
X57700D01*
G01X-12861Y163165D02*
X-10714Y165312D01*
X-10022D01*
X-9597Y165737D01*
Y167051D01*
X-9172Y167476D01*
X-8097D01*
X-7672Y167051D01*
Y165737D01*
X-7247Y165312D01*
X-6172D01*
X-5747Y165737D01*
Y167051D01*
X-5322Y167476D01*
X-4247D01*
X-3822Y167051D01*
Y165737D01*
X-3397Y165312D01*
X-2322D01*
X-1897Y165737D01*
Y167051D01*
X-1472Y167476D01*
X-397D01*
X28Y167051D01*
Y165737D01*
X453Y165312D01*
X1528D01*
X1953Y165737D01*
Y167051D01*
X2378Y167476D01*
X3453D01*
X3878Y167051D01*
Y165737D01*
X6115Y163500D01*
X34300D01*
X34900Y164100D01*
G01X41508Y402597D02*
X46100Y407189D01*
Y413520D01*
G01X41508Y402597D02*
X31000Y392089D01*
Y386700D01*
X29400Y385100D01*
X27344D01*
X23228Y380984D01*
G01X5100Y478330D02*
X523Y473753D01*
Y461433D01*
X-3010Y457900D01*
X-13265D01*
X-13690Y458325D01*
Y460640D01*
G01X2160Y479000D02*
Y476838D01*
X-644Y474034D01*
Y463618D01*
X-1458Y462804D01*
G01X-8690Y460640D02*
Y459505D01*
X-8265Y459080D01*
X-4850D01*
X-1458Y462472D01*
Y462804D01*
G01X2450Y460000D02*
Y469550D01*
X2350Y469650D01*
G01X43942Y487879D02*
X47521D01*
X47800Y487600D01*
G01X-6676Y501800D02*
Y499695D01*
X-5602Y498621D01*
G01X-10669Y516148D02*
X-10252Y515731D01*
X-6712D01*
G01X31477Y482788D02*
Y482659D01*
X30850Y482032D01*
X28700D01*
G01X-2083Y513704D02*
X-1706D01*
X-500Y514910D01*
Y517500D01*
G01X-3500D02*
Y515121D01*
X-2083Y513704D01*
G01X-3500Y521000D02*
X-12010D01*
X-12210Y521200D01*
G01X-12690Y478240D02*
Y475040D01*
X-11490Y473840D01*
G01D02*
X-8690D01*
G01X-1000Y479000D02*
X-2928Y477072D01*
Y475510D01*
X-4598Y473840D01*
X-5690D01*
G01X-9190Y478240D02*
X-6530D01*
X-5690Y477400D01*
Y473840D01*
G01X43942Y495721D02*
Y492332D01*
X43310Y491700D01*
X37100D01*
X36458Y491058D01*
Y487879D01*
G01X43942Y495721D02*
X48021D01*
X48550Y496250D01*
X51200D01*
G01X28246Y491557D02*
X31924Y487879D01*
X36458D01*
G01X93500Y-18000D02*
X86697Y-11197D01*
Y-9875D01*
X86762Y-9810D01*
Y82356D01*
X79781Y89337D01*
X76106D01*
G01X88777Y-10586D02*
X87700Y-9509D01*
Y92900D01*
X86600Y94000D01*
G01X51090Y8080D02*
X51819Y8809D01*
X53786D01*
X55887Y6708D01*
Y-1156D01*
X58919Y-4188D01*
Y-9488D01*
X58316Y-10091D01*
Y-11754D01*
G01D02*
Y-12204D01*
X58308Y-12212D01*
Y-14773D01*
G01X54816Y-11754D02*
Y-8560D01*
X54307Y-8051D01*
G01X76899Y157895D02*
X81181D01*
X86702Y152374D01*
X87200D01*
G01X110470Y308170D02*
Y304990D01*
X109040Y303560D01*
Y289840D01*
X104700Y285500D01*
Y211006D01*
X111958Y203748D01*
Y188146D01*
X89283Y165471D01*
Y156217D01*
X95700Y149800D01*
Y142330D01*
X83400Y130030D01*
Y119800D01*
X79600Y116000D01*
Y112500D01*
X74763Y107663D01*
X70555D01*
X69725Y106833D01*
Y101155D01*
X70980Y99900D01*
Y97166D01*
G01X79670Y135828D02*
Y132300D01*
G01X81600Y124700D02*
Y130370D01*
X79670Y132300D01*
G01X102400Y118500D02*
Y113200D01*
X98636Y109436D01*
X92000D01*
X87564Y105000D01*
G01X102400Y118500D02*
X105700D01*
G01X89980Y145531D02*
X80663Y154848D01*
X62744D01*
X60723Y156869D01*
G01X95777Y129396D02*
Y138141D01*
X99980Y142344D01*
Y145531D01*
G01X91306Y157194D02*
X94750Y153750D01*
X100250D01*
X105300Y148700D01*
Y128250D01*
X104550Y127500D01*
Y126600D01*
X101900Y123950D01*
X97988D01*
X97214Y124724D01*
G01X94000Y118500D02*
Y120430D01*
X97214Y123644D01*
Y124724D01*
G01X94000Y118500D02*
X89313D01*
X87013Y116200D01*
X85350D01*
G01X76899Y157895D02*
X63654D01*
X58549Y163000D01*
X55000D01*
G01X69500Y166500D02*
X76300D01*
G01D02*
X80310D01*
X89685Y175875D01*
Y182338D01*
X87151Y184872D01*
G01X86952Y181721D02*
Y176452D01*
X79800Y169300D01*
X57700D01*
G01X60723Y156869D02*
X58092Y159500D01*
X55000D01*
G01X62400Y166500D02*
X66000D01*
G01X69125Y310625D02*
Y307375D01*
X69300Y307200D01*
Y306000D01*
G01X76600Y342000D02*
X74800Y340200D01*
Y338850D01*
G01X69000Y341800D02*
Y338800D01*
G01X72000Y341800D02*
Y338800D01*
G01X89000Y306000D02*
X84600D01*
X84300Y305700D01*
G01X80100Y307300D02*
X80900D01*
X84300Y310700D01*
G01X110470Y308170D02*
Y308330D01*
X102400Y316400D01*
Y317500D01*
G01X57000Y341500D02*
X56300Y340800D01*
Y338500D01*
G01X105800Y338200D02*
Y333599D01*
X105001Y332800D01*
X103900D01*
G01X105800Y338200D02*
Y342100D01*
X104430Y343470D01*
X103010D01*
G01X103900Y332800D02*
X102890D01*
X100550Y335140D01*
G01X102400Y313000D02*
Y309600D01*
X103500Y308500D01*
G01D02*
X105100D01*
X106600Y307000D01*
G01X94900Y332800D02*
Y331127D01*
X94395Y330622D01*
X90410D01*
X88532Y332500D01*
X86750D01*
G01X92000Y338200D02*
X88400D01*
X87400Y337200D01*
G01X94900Y332800D02*
X91541D01*
X90570Y333771D01*
Y336770D01*
X92000Y338200D01*
G01X103200Y330190D02*
X104710D01*
X107300Y327600D01*
G01X77600Y320800D02*
X76300Y319500D01*
X67500D01*
G01X85500Y341000D02*
X83437Y343063D01*
X81544D01*
X74631Y336150D01*
X68418D01*
G01D02*
X66250D01*
X65550Y336850D01*
X62250D01*
X61200Y337900D01*
Y339100D01*
X61100Y339200D01*
Y343150D01*
G01X68418Y332500D02*
Y336150D01*
G01X85500Y341000D02*
X87810D01*
X90280Y343470D01*
X94010D01*
G01X70900Y317400D02*
X65600D01*
X64000Y319000D01*
Y319500D01*
G01X63300Y325500D02*
Y322230D01*
X64000Y321530D01*
Y319500D01*
G01X53250Y302800D02*
Y302650D01*
X48700Y298100D01*
X46900D01*
G01X57000Y345000D02*
Y345800D01*
X59500Y348300D01*
X60900D01*
G01X49100Y354500D02*
X50900Y352700D01*
X53000D01*
X54500Y351200D01*
Y351000D01*
G01X67130Y369550D02*
Y369306D01*
X69250Y367186D01*
Y364500D01*
G01D02*
X72250D01*
X73500Y363250D01*
X76500D01*
G01X80250Y354750D02*
Y357550D01*
X80000Y357800D01*
Y363000D01*
X84900Y367900D01*
Y375400D01*
X82800Y377500D01*
Y382425D01*
X85609Y385234D01*
G01X79330Y531361D02*
X82566D01*
X91650Y522277D01*
Y522000D01*
G01X79346Y528307D02*
X82907D01*
X88855Y522359D01*
G01X111961Y499877D02*
X105464D01*
X99888Y505453D01*
X89435D01*
X85554Y509334D01*
Y520410D01*
X80524Y525440D01*
X74933D01*
X73567Y526806D01*
Y530533D01*
X74395Y531361D01*
X75830D01*
G01X112427Y497225D02*
X113624Y498422D01*
Y500566D01*
X112650Y501540D01*
X106037D01*
X101007Y506570D01*
X101006D01*
X100916Y506660D01*
X89935D01*
X86761Y509834D01*
Y520910D01*
X81082Y526589D01*
X76579D01*
X75846Y527322D01*
Y528307D01*
G01X148901Y-50423D02*
X441680D01*
G02Y-53848I0J-1712D01*
G01X142098D01*
X140500Y-52250D01*
G01X154841Y424439D02*
X170317D01*
X171188Y423568D01*
X203433D01*
X226039Y400962D01*
G01X148409Y422239D02*
Y423739D01*
X149109Y424439D01*
X151341D01*
G01X154754Y417659D02*
X155910D01*
X158061Y419810D01*
X200689D01*
X249499Y371000D01*
X260000D01*
G01X151254Y417659D02*
Y417554D01*
X148300Y414600D01*
G01X164830Y422339D02*
X165489Y421680D01*
X201820D01*
X248600Y374900D01*
X275085D01*
X277208Y372777D01*
X278461D01*
X279936Y371302D01*
X282822D01*
X284086Y372566D01*
X285432D01*
X286696Y371302D01*
X289582D01*
X290846Y372566D01*
X292192D01*
X293456Y371302D01*
X296342D01*
X297606Y372566D01*
X298952D01*
X300216Y371302D01*
X303102D01*
X304366Y372566D01*
X305712D01*
X306981Y371297D01*
X309180D01*
X311130Y369347D01*
X311981D01*
X314607Y366721D01*
X315846D01*
X317425Y365142D01*
X319541D01*
X321862Y362821D01*
X322606D01*
X323874Y361553D01*
X326083D01*
X327750Y363220D01*
X329659D01*
X331326Y361553D01*
X332751D01*
X334014Y362816D01*
X336131D01*
X337749Y361198D01*
X339698D01*
X341316Y362816D01*
X342969D01*
X344686Y361099D01*
X346519D01*
X348236Y362816D01*
X349794D01*
X351457Y361153D01*
X353389D01*
X355052Y362816D01*
X356410D01*
X358109Y361117D01*
X360020D01*
X361719Y362816D01*
X362758D01*
X365064Y365122D01*
X366667D01*
X368789Y363000D01*
X369885D01*
X371714Y361171D01*
X373596D01*
X375241Y362816D01*
X376859D01*
X378674Y361001D01*
X380128D01*
X381943Y362816D01*
X383468D01*
X385309Y360975D01*
X387324D01*
X388799Y359500D01*
X390228D01*
X392075Y357653D01*
X393676D01*
X395318Y359295D01*
X397218D01*
X398860Y357653D01*
X400553D01*
X402300Y359400D01*
X405287D01*
X411547Y365660D01*
G01X154861Y420954D02*
X156313D01*
X157858Y422499D01*
X164670D01*
X164830Y422339D01*
G01X151361Y420954D02*
X149553D01*
X148666Y420067D01*
Y417397D01*
G01X119016Y414201D02*
X117821D01*
X115750Y412130D01*
G01X226039Y400962D02*
X248301Y378700D01*
X275779D01*
X277331Y377148D01*
X278767D01*
X280713Y375202D01*
X282307D01*
X284071Y376966D01*
X285447D01*
X287211Y375202D01*
X288812D01*
X290453Y376843D01*
X292554D01*
X294195Y375202D01*
X295827D01*
X297591Y376966D01*
X298967D01*
X300731Y375202D01*
X302516D01*
X304404Y377090D01*
X305780D01*
X307673Y375197D01*
X309181D01*
X311130Y373248D01*
X312559D01*
X314510Y371297D01*
X315652D01*
X315977Y370972D01*
X315991D01*
X317140Y369823D01*
Y369809D01*
X317597Y369352D01*
X318738D01*
X321100Y366990D01*
X322760D01*
X324450Y365300D01*
X326100D01*
X327848Y367048D01*
X329511D01*
X331209Y365350D01*
X333140D01*
X334838Y367048D01*
X336271D01*
X338069Y365250D01*
X339570D01*
X341120Y366800D01*
X343020D01*
X344570Y365250D01*
X346510D01*
X348280Y367020D01*
X349640D01*
X351490Y365170D01*
X353240D01*
X355070Y367000D01*
X356540D01*
X358180Y365360D01*
X360270D01*
X361890Y366980D01*
X363260D01*
X365370Y369090D01*
X366450D01*
X368490Y367050D01*
X369650D01*
X371290Y365410D01*
X373690D01*
X375170Y366890D01*
X377050D01*
X378700Y365240D01*
X380160D01*
X381810Y366890D01*
X383690D01*
X385280Y365300D01*
X386830D01*
X389240Y362890D01*
X390260D01*
X392120Y361030D01*
X393760D01*
X395870Y363140D01*
X396790D01*
X398890Y361040D01*
X400440D01*
X402630Y363230D01*
X403910D01*
X407728Y367048D01*
X410335D01*
X411547Y368260D01*
G01X260000Y371000D02*
X275206D01*
X276859Y369347D01*
X278198D01*
X280659Y366886D01*
X282297D01*
X284083Y368672D01*
X285611D01*
X287308Y366975D01*
X288916D01*
X290613Y368672D01*
X292957D01*
X294231Y367398D01*
X295617D01*
X297278Y369059D01*
X299330D01*
X300991Y367398D01*
X303097D01*
X304371Y368672D01*
X306349D01*
X308300Y366721D01*
X309857D01*
X311130Y365448D01*
X312559D01*
X314510Y363497D01*
X315170D01*
X317667Y361000D01*
X319300D01*
X320824Y359476D01*
X322822D01*
X324650Y357648D01*
X326145D01*
X327599Y359102D01*
X329956D01*
X331410Y357648D01*
X332985D01*
X334699Y359362D01*
X336456D01*
X338170Y357648D01*
X339781D01*
X341459Y359326D01*
X343252D01*
X344930Y357648D01*
X346514D01*
X348155Y359289D01*
X350048D01*
X351689Y357648D01*
X353178D01*
X354808Y359278D01*
X356819D01*
X358449Y357648D01*
X359989D01*
X361943Y359602D01*
X363163D01*
X364431Y360870D01*
X367131D01*
X368501Y359500D01*
X370117D01*
X371969Y357648D01*
X373313D01*
X375025Y359360D01*
X376946D01*
X378658Y357648D01*
X380295D01*
X382109Y359462D01*
X383479D01*
X385441Y357500D01*
X386460D01*
X388715Y355245D01*
X390142D01*
X391754Y353633D01*
X393733D01*
X395400Y355300D01*
X396900D01*
X398567Y353633D01*
X400733D01*
X402600Y355500D01*
X403787D01*
X411447Y363160D01*
G01X315178Y349509D02*
X310922D01*
X309091Y351340D01*
X308160D01*
X306428Y353072D01*
X304371D01*
X303096Y351797D01*
X300991D01*
X299716Y353072D01*
X297611D01*
X296823Y352300D01*
X296320Y351797D01*
X294231D01*
X292956Y353072D01*
X290851D01*
X289549Y351797D01*
X286702D01*
X285427Y353072D01*
X284091D01*
X283507Y352500D01*
X282804Y351797D01*
X280711D01*
X279436Y353072D01*
X277331D01*
X276645Y352400D01*
X276042Y351797D01*
X273951D01*
X272676Y353072D01*
X270571D01*
X269578Y352100D01*
X269275Y351797D01*
X266194D01*
X264868Y353123D01*
X260900D01*
G01D02*
X257177D01*
X256000Y354300D01*
X252700D01*
G01X251700Y366800D02*
X260000D01*
X262400Y364400D01*
X267400D01*
G01D02*
X269300D01*
X270203Y363497D01*
X276056D01*
X277331Y364772D01*
X279436D01*
X280711Y363497D01*
X282816D01*
X284091Y364772D01*
X286196D01*
X287471Y363497D01*
X289576D01*
X290851Y364772D01*
X292956D01*
X294231Y363497D01*
X296336D01*
X297611Y364772D01*
X298947D01*
X300222Y363497D01*
X303096D01*
X304371Y364772D01*
X305707D01*
X306982Y363497D01*
X308499D01*
X311124Y360872D01*
X312466D01*
X313566Y359772D01*
Y355021D01*
X315178Y353409D01*
G01X252700Y362800D02*
X260600D01*
X262200Y361200D01*
G01D02*
X264600Y358800D01*
X270406D01*
X271203Y359597D01*
X276040D01*
X276536Y360093D01*
X277331Y360872D01*
X278667D01*
X280534Y359005D01*
X282183D01*
X284091Y360872D01*
X285427D01*
X286702Y359597D01*
X289549D01*
X290851Y360872D01*
X292187D01*
X293929Y359130D01*
X295869D01*
X297611Y360872D01*
X298947D01*
X300672Y359147D01*
X302646D01*
X304371Y360872D01*
X305707D01*
X307658Y358921D01*
X309086D01*
X311798Y356209D01*
Y355360D01*
G01Y347560D02*
X307319D01*
X305712Y349167D01*
X303597D01*
X302332Y347902D01*
X300986D01*
X299227Y349661D01*
X297331D01*
X295572Y347902D01*
X293465D01*
X292567Y348800D01*
X292192Y349167D01*
X290077D01*
X288812Y347902D01*
X287466D01*
X285787Y349581D01*
X283731D01*
X282052Y347902D01*
X279945D01*
X279047Y348800D01*
X278672Y349167D01*
X277326D01*
X276061Y347902D01*
X273744D01*
X271909Y349737D01*
X270533D01*
X268698Y347902D01*
X266929D01*
X265232Y349599D01*
X262301D01*
X262100Y349800D01*
X256300D01*
G01D02*
X252700D01*
G01X311798Y351460D02*
X310030Y353228D01*
Y354077D01*
X309086Y355021D01*
X308294D01*
X305978Y357337D01*
X303967D01*
X302261Y355631D01*
X300914D01*
X299215Y357324D01*
X297252D01*
X295625Y355697D01*
X293470D01*
X292195Y356972D01*
X290082D01*
X288807Y355697D01*
X287216D01*
X285447Y357466D01*
X284071D01*
X282302Y355697D01*
X280597D01*
X278899Y357395D01*
X277169D01*
X275462Y355697D01*
X273303D01*
X271977Y357023D01*
X261323D01*
X259546Y358800D01*
X256300D01*
G01D02*
X252700D01*
G01X307675Y22133D02*
Y17057D01*
G01X317714Y4023D02*
Y9114D01*
G01X307675Y97733D02*
Y92657D01*
G01Y59933D02*
Y54857D01*
G01X317714Y79623D02*
Y84714D01*
G01Y41823D02*
Y46914D01*
G01X382777Y353409D02*
Y352035D01*
X380163Y349421D01*
X378459D01*
X376595Y351285D01*
X375483D01*
X373566Y349368D01*
X371927D01*
X370141Y351154D01*
X368539D01*
X367839Y351854D01*
Y352273D01*
X366690Y353422D01*
X365064D01*
X363915Y352273D01*
Y351863D01*
X363215Y351163D01*
X361759D01*
X360016Y349420D01*
X358278D01*
X356469Y351229D01*
X354929D01*
X353182Y349482D01*
X351518D01*
X349811Y351189D01*
X348233D01*
X346473Y349429D01*
X344671D01*
X342871Y351229D01*
X341529D01*
X340055Y349755D01*
X338097D01*
X336703Y351149D01*
X334649D01*
X332921Y349421D01*
X331079D01*
X329301Y351199D01*
X327907D01*
X326108Y349400D01*
X324544D01*
X322644Y347500D01*
X321252D01*
X320000Y346248D01*
Y343402D01*
X318107Y341509D01*
X315563D01*
G01Y345009D02*
Y345668D01*
X318495Y348600D01*
G01D02*
X321345Y351450D01*
X322422D01*
X324591Y353619D01*
X326119D01*
X327718Y355218D01*
X329482D01*
X331098Y353602D01*
X333302D01*
X334887Y355187D01*
X336313D01*
X337949Y353551D01*
X339753D01*
X341369Y355167D01*
X343023D01*
X344504Y353686D01*
X346535D01*
X347895Y355046D01*
X350010D01*
X351525Y353531D01*
X353362D01*
X355056Y355225D01*
X356378D01*
X357900Y353703D01*
X360036D01*
X361467Y355134D01*
X363570D01*
X364270Y355834D01*
Y356026D01*
X365211Y356967D01*
X366543D01*
X367484Y356026D01*
Y355846D01*
X368184Y355146D01*
X370075D01*
X371599Y353622D01*
X373864D01*
X375386Y355144D01*
X376708D01*
X378220Y353632D01*
X380271D01*
X381856Y355217D01*
X386014D01*
X386157Y355360D01*
G01X307675Y523134D02*
Y518057D01*
G01X317714Y505024D02*
Y510114D01*
G01X307675Y560934D02*
Y555857D01*
G01X317714Y547914D02*
Y542824D01*
G01Y585714D02*
Y580624D01*
G01X307675Y598734D02*
Y593657D01*
G01X421454Y-1817D02*
X420100Y-3171D01*
Y-5392D01*
X418892Y-6600D01*
X417192D01*
X415792Y-5200D01*
X413992D01*
X412592Y-6600D01*
X410792D01*
X409192Y-5000D01*
X407192D01*
X405492Y-6700D01*
X404092D01*
X402392Y-5000D01*
X400492D01*
X399192Y-6300D01*
X396392D01*
X392592Y-2500D01*
Y40300D01*
X390842Y42050D01*
Y44350D01*
X392500Y46008D01*
Y52708D01*
X394492Y54700D01*
G01X411415Y4023D02*
Y9121D01*
X411416Y9122D01*
G01X394683Y22133D02*
Y17158D01*
X394682Y17157D01*
G01X421455Y46921D02*
X421456Y46922D01*
X419678Y48700D01*
X397000D01*
X396443Y49257D01*
Y53543D01*
X395286Y54700D01*
X394492D01*
G01X411415Y79623D02*
Y84714D01*
G01Y41823D02*
Y46921D01*
X411416Y46922D01*
G01X394683Y97733D02*
X394682Y97732D01*
Y92482D01*
X392592Y90392D01*
Y76078D01*
X394682Y73988D01*
Y68492D01*
G01X411086Y390460D02*
X414060D01*
X415500Y391900D01*
G01X421455Y505024D02*
Y510950D01*
X419630Y512775D01*
Y512792D01*
X417500D01*
X415792Y514500D01*
X413992D01*
X412392Y512900D01*
X411092D01*
X409192Y514800D01*
X406992D01*
X405292Y513100D01*
X403892D01*
X402392Y514600D01*
X400292D01*
X399092Y513400D01*
X397192D01*
X392492Y518100D01*
Y528950D01*
X392800Y529258D01*
Y536692D01*
X392492Y537000D01*
Y548492D01*
X392500Y548500D01*
Y551924D01*
X392800Y552224D01*
G01X411415Y505024D02*
Y510114D01*
G01X394683Y523134D02*
Y528930D01*
X394587Y529026D01*
G01X392800Y552224D02*
X393176Y552600D01*
X395900D01*
X396500Y552000D01*
Y550400D01*
X397200Y549700D01*
X420330D01*
X421455Y548575D01*
Y547921D01*
G01X394091Y591701D02*
X395500D01*
X396400Y590801D01*
Y588000D01*
X397000Y587400D01*
X419778D01*
X421456Y585722D01*
G01X392800Y552224D02*
Y555992D01*
X392492Y556300D01*
Y565750D01*
X392750Y566008D01*
Y575892D01*
X392492Y576150D01*
Y584550D01*
X392500Y584558D01*
Y590110D01*
X394091Y591701D01*
G01X411415Y547921D02*
Y542824D01*
G01Y580624D02*
Y585721D01*
X411416Y585722D01*
G01X394682Y569492D02*
Y560934D01*
X394683D01*
G01X394091Y591701D02*
X392892Y592900D01*
Y608500D01*
X393592Y609200D01*
X394692D01*
X397292Y611800D01*
X399800D01*
X400650Y610950D01*
X402142D01*
X402788Y611596D01*
X406396D01*
X407392Y610600D01*
X409092D01*
X410392Y611900D01*
X412292D01*
X414892Y609300D01*
X415592D01*
X417192Y607700D01*
X418892D01*
X421454Y610262D01*
Y612560D01*
G01X394682Y607292D02*
Y598734D01*
X394683D01*
G01X421454Y-1817D02*
X422600Y-2963D01*
Y-5200D01*
X424400Y-7000D01*
X425400D01*
X427200Y-5200D01*
X429200D01*
X430500Y-6500D01*
X432700D01*
X434200Y-5000D01*
X435300D01*
X437600Y-2700D01*
X439500D01*
X443100Y-6300D01*
X445700D01*
X447000Y-5000D01*
X448700D01*
X449650Y-5950D01*
X461850D01*
X462920Y-7020D01*
Y-12120D01*
X470733Y-19933D01*
X656088D01*
X656807Y-20652D01*
G01X421455Y4023D02*
Y9121D01*
G01Y22133D02*
Y17058D01*
X421456Y17057D01*
G01X421455Y41823D02*
Y46921D01*
G01Y79623D02*
Y73758D01*
X421456Y73757D01*
G01X438187Y41823D02*
Y46920D01*
X438189Y46922D01*
G01X421455Y59933D02*
Y54858D01*
X421456Y54857D01*
G01X458400Y276400D02*
X458100D01*
X456000Y278500D01*
G01X444752Y264188D02*
Y264520D01*
X441165Y268107D01*
X440592D01*
X438934Y269765D01*
Y270091D01*
G01X463671Y319386D02*
X462254Y320803D01*
X461000D01*
G01X461500Y298000D02*
X463359D01*
X469018Y292341D01*
X472648D01*
X472692Y292385D01*
G01D02*
X474276Y293969D01*
X478941D01*
X480434Y292476D01*
X481968D01*
X483735Y294243D01*
X484827D01*
X486836Y292234D01*
X488745D01*
X490672Y294161D01*
X492095D01*
X493670Y292586D01*
X495014D01*
X497468Y290132D01*
X498892D01*
X500486Y288538D01*
X502566D01*
X504049Y290021D01*
X505767D01*
X507197Y288591D01*
X508863D01*
X511179Y286275D01*
X512622D01*
X514520Y284377D01*
X515448D01*
X517488Y282337D01*
X519024D01*
X521012Y280349D01*
X522529D01*
X525111Y277767D01*
Y276646D01*
G01X518352D02*
X514298D01*
X512629Y278315D01*
X510819D01*
X508634Y280500D01*
X507400D01*
X505100Y282800D01*
X503500D01*
X502047Y284253D01*
X500595D01*
X498348Y286500D01*
X497200D01*
X495300Y288400D01*
X494148D01*
X492129Y290419D01*
X490541D01*
X488620Y288498D01*
X486802D01*
X485200Y290100D01*
X483700D01*
X482000Y288400D01*
X480500D01*
X478828Y290072D01*
X476572D01*
X475000Y288500D01*
X468757D01*
X467612Y289645D01*
X466055D01*
X461500Y294200D01*
Y295000D01*
G01X474057Y299057D02*
X477100Y302100D01*
X478607D01*
X479399Y302892D01*
Y316313D01*
X479087Y316625D01*
Y318569D01*
X479399Y318881D01*
Y320213D01*
X479087Y320525D01*
Y322468D01*
X479399Y322780D01*
Y324112D01*
X479087Y324424D01*
Y326369D01*
X479399Y326681D01*
Y328279D01*
X478537Y329141D01*
X477160D01*
X475101Y331200D01*
X473871D01*
X472619Y332452D01*
Y337363D01*
X473185Y338730D01*
Y339343D01*
X472811Y340247D01*
X471033Y342025D01*
Y342947D01*
G01X461500Y301000D02*
X461864D01*
X465435Y297429D01*
X467970D01*
X469299Y296100D01*
X471100D01*
X474057Y299057D01*
G01X421456Y547922D02*
X421455Y547921D01*
G01D02*
Y542824D01*
G01X421456Y585722D02*
X421455Y585721D01*
Y580624D01*
G01Y560934D02*
Y555858D01*
X421456Y555857D01*
G01X438187Y580624D02*
Y585720D01*
X438189Y585722D01*
G01X421455Y598734D02*
Y593658D01*
X421456Y593657D01*
G01X501452Y270796D02*
X501675Y270573D01*
X506067D01*
X507772Y268868D01*
X508990D01*
X510937Y266921D01*
Y266447D01*
G01X498072Y264947D02*
X498236Y265111D01*
X502333D01*
X504104Y263340D01*
X505722D01*
X506878Y264496D01*
X507400D01*
G01X512430Y258547D02*
Y257319D01*
X513266Y256483D01*
Y247121D01*
X511592Y245447D01*
G01X518352Y241547D02*
X518170Y241365D01*
X514225D01*
X512222Y243368D01*
X511123D01*
X509922Y244569D01*
Y246392D01*
X510074Y246544D01*
Y247973D01*
X509786Y248261D01*
Y250268D01*
X509953Y250435D01*
Y254000D01*
X510972Y255019D01*
Y255647D01*
G01X514220Y266791D02*
Y267967D01*
X515100Y268847D01*
X518352D01*
G01X510937Y262947D02*
Y261047D01*
X510401Y260511D01*
G01X514220Y263291D02*
Y261244D01*
X513857Y260881D01*
G01X607339Y458540D02*
X605640D01*
X595070Y447970D01*
G01X605510Y22133D02*
Y16999D01*
G01X647400Y-6900D02*
X659128D01*
X659755Y-7527D01*
Y-8699D01*
G01X656255D02*
X655300Y-9654D01*
Y-12800D01*
X656500Y-14000D01*
G01X656255Y-8699D02*
Y-9623D01*
X658764Y-12132D01*
X659747D01*
G01X605510Y4023D02*
Y9157D01*
G01X649600Y-9000D02*
X647500D01*
X647000Y-9500D01*
G01X653150Y-14000D02*
Y-12750D01*
X653850Y-12050D01*
Y-9750D01*
X653100Y-9000D01*
G01X647000Y-12100D02*
X650400D01*
X653100Y-9400D01*
Y-9000D01*
G01X615549Y22133D02*
Y16999D01*
G01X661800Y25500D02*
X659700Y23400D01*
Y22900D01*
G01X667000Y28400D02*
X664100Y25500D01*
X661800D01*
G01X656406Y92766D02*
X653833D01*
X652718Y93881D01*
G01X660600Y84800D02*
X657900D01*
X656405Y86295D01*
Y89566D01*
G01D02*
X656406Y89567D01*
Y92766D01*
G01X605510Y92599D02*
Y97733D01*
G01Y59933D02*
Y54799D01*
G01Y41823D02*
Y46957D01*
G01Y79623D02*
Y84757D01*
G01X659905Y89566D02*
X662352D01*
G01X615549Y92599D02*
Y97733D01*
G01Y59933D02*
Y54799D01*
G01X653000Y256500D02*
X654950Y254550D01*
Y253446D01*
G01X649500Y261300D02*
Y260000D01*
X653000Y256500D01*
G01X638500Y270500D02*
X636925D01*
X636000Y269575D01*
Y263500D01*
X623893Y251393D01*
X618279D01*
G01X646000Y272000D02*
Y272368D01*
X643500Y274868D01*
G01X646000Y268500D02*
X644840Y269660D01*
X642855D01*
G01X651235Y249165D02*
X652260Y250190D01*
Y253440D01*
X652153Y253547D01*
Y253575D01*
X646000Y259728D01*
Y261500D01*
G01X682204Y270276D02*
X679588D01*
X677816Y272048D01*
X666687D01*
X664415Y274320D01*
Y276455D01*
X662786Y278084D01*
G01X638500Y280500D02*
X635857D01*
X628525Y287832D01*
G01X639622Y286894D02*
Y290210D01*
G01X643823Y286894D02*
Y289650D01*
G01X658617Y291871D02*
Y294069D01*
X658853Y294305D01*
G01X657950Y296850D02*
X655500Y294400D01*
Y293500D01*
G01X661767Y293474D02*
Y295675D01*
X662238Y296146D01*
G01X673240Y274190D02*
X671749D01*
X670736Y273177D01*
X667031D01*
X665688Y274520D01*
Y278489D01*
X664321Y279856D01*
X660901D01*
G01X612307Y470019D02*
Y463508D01*
X607339Y458540D01*
G01X614870Y492153D02*
Y491653D01*
X616195Y490328D01*
Y486785D01*
X617930Y485050D01*
X618430D01*
G01X614430D02*
X616170Y483310D01*
X617738D01*
X618430Y484002D01*
Y485050D01*
G01X614430D02*
X613050D01*
X612000Y484000D01*
G01X614930Y481550D02*
X618430D01*
G01X609284Y480055D02*
X610779Y481550D01*
X614930D01*
G01X605510Y523134D02*
Y517999D01*
G01X636930Y488050D02*
Y489701D01*
X635880Y490751D01*
Y493304D01*
X636500Y493924D01*
G01X641500Y487400D02*
X638650Y484550D01*
X636930D01*
G01D02*
X632930D01*
G01X628700Y482000D02*
X631250Y484550D01*
X632930D01*
G01X631600Y477600D02*
X627700D01*
X627000Y478300D01*
G01X605510Y505024D02*
Y510157D01*
G01X625569Y481568D02*
X626800Y480337D01*
X629389D01*
X630152Y481100D01*
X631600D01*
G01X636600Y480900D02*
X636400Y481100D01*
X631600D01*
G01X624700Y484100D02*
Y482437D01*
X625569Y481568D01*
G01X609470Y484060D02*
Y486294D01*
X611726Y488550D01*
X614430D01*
G01X613700Y474560D02*
X614105D01*
X614930Y475385D01*
Y478050D01*
G01X613700Y474560D02*
X611840D01*
X611250Y475150D01*
Y476750D01*
G01X615549Y523134D02*
Y517999D01*
G01X658900Y509300D02*
X660700Y507500D01*
X663000D01*
G01X662000Y488500D02*
X659279D01*
X659070Y488709D01*
G01X655100Y614100D02*
Y614000D01*
X651100Y610000D01*
Y586900D01*
X647700Y583500D01*
Y573700D01*
X649900Y571500D01*
X662200D01*
X664100Y569600D01*
X673637D01*
X676900Y566337D01*
Y554699D01*
X665787Y543586D01*
Y529513D01*
X668000Y527300D01*
Y521929D01*
X669900Y520029D01*
Y516283D01*
X673316Y512867D01*
X675841D01*
X678193Y510515D01*
Y507827D01*
X682050Y503970D01*
G01X605510Y560934D02*
Y555799D01*
G01Y542824D02*
Y547957D01*
G01Y580624D02*
Y585757D01*
G01X615549Y560934D02*
Y555799D01*
G01X658600Y590900D02*
Y587320D01*
X660320Y585600D01*
G01X605510Y598734D02*
Y593599D01*
G01X615549Y598734D02*
Y593599D01*
G01X662000Y589000D02*
X660100Y590900D01*
X658600D01*
G01X708330Y-17806D02*
Y-16726D01*
X707487Y-15883D01*
Y14513D01*
X706000Y16000D01*
Y22022D01*
X709975Y25997D01*
Y27831D01*
X712169Y30025D01*
X728175D01*
X735717Y22483D01*
X752919D01*
X753675Y23239D01*
G01X710107Y-19839D02*
X710673Y-19273D01*
Y-17775D01*
X709255Y-16357D01*
Y-16342D01*
X708412Y-15499D01*
Y15088D01*
X707000Y16500D01*
Y21572D01*
X711000Y25572D01*
Y27406D01*
X712594Y29000D01*
X727891D01*
X735433Y21458D01*
X755033D01*
X756705Y23130D01*
X756714D01*
G01X716921Y-6048D02*
Y-6100D01*
X716869Y-6048D01*
X713937D01*
G01X664888Y89189D02*
Y88812D01*
X667900Y85800D01*
Y84100D01*
G01X664888Y89189D02*
Y92766D01*
G01X667900Y84100D02*
X666432D01*
X664471Y86061D01*
G01X668388Y89189D02*
X670795D01*
G01X703845Y88830D02*
Y88552D01*
X703919Y88478D01*
Y82850D01*
G01X694000Y79500D02*
Y80500D01*
X698300Y84800D01*
Y85300D01*
G01X713300Y86000D02*
X711900Y84600D01*
Y82965D01*
X711233Y82298D01*
G01X707329Y88955D02*
Y88655D01*
X707893Y88091D01*
Y82298D01*
G01X705972Y86660D02*
X706074Y86558D01*
Y81705D01*
X703919Y79550D01*
G01X690048Y281053D02*
X691732D01*
X693252Y279533D01*
X693259D01*
X696213Y276579D01*
Y274186D01*
X699869Y270530D01*
X700567D01*
X702036Y269061D01*
G01X702011Y272561D02*
X699147D01*
X697138Y274570D01*
Y276963D01*
X690048Y284053D01*
G01X710500Y252500D02*
X709690D01*
X706110Y256080D01*
X704090D01*
G01X683000Y256000D02*
X679700D01*
X677800Y254100D01*
G01X710700Y260200D02*
X710500Y260000D01*
Y256000D01*
G01X710675Y263425D02*
X716761Y269511D01*
Y284408D01*
X704516Y296653D01*
X702503D01*
G01X690704Y274026D02*
X681321D01*
X680472Y273177D01*
X674253D01*
X673240Y274190D01*
G01X673500Y295000D02*
Y297656D01*
X673922Y298078D01*
G01X683000Y294800D02*
Y295120D01*
X686140Y298260D01*
G01X709100Y303600D02*
X707631Y305069D01*
X705319D01*
X702503Y302253D01*
Y296653D01*
G01X712600Y300100D02*
Y301000D01*
X711800Y301800D01*
X709856D01*
X709100Y302556D01*
Y303600D01*
G01X705800Y301600D02*
X706780D01*
X708380Y300000D01*
X709000D01*
X709100Y300100D01*
G01X700700Y304300D02*
Y306100D01*
X700500Y306300D01*
Y308000D01*
G01X688100Y308600D02*
X689300Y309800D01*
X697700D01*
X699500Y308000D01*
X700500D01*
G01X688924Y288147D02*
X688974D01*
X690284Y289457D01*
Y291412D01*
G01X687427Y384926D02*
Y380000D01*
G01X695700Y357300D02*
X693800D01*
X689000Y352500D01*
G01X693000D02*
X695144Y354644D01*
X695644D01*
G01X689000Y349000D02*
Y348400D01*
X692000Y345400D01*
G01D02*
X694800D01*
X695700Y346300D01*
G01X695790Y351300D02*
Y350286D01*
X694504Y349000D01*
X693000D01*
G01X679700Y489400D02*
X680500Y490200D01*
Y493000D01*
G01X679049Y503746D02*
Y499575D01*
X678020Y498546D01*
X674546D01*
X670500Y494500D01*
G01X669150Y489450D02*
X667000Y491600D01*
Y494500D01*
G01D02*
Y496200D01*
X668118Y497318D01*
Y500500D01*
G01X664000Y494500D02*
X667000D01*
G01X673464Y503784D02*
X671436D01*
X668152Y500500D01*
X668118D01*
G01X725600Y594600D02*
X724300D01*
X722406Y596494D01*
Y598950D01*
G01X730923Y75315D02*
X726815D01*
G01X763200Y407700D02*
X758970D01*
X758150Y406880D01*
G01X762989Y411728D02*
X763200Y411517D01*
Y407700D01*
G01X763069Y414441D02*
X766300Y411210D01*
Y407700D01*
G01X769600Y407600D02*
Y410300D01*
X768663Y411237D01*
Y418197D01*
X768080Y418780D01*
G01X729350Y506700D02*
X726660D01*
X726040Y506080D01*
G01D02*
X725190Y506930D01*
Y510910D01*
G01X728141Y579451D02*
X726692Y580900D01*
X725400D01*
G01X726500Y574500D02*
Y576500D01*
X728141Y578141D01*
Y579451D01*
G01X727000Y600500D02*
Y596000D01*
X725600Y594600D01*
G01X810000Y418500D02*
X812000D01*
X816413Y414087D01*
X844725D01*
X893471Y365341D01*
Y355029D01*
X895020Y353480D01*
X901579D01*
X902559Y352500D01*
G01X806500Y418500D02*
X803785D01*
X802900Y417615D01*
G01D02*
X800610Y415325D01*
Y415000D01*
G01X810000Y412500D02*
X810005Y412505D01*
X812190D01*
X814159Y410536D01*
X843254D01*
X889625Y364165D01*
Y353853D01*
X893548Y349930D01*
X899842D01*
X901010Y348762D01*
X902337D01*
X910455Y340644D01*
G01X797200Y409830D02*
X800463D01*
X803133Y412500D01*
X806500D01*
G01X810000Y415500D02*
X812000D01*
X815189Y412311D01*
X843988D01*
X843989Y412312D01*
X891401Y364900D01*
Y363430D01*
X891400Y363429D01*
Y354589D01*
X894284Y351705D01*
X900578D01*
X901746Y350537D01*
X904462D01*
X906622Y348377D01*
G01X798500Y412600D02*
X800721D01*
X803621Y415500D01*
X806500D01*
G01X902559Y352500D02*
X906399D01*
X913099Y345800D01*
X914401D01*
X916580Y343621D01*
X918468D01*
X920347Y345500D01*
X921501D01*
X923239Y343762D01*
X924831D01*
X926790Y341803D01*
X928250D01*
X930159Y343712D01*
X931816D01*
X933789Y341739D01*
X934917D01*
X936499Y343321D01*
X938638D01*
X940114Y341845D01*
X941792D01*
X943636Y343689D01*
X945432D01*
X947073Y342048D01*
X948555D01*
X950364Y343857D01*
X952115D01*
X954272Y341700D01*
X955200D01*
X957226Y339674D01*
X958750D01*
X959808Y338616D01*
X969302D01*
X970720Y340034D01*
X972434D01*
X973800Y341400D01*
X976000D01*
X977300Y340100D01*
X979200D01*
X980500Y341400D01*
X982800D01*
X984100Y340100D01*
X985900D01*
X987200Y341400D01*
X989300D01*
X990600Y340100D01*
X992700D01*
X994200Y341600D01*
X995790D01*
X997821Y343631D01*
X999314D01*
X1001147Y345464D01*
X1002840D01*
X1004193Y346817D01*
Y348247D01*
X1003530Y348910D01*
Y350130D01*
X1005110Y351710D01*
X1006430D01*
X1008110Y353390D01*
X1009661D01*
Y353451D01*
X1011510Y355300D01*
X1012524D01*
X1014613Y353211D01*
X1016192D01*
X1018008Y355027D01*
X1019417D01*
X1021508Y357118D01*
X1023025D01*
X1024539Y355604D01*
X1026139D01*
X1028295Y353448D01*
X1029863D01*
X1031645Y351666D01*
X1033296D01*
X1035383Y353753D01*
X1036852D01*
X1038409Y355310D01*
X1040189D01*
X1042276Y357397D01*
X1043497D01*
X1045076Y358976D01*
X1046924D01*
X1048400Y357500D01*
X1050300D01*
X1051885Y359085D01*
X1060773D01*
X1061039Y359351D01*
G01X1052664Y353409D02*
X1052430Y353175D01*
X1048433D01*
X1046208Y355400D01*
X1045100D01*
X1043100Y353400D01*
X1042014D01*
X1039410Y350796D01*
X1038131D01*
X1037285Y349950D01*
X1036371D01*
X1035961Y349540D01*
X1035505D01*
X1033502Y347537D01*
X1031908D01*
X1030062Y349383D01*
X1028113D01*
X1025880Y351616D01*
X1024967D01*
X1023053Y353530D01*
X1021484D01*
X1019332Y351378D01*
X1018180D01*
X1016499Y349697D01*
X1014684D01*
X1013051Y351330D01*
X1011230D01*
X1009620Y349720D01*
X1007990D01*
X1006540Y348270D01*
Y347000D01*
X1007107Y346433D01*
Y344552D01*
X1006400Y343845D01*
X1004686D01*
X1002822Y341981D01*
X1001181D01*
X999153Y339953D01*
X997777D01*
X995424Y337600D01*
X994520D01*
X992628Y335708D01*
X991040D01*
X988948Y337800D01*
X987714D01*
X985806Y335892D01*
X984406D01*
X982698Y337600D01*
X980948D01*
X979048Y335700D01*
X977500D01*
X975500Y337700D01*
X973800D01*
X972300Y336200D01*
X970400D01*
X969070Y337530D01*
X967180D01*
X965557Y335907D01*
X957616D01*
X955602Y337921D01*
X953779D01*
X952000Y339700D01*
X950107D01*
X948555Y338148D01*
X947219D01*
X945946Y339421D01*
X943068D01*
X941795Y338148D01*
X940459D01*
X939186Y339421D01*
X936308D01*
X935035Y338148D01*
X933699D01*
X932426Y339421D01*
X929548D01*
X928275Y338148D01*
X926939D01*
X925666Y339421D01*
X924007D01*
X921629Y341799D01*
X919973D01*
X918271Y340097D01*
X916304D01*
X914601Y341800D01*
X912939D01*
X906622Y348117D01*
Y348377D01*
G01X918255Y351719D02*
X916657D01*
X914679Y353697D01*
X912903D01*
X908100Y358500D01*
X899500D01*
G01Y367500D02*
X908300D01*
G01D02*
X909762D01*
X913848Y363414D01*
X924733D01*
X926804Y361343D01*
X928295D01*
X930045Y363093D01*
X931710D01*
X933460Y361343D01*
X935081D01*
X936693Y362955D01*
X938506D01*
X940118Y361343D01*
X941995D01*
X943526Y362874D01*
X945288D01*
X946904Y361258D01*
X948868D01*
X950532Y362922D01*
X952368D01*
X953989Y361301D01*
X955580D01*
X957629Y359252D01*
X958663D01*
X961406Y356509D01*
Y355360D01*
G01X916293Y348207D02*
X915054Y349446D01*
X912740D01*
X906686Y355500D01*
X899500D01*
G01X909450Y395500D02*
X919706D01*
X920847Y394359D01*
G01Y398260D02*
X903550D01*
G01X927607D02*
Y400992D01*
X923099Y405500D01*
X910700D01*
X908650Y403450D01*
G01X957285Y22133D02*
X957283D01*
Y17057D01*
G01X967324Y4023D02*
Y9112D01*
X967322Y9114D01*
G01X957285Y97733D02*
X957283D01*
Y92657D01*
G01X957285Y59933D02*
X957283D01*
Y54857D01*
G01X967324Y79623D02*
Y84712D01*
X967322Y84714D01*
G01X967324Y41823D02*
Y46912D01*
X967322Y46914D01*
G01X915457Y207159D02*
X920847D01*
G01X917467Y209109D02*
X914773Y211803D01*
X910900D01*
G01Y203260D02*
X920847D01*
G01X910455Y340644D02*
Y340464D01*
X913019Y337900D01*
X914901D01*
X916701Y336100D01*
X918501D01*
X920001Y337600D01*
X921701D01*
X923780Y335521D01*
X925081D01*
X926904Y333698D01*
X928240D01*
X930063Y335521D01*
X931911D01*
X933699Y333733D01*
X935035D01*
X936823Y335521D01*
X939186D01*
X940459Y334248D01*
X941795D01*
X943068Y335521D01*
X945448D01*
X947254Y333715D01*
X948590D01*
X950396Y335521D01*
X951996D01*
X953748Y333769D01*
X955794D01*
X957327Y332236D01*
X958832D01*
X960624Y334028D01*
X962225D01*
X964167Y332086D01*
X965400D01*
X967321Y334007D01*
X969077D01*
X970884Y332200D01*
X972262D01*
X974017Y333955D01*
X975863D01*
X977718Y332100D01*
X979000D01*
X980700Y333800D01*
X982248D01*
X984115Y331933D01*
X986015D01*
X987982Y333900D01*
X989400D01*
X991100Y332200D01*
X992400D01*
X994100Y333900D01*
X996200D01*
X997900Y335600D01*
X999200D01*
X1001310Y337710D01*
X1002811D01*
X1004708Y339607D01*
X1006113D01*
X1008046Y341540D01*
X1009419D01*
X1011359Y343480D01*
X1012850D01*
X1014857Y345487D01*
X1016215D01*
X1018148Y347420D01*
X1019490D01*
X1021120Y345790D01*
X1022700D01*
X1024770Y343720D01*
X1032873D01*
X1033969Y344816D01*
X1034785D01*
X1037379Y347410D01*
X1039040D01*
X1040356Y348726D01*
X1053516D01*
X1060150Y355360D01*
X1060694D01*
G01X1032385Y353409D02*
X1031666Y354128D01*
Y355253D01*
X1030423Y356496D01*
Y356578D01*
X1029392Y357609D01*
X1027996D01*
X1026582Y359023D01*
X1024938D01*
X1022917Y361044D01*
X1021656D01*
X1019757Y359145D01*
X1017966D01*
X1016174Y357353D01*
X1014647D01*
X1012940Y359060D01*
X1011070D01*
X1009320Y357310D01*
X1008050D01*
X1008013Y357273D01*
X1007743D01*
X1005810Y355340D01*
X1004950D01*
X1003057Y353447D01*
X1001407D01*
X1000250Y352290D01*
Y348859D01*
X999035Y347644D01*
X998150D01*
X996037Y345531D01*
X994386D01*
X992593Y343738D01*
X991269D01*
X989241Y345766D01*
X987690D01*
X985683Y343759D01*
X984398D01*
X982462Y345695D01*
X980841D01*
X978820Y343674D01*
X977633D01*
X975831Y345476D01*
X974272D01*
X972257Y343461D01*
X970592D01*
X967971Y340840D01*
X967830D01*
G01D02*
X965130D01*
G01Y344340D02*
Y346394D01*
X967347Y348611D01*
X967498D01*
G01D02*
X968749D01*
X969567Y347793D01*
X972619D01*
X974134Y349308D01*
X975969D01*
X977548Y347729D01*
X979213D01*
X980920Y349436D01*
X982584D01*
X984206Y347814D01*
X985828D01*
X987578Y349564D01*
X989106D01*
X991013Y351471D01*
X992639D01*
X994404Y349706D01*
X996086D01*
X996850Y350470D01*
Y354030D01*
X997910Y355090D01*
X998850D01*
X1001033Y357273D01*
X1002743D01*
X1004386Y358916D01*
X1005926D01*
X1008230Y361220D01*
X1009230D01*
X1011160Y363150D01*
X1013187D01*
X1015250Y361087D01*
X1015960D01*
X1018226Y363353D01*
X1019890D01*
X1021508Y364971D01*
X1023002D01*
X1024624Y363349D01*
X1026366D01*
X1028315Y361400D01*
X1029800D01*
X1031400Y363000D01*
X1031401D01*
X1031572Y363171D01*
X1033481D01*
X1034500Y362152D01*
Y360268D01*
X1034158Y359926D01*
Y358342D01*
X1035300Y357200D01*
Y355825D01*
X1035765Y355360D01*
G01X916700Y403300D02*
X919791Y400209D01*
X924227D01*
G01X957285Y523134D02*
X957283Y523133D01*
Y518057D01*
G01X967324Y505024D02*
Y510112D01*
X967322Y510114D01*
G01X957285Y560934D02*
X957283Y560933D01*
Y555857D01*
G01X967324Y542824D02*
Y547912D01*
X967322Y547914D01*
G01X967324Y580624D02*
Y585712D01*
X967322Y585714D01*
G01X957285Y598734D02*
X957283Y598733D01*
Y593657D01*
G01X1071065Y4023D02*
X1071063D01*
Y9121D01*
X1071064Y9122D01*
G01X1071062Y-1817D02*
Y-4038D01*
X1068500Y-6600D01*
X1066800D01*
X1065400Y-5200D01*
X1063600D01*
X1062200Y-6600D01*
X1060400D01*
X1058800Y-5000D01*
X1056800D01*
X1055100Y-6700D01*
X1053700D01*
X1052000Y-5000D01*
X1050100D01*
X1048800Y-6300D01*
X1046000D01*
X1042200Y-2500D01*
Y40300D01*
X1040450Y42050D01*
Y44350D01*
X1042500Y46400D01*
Y53100D01*
X1044100Y54700D01*
G01X1061025Y4023D02*
Y9121D01*
X1061024Y9122D01*
G01X1045525Y15357D02*
Y16376D01*
X1044291Y17610D01*
Y22133D01*
X1044293D01*
G01X1071065Y79623D02*
X1071063D01*
Y73758D01*
X1071064Y73757D01*
G01Y46922D02*
X1071063Y46921D01*
Y41823D01*
X1071065D01*
G01X1044100Y54700D02*
X1044894D01*
X1046200Y53394D01*
Y49400D01*
X1046900Y48700D01*
X1069286D01*
X1071064Y46922D01*
G01X1087797Y41823D02*
X1087795D01*
Y46920D01*
X1087797Y46922D01*
G01X1071065Y59933D02*
X1071063D01*
Y54858D01*
X1071064Y54857D01*
G01X1061025Y79623D02*
Y84712D01*
X1061023Y84714D01*
G01X1061025Y41823D02*
Y46921D01*
X1061024Y46922D01*
G01X1044290Y68964D02*
Y71010D01*
X1042200Y73100D01*
Y90600D01*
X1044293Y92693D01*
Y97733D01*
G01Y59933D02*
Y68961D01*
X1044290Y68964D01*
G01X1092100Y264500D02*
X1090607Y265993D01*
Y267665D01*
X1089665Y268607D01*
X1089592D01*
X1088500Y269699D01*
Y270000D01*
G01X1060694Y390460D02*
Y391094D01*
X1066300Y396700D01*
G01X1071065Y505024D02*
X1071063Y505026D01*
Y511280D01*
X1069543Y512800D01*
X1067100D01*
X1065400Y514500D01*
X1063600D01*
X1062000Y512900D01*
X1060700D01*
X1058800Y514800D01*
X1056600D01*
X1054900Y513100D01*
X1053500D01*
X1052000Y514600D01*
X1049900D01*
X1048700Y513400D01*
X1046800D01*
X1042100Y518100D01*
Y528800D01*
X1042450Y529150D01*
Y536850D01*
X1042100Y537200D01*
Y547150D01*
X1042500Y547550D01*
Y552266D01*
X1043734Y553500D01*
G01X1061025Y505024D02*
Y510112D01*
X1061023Y510114D01*
G01X1044195Y529026D02*
X1044291Y528930D01*
Y523134D01*
X1044293D01*
G01X1043734Y553500D02*
X1042100Y555134D01*
Y565850D01*
X1042500Y566250D01*
Y575200D01*
X1041500Y576200D01*
Y584832D01*
X1042110Y585442D01*
Y590112D01*
X1043699Y591701D01*
G01X1071065Y580624D02*
Y585721D01*
X1071064Y585722D01*
G01Y547922D02*
X1071065Y547921D01*
Y542824D01*
G01X1043734Y553500D02*
X1046000Y551234D01*
Y550621D01*
X1046784Y549837D01*
X1069149D01*
X1071064Y547922D01*
G01X1043699Y591701D02*
X1044799D01*
X1046000Y590500D01*
Y588000D01*
X1046500Y587500D01*
X1069286D01*
X1071064Y585722D01*
G01X1071065Y560934D02*
X1071063Y560933D01*
Y555858D01*
X1071064Y555857D01*
G01X1087797Y580624D02*
X1087795D01*
Y585720D01*
X1087797Y585722D01*
G01X1061025Y542824D02*
Y547921D01*
X1061024Y547922D01*
G01X1061025Y580624D02*
Y585721D01*
X1061024Y585722D01*
G01X1044293Y560934D02*
Y569489D01*
X1044290Y569492D01*
G01X1071062Y612560D02*
Y610562D01*
X1068500Y608000D01*
X1067000D01*
X1065500Y609500D01*
X1063011D01*
X1061511Y608000D01*
X1060500D01*
X1059000Y609500D01*
X1057000D01*
X1055500Y608000D01*
X1053500D01*
X1052000Y609500D01*
X1050000D01*
X1048500Y608000D01*
X1047000D01*
X1045500Y609500D01*
X1043017D01*
X1042500Y608983D01*
Y592900D01*
X1043699Y591701D01*
G01X1296295Y615596D02*
X1286304D01*
X1281064Y620836D01*
X1242586D01*
X1238579Y616829D01*
X1116129D01*
X1112300Y613000D01*
Y609100D01*
X1111800Y608600D01*
X1100700D01*
X1098514Y610786D01*
X1096314D01*
X1095400Y611700D01*
X1093972D01*
X1093166Y610894D01*
X1090106D01*
X1088500Y612500D01*
X1087000D01*
X1082500Y608000D01*
X1080000D01*
X1078000Y610000D01*
X1077000D01*
X1074343Y612657D01*
X1071159D01*
X1071062Y612560D01*
G01X1071065Y598734D02*
X1071063Y598733D01*
Y593658D01*
X1071064Y593657D01*
G01X1044290Y607292D02*
X1044293Y607289D01*
Y598734D01*
G01X1151060Y270796D02*
X1152478Y269378D01*
Y267922D01*
X1153600Y266800D01*
X1154859D01*
X1156100Y265559D01*
Y265300D01*
X1156980Y264420D01*
G01X1107600Y271900D02*
X1105456Y274044D01*
Y278241D01*
G01X1123769Y290624D02*
X1125578Y288815D01*
Y287897D01*
X1127421Y286054D01*
X1128066D01*
X1129420Y284700D01*
X1131000D01*
X1133500Y282200D01*
X1134780D01*
X1136091Y280889D01*
X1138458D01*
X1138958Y280389D01*
Y279734D01*
X1140107Y278585D01*
X1141733D01*
X1143648Y280500D01*
X1145361D01*
X1147015Y282154D01*
X1148746D01*
X1150200Y280700D01*
X1151582D01*
X1153648Y278634D01*
X1155232D01*
X1157181Y280583D01*
X1158317D01*
X1160300Y278600D01*
X1162311D01*
X1163914Y280203D01*
X1165246D01*
X1166949Y278500D01*
X1168400D01*
X1170266Y276634D01*
X1172152D01*
X1172164Y276646D01*
X1174719D01*
G01X1123256Y282984D02*
X1124040Y282200D01*
X1128020D01*
X1130017Y280203D01*
X1131446D01*
X1132949Y278700D01*
X1135000D01*
X1136711Y276989D01*
X1137912D01*
X1140001Y274900D01*
X1141699D01*
X1143788Y276989D01*
X1144966D01*
X1146585Y278608D01*
X1148632D01*
X1150251Y276989D01*
X1151512D01*
X1153501Y275000D01*
X1155199D01*
X1157188Y276989D01*
X1158312D01*
X1160401Y274900D01*
X1161899D01*
X1163657Y276658D01*
X1165393D01*
X1165405Y276646D01*
X1167960D01*
G01X1114839Y320075D02*
X1112564Y317800D01*
X1110300D01*
G01X1111300Y298100D02*
X1113174Y296226D01*
Y295926D01*
X1115489Y293611D01*
X1117351D01*
X1118562Y292400D01*
X1121993D01*
X1123769Y290624D01*
G01X1111300Y294500D02*
X1113000D01*
X1119155Y288345D01*
X1120600D01*
X1121891Y287054D01*
Y284349D01*
X1123256Y282984D01*
G01X1111300Y301100D02*
X1113300D01*
X1116200Y298200D01*
X1116832D01*
X1118832Y296200D01*
X1121664D01*
X1123747Y298283D01*
G01D02*
X1125100Y299636D01*
Y300800D01*
X1126453Y302153D01*
X1128144D01*
X1129917Y303926D01*
X1131302D01*
X1132251Y304875D01*
X1132668Y305881D01*
Y306632D01*
X1132200Y307100D01*
Y308600D01*
X1132574Y308974D01*
Y310626D01*
X1132200Y311000D01*
Y312400D01*
X1132574Y312774D01*
Y314526D01*
X1132303Y315180D01*
Y315743D01*
X1132898Y317181D01*
X1133302Y317585D01*
X1134973D01*
X1136122Y318734D01*
Y320360D01*
X1134973Y321509D01*
X1133559D01*
X1132366Y322702D01*
Y322734D01*
X1132284Y322816D01*
Y323480D01*
X1132958Y325108D01*
Y325628D01*
X1132804Y326000D01*
X1132509Y326711D01*
X1131699Y327521D01*
X1129779D01*
X1128100Y329200D01*
X1126801D01*
X1125600Y330401D01*
Y332000D01*
X1126100Y332500D01*
Y333700D01*
X1125500Y334300D01*
Y335900D01*
X1126000Y336400D01*
Y337701D01*
X1124601Y339100D01*
X1123379D01*
X1122200Y340279D01*
Y341388D01*
X1120641Y342947D01*
G01X1244331Y116188D02*
Y113820D01*
X1245866Y112285D01*
Y106753D01*
X1244355Y105242D01*
X1236001D01*
X1233661Y102902D01*
X1217598D01*
X1216100Y104400D01*
Y106520D01*
G01D02*
Y108302D01*
X1218254Y110456D01*
G01X1217277Y226750D02*
X1218771Y225256D01*
X1231141D01*
X1244418Y230742D01*
X1249737Y234238D01*
X1259201Y238129D01*
X1263401Y240889D01*
G01X1165400Y257726D02*
Y256915D01*
X1166256Y256059D01*
Y253866D01*
X1166084Y253694D01*
Y252223D01*
X1167960Y250347D01*
Y249347D01*
G01Y245447D02*
Y246288D01*
X1165245Y249003D01*
X1164601D01*
X1162083Y251521D01*
X1160303D01*
X1157776Y254048D01*
X1157013D01*
G01X1171339Y243496D02*
Y242061D01*
X1173950Y239450D01*
X1175385D01*
X1177335Y237500D01*
X1179100D01*
X1181000Y235600D01*
X1182350D01*
X1184450Y233500D01*
X1185950D01*
X1187850Y231600D01*
X1189350D01*
X1191250Y229700D01*
X1192600D01*
X1194150Y228150D01*
X1195850D01*
X1197850Y226150D01*
X1199100D01*
X1200472Y227522D01*
G01X1210027Y226745D02*
G03X1211763Y225700I1736J920D01*
G01X1216380D01*
X1218080Y224000D01*
X1230569D01*
X1244852Y229919D01*
X1246397Y230934D01*
X1246403Y230937D01*
X1250014Y233313D01*
X1256327Y235900D01*
X1269500D01*
G01X1165522Y261143D02*
X1167374Y262995D01*
X1168505D01*
X1170300Y261200D01*
X1172100D01*
X1173909Y263009D01*
X1178086D01*
X1178099Y262996D01*
G01X1167960Y268847D02*
X1167439Y268326D01*
X1164900D01*
G01X1159390Y262460D02*
X1157850Y260920D01*
X1156980D01*
G01X1164900Y264826D02*
X1167839D01*
X1167960Y264947D01*
G01X1198029Y405411D02*
Y405171D01*
X1201000Y402200D01*
G01X1255120Y22133D02*
X1255118D01*
Y16999D01*
G01X1255120Y4023D02*
X1255118D01*
Y9157D01*
G01X1265159Y22133D02*
Y17001D01*
X1265157Y16999D01*
G01X1255120Y97733D02*
X1255118D01*
Y92599D01*
G01X1255120Y59933D02*
X1255118D01*
Y54799D01*
G01X1255120Y79623D02*
X1255118D01*
Y84757D01*
G01X1255120Y41823D02*
X1255118D01*
Y46957D01*
G01X1265159Y97733D02*
Y92601D01*
X1265157Y92599D01*
G01X1265159Y59933D02*
Y54801D01*
X1265157Y54799D01*
G01X1257500Y142000D02*
Y142200D01*
X1259950Y144650D01*
G01X1271550Y129670D02*
Y125857D01*
G01D02*
Y122550D01*
X1271500Y122500D01*
G01X1259371Y129171D02*
X1256391Y126191D01*
X1247733D01*
X1244025Y129899D01*
Y137770D01*
X1240022Y141773D01*
G01X1275050Y129670D02*
Y131150D01*
X1274500Y131700D01*
X1261900D01*
X1259371Y129171D01*
G01X1268050Y129670D02*
Y125670D01*
G01X1268900Y122500D02*
Y122530D01*
X1268050Y123380D01*
Y125670D01*
G01X1264550Y129670D02*
X1262920D01*
X1258016Y124766D01*
X1246904D01*
X1245385Y126285D01*
Y126352D01*
X1244996Y126741D01*
X1244929D01*
X1242463Y129207D01*
Y136980D01*
X1238323Y141120D01*
Y142555D01*
X1240010Y144242D01*
Y144754D01*
G01X1271500Y102100D02*
X1272100D01*
X1275050Y105050D01*
Y107918D01*
G01X1271550Y111670D02*
Y107918D01*
G01D02*
Y104760D01*
X1271490Y104700D01*
G01X1264550Y107670D02*
Y105950D01*
X1268400Y102100D01*
X1268500D01*
G01X1268050Y107670D02*
Y105250D01*
X1268600Y104700D01*
G01X1268050Y111670D02*
Y107670D01*
G01X1255800Y130700D02*
Y131700D01*
X1259964Y135864D01*
Y135865D01*
X1260389Y136290D01*
X1267441D01*
X1268401Y137250D01*
G01D02*
X1268550Y137399D01*
Y138792D01*
X1266774Y140568D01*
X1265828D01*
G01X1278030Y148510D02*
X1277946Y148426D01*
X1276890D01*
X1275540Y147076D01*
Y140474D01*
X1275006Y139940D01*
X1271155D01*
X1270088Y141007D01*
Y142814D01*
X1269114Y143788D01*
X1266638D01*
X1262900Y140050D01*
G01D02*
X1261580D01*
X1256230Y134700D01*
X1255800D01*
G01X1248616Y133817D02*
X1250078D01*
X1250961Y134700D01*
X1252300D01*
G01D02*
Y130700D01*
G01X1231442Y124775D02*
X1232700Y126033D01*
Y143419D01*
X1237704Y148423D01*
G01X1271139Y117373D02*
X1268991D01*
X1268576Y117788D01*
G01X1228835Y109162D02*
X1226210D01*
X1224924Y110448D01*
G01X1228835Y109162D02*
Y106965D01*
X1229336Y106464D01*
X1230948D01*
X1231394Y106910D01*
Y109162D01*
G01X1221300Y106600D02*
Y106824D01*
X1224924Y110448D01*
G01X1221682Y110456D02*
X1219300Y108074D01*
Y105701D01*
X1220589Y104412D01*
X1233155D01*
X1235462Y106719D01*
X1238144D01*
X1239213Y107788D01*
Y109188D01*
G01X1233953Y116162D02*
Y114448D01*
X1239213Y109188D01*
G01X1233953Y116162D02*
Y127053D01*
X1235165Y128265D01*
Y129710D01*
G01D02*
Y130735D01*
X1233953Y131947D01*
Y141918D01*
X1240843Y148808D01*
Y151811D01*
X1243948Y154916D01*
G01X1229600Y128300D02*
Y122400D01*
X1230725Y121275D01*
X1231442D01*
G01X1231394Y116162D02*
Y121227D01*
X1231442Y121275D01*
G01X1249025Y130460D02*
X1248210D01*
X1246338Y132332D01*
Y154894D01*
X1244371Y156861D01*
X1226519D01*
X1224600Y158780D01*
Y187370D01*
X1228500Y191270D01*
Y206293D01*
X1226866Y207927D01*
Y207904D01*
X1226867D01*
G01X1240000Y129500D02*
X1236600Y126100D01*
Y124877D01*
G01X1242000Y125000D02*
X1238377Y121377D01*
X1236600D01*
G01X1241772Y109188D02*
Y110811D01*
X1240672Y111911D01*
X1238944D01*
X1236125Y114730D01*
Y120902D01*
X1236600Y121377D01*
G01X1241772Y116188D02*
Y118934D01*
X1242116Y119278D01*
X1243693D01*
X1244331Y118640D01*
Y116188D01*
G01X1227200Y215543D02*
X1229700Y213043D01*
Y204400D01*
X1259200Y174900D01*
Y168350D01*
G01X1263300Y172440D02*
Y169450D01*
G01X1302000Y282300D02*
Y274403D01*
X1280026Y252429D01*
X1277235D01*
X1271477Y246671D01*
X1268771D01*
X1268404Y246304D01*
G01X1274100Y255300D02*
X1280087D01*
X1287743Y262956D01*
G01X1279393Y247602D02*
X1274801D01*
X1272445Y245246D01*
X1270029D01*
X1263401Y240889D01*
G01X1279393Y247602D02*
X1281712Y247597D01*
X1285809Y243500D01*
X1287500D01*
G01X1270478Y243490D02*
X1276337D01*
G01X1287500Y240500D02*
X1279327D01*
X1276337Y243490D01*
G01X1287670Y231199D02*
X1284139D01*
X1277350Y237988D01*
X1273744D01*
X1271656Y235900D01*
X1269500D01*
G01X1255120Y523134D02*
Y518000D01*
G01X1250890Y497310D02*
X1248610D01*
X1246300Y495000D01*
G01D02*
Y492850D01*
X1247842Y491308D01*
X1249193D01*
G01X1250890Y493810D02*
Y492110D01*
X1251710Y491290D01*
Y486010D01*
X1249500Y483800D01*
G01X1263600Y480980D02*
X1258770D01*
X1258290Y480500D01*
X1251410D01*
X1249500Y482410D01*
Y483800D01*
G01X1250890Y493810D02*
X1254390D01*
G01X1255120Y510158D02*
Y505024D01*
G01X1245300Y477300D02*
X1244199D01*
X1242100Y479399D01*
Y484100D01*
G01D02*
Y487499D01*
X1244001Y489400D01*
X1247987D01*
X1248474Y488913D01*
G01X1263600Y478420D02*
X1260120D01*
X1259010Y477310D01*
X1254000D01*
G01D02*
X1248810D01*
X1248800Y477300D01*
G01D02*
Y475702D01*
X1248700Y475602D01*
Y473700D01*
G01X1265159Y523134D02*
Y518001D01*
X1265157Y517999D01*
G01X1266900Y469500D02*
X1263600Y472800D01*
Y475860D01*
G01X1255120Y560934D02*
Y555144D01*
G01Y537034D02*
Y542824D01*
G01Y580624D02*
Y574834D01*
G01X1265159Y560934D02*
Y555801D01*
X1265157Y555799D01*
G01X1255120Y598734D02*
Y593600D01*
G01X1265159Y598734D02*
Y593601D01*
X1265157Y593599D01*
G01X1301500Y23500D02*
X1300299D01*
X1298309Y21510D01*
X1297010D01*
G01X1303760Y28900D02*
X1301200D01*
G01D02*
X1300600Y29500D01*
X1297000D01*
G01X1297010Y21510D02*
X1296910Y21610D01*
Y29410D01*
X1297000Y29500D01*
G01X1347500Y83000D02*
Y82160D01*
X1344340Y79000D01*
X1315620D01*
X1313020Y81600D01*
X1307428D01*
X1304670Y78842D01*
Y78827D01*
X1304685D01*
G01X1330100Y71510D02*
X1327892D01*
X1327467Y71085D01*
Y70786D01*
G01X1330100Y68000D02*
X1327500D01*
G01X1304500Y40066D02*
X1303634D01*
X1301100Y42600D01*
G01X1303760Y35900D02*
Y38260D01*
X1304500Y39000D01*
Y40066D01*
G01X1306320Y35900D02*
Y40780D01*
X1304500Y42600D01*
G01X1296935Y51335D02*
X1300265D01*
X1302774Y48826D01*
Y43626D01*
X1303800Y42600D01*
X1304500D01*
G01X1330800Y220450D02*
Y218663D01*
X1330074Y217937D01*
Y216500D01*
G01D02*
X1336561Y210013D01*
Y208048D01*
X1345509Y199100D01*
X1385496D01*
X1408381Y176215D01*
Y155965D01*
X1441233Y123113D01*
X1469213D01*
X1471500Y125400D01*
X1474218D01*
X1479138Y130320D01*
G01X1334600Y228400D02*
X1335525Y227475D01*
Y216849D01*
X1335874Y216500D01*
X1336074D01*
G01X1333074D02*
X1333274D01*
X1334100Y217326D01*
Y225600D01*
X1331387Y228313D01*
X1310486D01*
X1300410Y238389D01*
X1296732D01*
X1293075Y242046D01*
Y246575D01*
X1294909Y248409D01*
G01X1287670Y231199D02*
Y232678D01*
X1287137Y233211D01*
Y235248D01*
X1287609Y235720D01*
X1292606D01*
X1297632Y230694D01*
X1301825D01*
X1308057Y224462D01*
X1323524D01*
X1326474Y221512D01*
Y216500D01*
G01X1334724Y209051D02*
Y207692D01*
X1344741Y197675D01*
X1384905D01*
X1406956Y175624D01*
Y155374D01*
X1440142Y122188D01*
X1465472D01*
X1468635Y119025D01*
G01X1338224Y209051D02*
X1346750Y200525D01*
X1386380D01*
X1409806Y177099D01*
Y156556D01*
X1442324Y124038D01*
X1468829D01*
X1471117Y126326D01*
X1471883D01*
X1471884Y126325D01*
X1473127D01*
X1475082Y128280D01*
Y129082D01*
X1482500Y136500D01*
X1488455D01*
X1489000Y135955D01*
G01X1329324Y208951D02*
Y207076D01*
X1336100Y200300D01*
G01X1513136Y157081D02*
X1513300D01*
X1517086Y153295D01*
Y148275D01*
X1511847Y143036D01*
Y141925D01*
X1510611Y140689D01*
X1508823D01*
X1506400Y138266D01*
X1500153D01*
X1495755Y133868D01*
X1493190D01*
X1484924Y125602D01*
Y123764D01*
X1483719Y122559D01*
X1482615D01*
X1474145Y114089D01*
X1469439D01*
X1463090Y120438D01*
X1439285D01*
X1405560Y154163D01*
X1405524D01*
X1405523Y154164D01*
X1404343D01*
X1404342Y154163D01*
X1399537D01*
X1397413Y156287D01*
Y180409D01*
X1382973Y194849D01*
X1341551D01*
X1336100Y200300D01*
G01X1428000Y124600D02*
X1427025Y125575D01*
Y128925D01*
X1404562Y151388D01*
X1398451D01*
X1394614Y155225D01*
Y179289D01*
X1381553Y192350D01*
X1338433D01*
X1326675Y204108D01*
Y213947D01*
X1324811Y215811D01*
Y221131D01*
X1322305Y223637D01*
X1307383D01*
X1303003Y228017D01*
X1296679D01*
G01X1474717Y110370D02*
X1471142D01*
X1462499Y119013D01*
X1438694D01*
X1433226Y124481D01*
X1433190D01*
X1404933Y152738D01*
X1398658D01*
X1395988Y155408D01*
Y179818D01*
X1382382Y193424D01*
X1339447D01*
X1327600Y205271D01*
Y213413D01*
X1328221Y214034D01*
Y221827D01*
X1324661Y225387D01*
X1308653D01*
X1299040Y235000D01*
X1295663D01*
X1293163Y237500D01*
X1291000D01*
G01X1285000Y211000D02*
X1289000D01*
X1291524Y213524D01*
Y214952D01*
G01D02*
X1294500Y217928D01*
Y219000D01*
G01X1287743Y262956D02*
X1299996Y275209D01*
Y296501D01*
X1301447Y297952D01*
Y301047D01*
X1304277Y303877D01*
Y307649D01*
X1305873Y309245D01*
G01X1287500Y237500D02*
Y240500D01*
G01X1310950Y255650D02*
Y253350D01*
X1310200Y252600D01*
X1308130D01*
G01D02*
X1306599D01*
X1305400Y253799D01*
Y256100D01*
X1304398Y257102D01*
X1303089D01*
G01X1315183Y289917D02*
X1312600Y287334D01*
Y270554D01*
X1314490Y268664D01*
Y251511D01*
X1309956Y246977D01*
X1305651D01*
X1304567Y245893D01*
X1303171D01*
G01D02*
Y244171D01*
X1302500Y243500D01*
X1300175D01*
X1299750Y243075D01*
Y241500D01*
G01X1334600Y228400D02*
X1333262Y229738D01*
X1311077D01*
X1300981Y239834D01*
X1297303D01*
X1294500Y242637D01*
Y245198D01*
X1296286Y246984D01*
X1298580D01*
X1299671Y245893D01*
G01X1303072Y249560D02*
Y252660D01*
G01X1315177Y297177D02*
Y292977D01*
X1311175Y288975D01*
Y269963D01*
X1312950Y268188D01*
Y251987D01*
X1309365Y248402D01*
X1305790D01*
X1304632Y249560D01*
X1303072D01*
G01X1294909Y248409D02*
X1298421D01*
X1299572Y249560D01*
G01X1306585Y258250D02*
Y259955D01*
X1305700Y260840D01*
X1303040D01*
G01Y264840D02*
X1306860D01*
X1308400Y263300D01*
G01D02*
X1309600Y262100D01*
Y257200D01*
X1308200Y255800D01*
G01X1296679Y228017D02*
X1294493D01*
X1293780Y228730D01*
Y231930D01*
X1291810Y233900D01*
X1288800D01*
G01X1288000Y219000D02*
X1286337D01*
X1283720Y221617D01*
Y223870D01*
G01X1291500Y219000D02*
X1294500D01*
G01X1289679Y222899D02*
Y222031D01*
X1291500Y220210D01*
Y219000D01*
G01X1302000Y282300D02*
Y293107D01*
X1304712Y295819D01*
Y297320D01*
X1304358Y297674D01*
Y299070D01*
X1305950Y300662D01*
Y306611D01*
G01X1330257Y293443D02*
X1338700Y285000D01*
Y284700D01*
G01X1341500Y325600D02*
X1334540D01*
X1329147Y320207D01*
Y314879D01*
X1326700Y312432D01*
Y297000D01*
X1330257Y293443D01*
G01X1323750Y319750D02*
X1322800Y318800D01*
Y314500D01*
X1314500Y306200D01*
Y302048D01*
X1317144Y299404D01*
Y291878D01*
X1315183Y289917D01*
G01X1320900Y321300D02*
X1321375Y320825D01*
Y315475D01*
X1313000Y307100D01*
Y301460D01*
X1315177Y299283D01*
Y297177D01*
G01X1339800Y336800D02*
X1337900D01*
X1335250Y339450D01*
Y341350D01*
G01X1339800Y336800D02*
X1341522D01*
X1343300Y338578D01*
Y340800D01*
G01X1322430Y333960D02*
X1322460Y333930D01*
X1327400D01*
G01Y327195D02*
Y333930D01*
G01X1321600Y294700D02*
X1325062Y298162D01*
Y313249D01*
X1327400Y315587D01*
Y327195D01*
G01X1306290Y298255D02*
X1308039Y300004D01*
Y309423D01*
X1313442Y314826D01*
Y344198D01*
X1315496Y346252D01*
Y354100D01*
G01X1305558Y294313D02*
X1309812Y298567D01*
Y308742D01*
X1315035Y313965D01*
Y343201D01*
X1321068Y349234D01*
G01X1303866Y292345D02*
X1306367D01*
X1311237Y297215D01*
Y307753D01*
X1316628Y313144D01*
Y341028D01*
X1317834Y342234D01*
G01X1336600Y323400D02*
X1344140D01*
X1345000Y324260D01*
Y325600D01*
G01X1336886Y351113D02*
X1337364Y351591D01*
X1341172D01*
X1343300Y349463D01*
Y347800D01*
G01X1335250Y341350D02*
Y344250D01*
G01X1339800Y346800D02*
X1340928D01*
X1341520Y346208D01*
Y344840D01*
X1342060Y344300D01*
X1343300D01*
G01X1339597Y349756D02*
X1339800Y349553D01*
Y346800D01*
G01X1315496Y354100D02*
Y361190D01*
G01X1321068Y349234D02*
X1323568Y351734D01*
X1330766D01*
X1332600Y349900D01*
G01X1317834Y342234D02*
X1325700Y350100D01*
X1330100D01*
G01X1281600Y480980D02*
X1286180D01*
X1287900Y482700D01*
X1290500D01*
G01X1281600Y478420D02*
X1285670D01*
X1288349Y481099D01*
X1289601D01*
X1290500Y480200D01*
G01X1290900Y563300D02*
Y558750D01*
X1294127Y555523D01*
Y548073D01*
X1296617Y545583D01*
X1318143D01*
X1323268Y540458D01*
X1338058D01*
X1340500Y542900D01*
X1368608D01*
X1372698Y546990D01*
X1388257D01*
X1390595Y549328D01*
G01X1362528Y547954D02*
X1363352Y547130D01*
Y546066D01*
X1362811Y545525D01*
X1335925D01*
X1333923Y543523D01*
X1323866D01*
X1319556Y547833D01*
X1298110D01*
X1296599Y549344D01*
Y575441D01*
X1293078Y578962D01*
X1290292D01*
G01X1292190Y576952D02*
X1293746D01*
X1295574Y575124D01*
Y548919D01*
X1297685Y546808D01*
X1319131D01*
X1323441Y542498D01*
X1334398D01*
X1336400Y544500D01*
X1363192D01*
X1364312Y545620D01*
Y547238D01*
X1365028Y547954D01*
G01X1400100Y10000D02*
X1401800Y8300D01*
X1405899D01*
X1406900Y9301D01*
Y10900D01*
X1405400Y12400D01*
Y16400D01*
X1409200Y20200D01*
X1410800D01*
G01X1415400Y23730D02*
X1410007D01*
X1403475Y17198D01*
Y10875D01*
X1402600Y10000D01*
G01X1401200Y124300D02*
Y123856D01*
X1402425Y122631D01*
X1432458D01*
X1437926Y117163D01*
X1461731D01*
X1471113Y107781D01*
X1471879D01*
X1471880Y107782D01*
X1479402D01*
X1486960Y115340D01*
Y124839D01*
X1493447Y131326D01*
X1501640D01*
X1502247Y131933D01*
X1515427D01*
X1518011Y134517D01*
Y152911D01*
X1518012Y152912D01*
Y153678D01*
X1518011Y153679D01*
Y154767D01*
X1514034Y158744D01*
X1501214D01*
X1500703Y158233D01*
G01X1536000Y135000D02*
X1531808Y130808D01*
X1520846D01*
X1519366Y129328D01*
X1517825D01*
X1516979Y130174D01*
X1502964D01*
X1502366Y129576D01*
X1494173D01*
X1488710Y124113D01*
Y114614D01*
X1480128Y106032D01*
X1472606D01*
X1472605Y106031D01*
X1470387D01*
X1470386Y106032D01*
X1470020D01*
X1461748Y114304D01*
X1434504D01*
X1427945Y120863D01*
X1402015D01*
X1400952Y119800D01*
X1397500D01*
X1396780Y119080D01*
G01X1400300Y121500D02*
X1400776Y121976D01*
X1401771D01*
X1402042Y121705D01*
X1402808D01*
X1402809Y121706D01*
X1429973D01*
X1434581Y117098D01*
G01X1396933Y215763D02*
X1397080Y215910D01*
X1399248D01*
X1400983Y214175D01*
X1409001D01*
X1414363Y219537D01*
Y227332D01*
X1412769Y228926D01*
Y251626D01*
X1395655Y268740D01*
X1390983D01*
X1377650Y282073D01*
Y287509D01*
X1383344Y293203D01*
X1388453D01*
X1388750Y293500D01*
G01X1393500Y213250D02*
X1409385D01*
X1415288Y219153D01*
Y227716D01*
X1413694Y229310D01*
Y252010D01*
X1396039Y269665D01*
X1391367D01*
X1378575Y282457D01*
Y287125D01*
X1383000Y291550D01*
X1394218D01*
X1394679Y292011D01*
X1422252D01*
X1430159Y299918D01*
Y317452D01*
X1432887Y320180D01*
X1439342D01*
X1439343Y320179D01*
X1456721D01*
X1458400Y318500D01*
G01X1367789Y209216D02*
X1370489D01*
X1378673Y217400D01*
X1386500D01*
X1390650Y213250D01*
X1393500D01*
G01X1402870Y207918D02*
X1411950Y198838D01*
G01X1406050Y200850D02*
X1403400Y203500D01*
Y204766D01*
G01X1444500Y126600D02*
X1441071D01*
X1410731Y156940D01*
Y178418D01*
X1387699Y201450D01*
X1348542D01*
X1344462Y205530D01*
Y209272D01*
G01X1402020Y165561D02*
X1403208D01*
X1406131Y162638D01*
Y155032D01*
X1439800Y121363D01*
X1463474D01*
X1469808Y115029D01*
X1473776D01*
X1482455Y123708D01*
Y124222D01*
G01X1456250Y204380D02*
X1451619D01*
X1445763Y210236D01*
Y211457D01*
X1437804Y219416D01*
X1427947D01*
X1424171Y223192D01*
X1423239D01*
X1420738Y225693D01*
Y229978D01*
X1419144Y231572D01*
Y254498D01*
X1398926Y274716D01*
Y281582D01*
G01X1432750Y204380D02*
X1427287D01*
X1425410Y206257D01*
Y217553D01*
X1423147Y219816D01*
X1420936D01*
X1419813Y220939D01*
Y229594D01*
X1418219Y231188D01*
Y254114D01*
X1395737Y276596D01*
Y283959D01*
X1397464Y285686D01*
X1428593D01*
X1432344Y289437D01*
G01X1415712Y213300D02*
Y217101D01*
X1417038Y218427D01*
Y228442D01*
X1415444Y230036D01*
Y252962D01*
X1392962Y275444D01*
Y284273D01*
X1392961Y284274D01*
Y285110D01*
X1396312Y288461D01*
X1424106D01*
X1432855Y297210D01*
Y316468D01*
X1433280Y316893D01*
X1440710D01*
X1440910Y316693D01*
G01X1398347Y284023D02*
X1398837D01*
X1400821Y282039D01*
Y277079D01*
X1407200Y270700D01*
Y269600D01*
G01X1434700Y315100D02*
X1433826Y314226D01*
Y296772D01*
X1424590Y287536D01*
X1396696D01*
X1393887Y284727D01*
Y275828D01*
X1416369Y253346D01*
Y230420D01*
X1417963Y228826D01*
Y206280D01*
G01X1456250Y214620D02*
X1449379D01*
X1442525Y221474D01*
X1428989D01*
X1422588Y227875D01*
Y230746D01*
X1421073Y232261D01*
Y255874D01*
X1409200Y267747D01*
Y271800D01*
X1402918Y278082D01*
G01X1402092Y284022D02*
X1402220Y283894D01*
Y278780D01*
X1402918Y278082D01*
G01X1408247Y206270D02*
Y210945D01*
X1416113Y218811D01*
Y228058D01*
X1414519Y229652D01*
Y252352D01*
X1386470Y280401D01*
X1385788D01*
X1385787Y280400D01*
X1381799D01*
X1379400Y282799D01*
Y285684D01*
X1380416Y286700D01*
X1385850D01*
G01X1390800Y279000D02*
X1389350Y280450D01*
Y283600D01*
G01X1422196Y218052D02*
X1421391D01*
X1418888Y220555D01*
Y229210D01*
X1417294Y230804D01*
Y253730D01*
X1394812Y276212D01*
Y284343D01*
X1397080Y286611D01*
X1426458D01*
X1434624Y294777D01*
G01X1363700Y321600D02*
X1364838Y322738D01*
Y324430D01*
X1363468Y325800D01*
X1361700D01*
X1361558Y325942D01*
G01D02*
X1361400Y326100D01*
Y332848D01*
X1361938Y333386D01*
Y334650D01*
G01X1367200Y321600D02*
X1365769Y323031D01*
Y324529D01*
X1365763Y324535D01*
Y324814D01*
X1362503Y328074D01*
Y332352D01*
X1363513Y333362D01*
Y334650D01*
G01X1353500Y329000D02*
X1357000D01*
G01X1353500D02*
X1352842D01*
X1352155Y329687D01*
X1350687D01*
X1350000Y329000D01*
G01D02*
X1350666D01*
X1351729Y327937D01*
Y322380D01*
X1352285Y321824D01*
G01X1358788Y334650D02*
Y333488D01*
X1357000Y331700D01*
Y329000D01*
G01X1392250Y293500D02*
X1392814Y292936D01*
X1421329D01*
X1429103Y300710D01*
Y317705D01*
X1432503Y321105D01*
X1461488D01*
X1462771Y319822D01*
X1463285D01*
X1464476Y318631D01*
Y315500D01*
G01X1345000Y332700D02*
X1350200D01*
G01X1354650Y337213D02*
X1353313D01*
X1352600Y336500D01*
Y335050D01*
X1350250Y332700D01*
X1350200D01*
G01X1357213Y334650D02*
Y333929D01*
X1353947Y330663D01*
X1348662D01*
X1347099Y329100D01*
X1345000D01*
G01Y325600D02*
Y329100D01*
G01X1353500Y325500D02*
Y324711D01*
X1355300Y322911D01*
Y321675D01*
G01X1392657Y288900D02*
X1393684D01*
X1395271Y290487D01*
X1422548D01*
X1431033Y298972D01*
Y317159D01*
X1433229Y319355D01*
X1455659D01*
X1456570Y318444D01*
Y317765D01*
X1457342Y316993D01*
X1461569D01*
X1462776Y318200D01*
G01X1392657Y288900D02*
X1391300D01*
X1390500Y289700D01*
X1389350D01*
G01X1385850Y286700D02*
Y289700D01*
G01X1381431Y284259D02*
X1382090Y283600D01*
X1385850D01*
G01X1389350Y286700D02*
Y283600D01*
G01Y286700D02*
X1393242D01*
X1396027Y289485D01*
X1423577D01*
X1431858Y297766D01*
Y316817D01*
X1433241Y318200D01*
X1442841D01*
X1444852Y316189D01*
X1449963D01*
X1451606Y314546D01*
X1451753D01*
G01X1381780Y356848D02*
Y359580D01*
X1384350Y362150D01*
X1386400D01*
G01X1381780Y356848D02*
X1380097D01*
X1376027Y352778D01*
G01X1346800Y347800D02*
X1349700D01*
G01X1389900Y447400D02*
Y448400D01*
X1392500Y451000D01*
Y458000D01*
X1390400Y460100D01*
X1388360D01*
X1380260Y468200D01*
X1370771D01*
X1358710Y480261D01*
Y496400D01*
X1364310Y502000D01*
X1404950D01*
X1414310Y511360D01*
X1435010D01*
X1446270Y522620D01*
Y535916D01*
X1443937Y538249D01*
Y543363D01*
X1442006Y545294D01*
X1439123D01*
G01X1395100Y432500D02*
Y437150D01*
X1395075Y437175D01*
Y437314D01*
X1390294Y442095D01*
X1390155D01*
X1386600Y445650D01*
X1383850D01*
X1383000Y446500D01*
Y458740D01*
X1377090Y464650D01*
X1371322D01*
X1371321Y464649D01*
X1369251D01*
X1355160Y478740D01*
Y497872D01*
X1362838Y505550D01*
X1403430D01*
X1413530Y515650D01*
X1434089D01*
X1442720Y524281D01*
Y533590D01*
X1439822Y536488D01*
Y537382D01*
G01X1438799Y542785D02*
X1440525D01*
X1442162Y541148D01*
Y537513D01*
X1444495Y535180D01*
Y523545D01*
X1434085Y513135D01*
X1413574D01*
X1413399Y512960D01*
X1413351D01*
X1404166Y503775D01*
X1363574D01*
X1356935Y497136D01*
Y479476D01*
X1369986Y466425D01*
X1377826D01*
X1387500Y456751D01*
Y447400D01*
X1397150Y437750D01*
Y429300D01*
X1395350Y427500D01*
X1395100D01*
G01X1387907Y544286D02*
X1388500Y543693D01*
Y530242D01*
X1392450Y526292D01*
Y509050D01*
X1390984Y507584D01*
X1361684D01*
X1352650Y498550D01*
Y478527D01*
X1367138Y464039D01*
Y457362D01*
X1368500Y456000D01*
X1375777D01*
X1377800Y453977D01*
Y447448D01*
X1379844Y445404D01*
X1381046D01*
X1383060Y443390D01*
Y441320D01*
X1384210Y440170D01*
X1389496D01*
X1393150Y436516D01*
Y426977D01*
X1395227Y424900D01*
X1407345D01*
X1409671Y422574D01*
Y387129D01*
X1412260Y384540D01*
Y363600D01*
X1411160Y362500D01*
Y361041D01*
X1417851Y354350D01*
Y348859D01*
X1413476Y344484D01*
Y332224D01*
X1414868Y330832D01*
X1417909D01*
X1422553Y326188D01*
G01X1407200Y521500D02*
X1404296D01*
X1403027Y520231D01*
G01X1414800Y521400D02*
Y520220D01*
X1413248Y518668D01*
X1407424D01*
X1403828Y515072D01*
Y511528D01*
X1402950Y510650D01*
G01X1388841Y487323D02*
X1386241D01*
G01X1368941Y482123D02*
X1366641D01*
X1366341Y481823D01*
G01X1371041Y493023D02*
X1368741D01*
X1368441Y492723D01*
G01X1391341Y494223D02*
X1389341D01*
X1388741Y493623D01*
G01X1388841Y482923D02*
X1386541D01*
X1386241Y482623D01*
G01X1368841Y486523D02*
X1366404D01*
X1366309Y486618D01*
G01X1371041Y497423D02*
X1368541D01*
X1368441Y497523D01*
G01X1391341Y498523D02*
X1388941D01*
X1388719Y498745D01*
G01X1492000Y-15000D02*
X1487688Y-19312D01*
X1459700D01*
X1457000Y-16612D01*
Y-12200D01*
X1454100Y-9300D01*
X1449800D01*
X1447391Y-6891D01*
Y-1425D01*
X1445971Y-5D01*
Y6179D01*
X1452017Y12225D01*
Y16800D01*
G01D02*
X1448600Y20217D01*
Y21050D01*
G01X1452000Y-15000D02*
X1446566Y-9566D01*
Y-1767D01*
X1444632Y167D01*
Y6007D01*
X1450100Y11475D01*
Y15101D01*
X1446600Y18601D01*
Y26500D01*
X1448100Y28000D01*
X1455865D01*
X1463115Y20750D01*
X1464500D01*
G01X1457674Y16774D02*
X1455900Y15000D01*
Y10802D01*
X1458715Y7987D01*
Y548D01*
X1457600Y-567D01*
Y-10600D01*
X1462000Y-15000D01*
G01X1457674Y16774D02*
Y19026D01*
X1455650Y21050D01*
X1455100D01*
G01X1452000Y-5000D02*
X1457890Y890D01*
Y7645D01*
X1454800Y10735D01*
Y17850D01*
X1451600Y21050D01*
G01X1462000Y-5000D02*
X1465581Y-1419D01*
Y8282D01*
X1469864Y12565D01*
Y14736D01*
X1468000Y16600D01*
Y17100D01*
G01X1413800Y20200D02*
Y22275D01*
X1413375Y22700D01*
X1410144D01*
X1404300Y16856D01*
Y10800D01*
X1405100Y10000D01*
G01X1415400Y23730D02*
X1416800Y22330D01*
Y20200D01*
G01X1413721Y13139D02*
X1414900Y14318D01*
Y15600D01*
X1413800Y16700D01*
G01X1416871Y13139D02*
X1415725Y14285D01*
Y15625D01*
X1416800Y16700D01*
G01D02*
X1421400D01*
G01X1407422Y13139D02*
Y15823D01*
X1408299Y16700D01*
X1410800D01*
G01X1456790Y87112D02*
Y86840D01*
X1453700Y83750D01*
G01X1420337Y45477D02*
Y48377D01*
G01X1414091Y46412D02*
X1415902D01*
X1416837Y45477D01*
G01X1505673Y146346D02*
X1505617D01*
Y146116D01*
X1505216Y146517D01*
X1503716D01*
X1503502Y146303D01*
Y146195D01*
X1502440Y145133D01*
X1502332D01*
X1495149Y137950D01*
X1482578D01*
X1478872Y134244D01*
X1466144D01*
X1464800Y132900D01*
G01X1419511Y176559D02*
X1418370Y177700D01*
X1414757D01*
X1413557Y176500D01*
Y159343D01*
X1441764Y131136D01*
X1463036D01*
X1464800Y132900D01*
G01X1447428Y145543D02*
X1450371D01*
X1451233Y146405D01*
G01X1447391Y139229D02*
X1449167D01*
X1451227Y141289D01*
Y141261D01*
X1451228D01*
G01X1435500Y145400D02*
X1437900D01*
X1443300Y140000D01*
Y137904D01*
X1444400Y136804D01*
X1453142D01*
X1455851Y139513D01*
X1477496D01*
X1480244Y142261D01*
X1493483D01*
X1497574Y146352D01*
Y147187D01*
X1497813Y147426D01*
Y147980D01*
X1500979Y151146D01*
X1510625D01*
X1513279Y153800D01*
X1513500D01*
G01X1435500Y145400D02*
X1433477D01*
X1417798Y161079D01*
Y166133D01*
X1418224Y166559D01*
X1419511D01*
G01X1439451Y140149D02*
X1440700Y138900D01*
Y137010D01*
X1442802Y134908D01*
X1454550D01*
X1457479Y137837D01*
X1477203D01*
X1480723Y141357D01*
X1493746D01*
X1498921Y146532D01*
Y147651D01*
X1501331Y150061D01*
X1513676D01*
X1515358Y151743D01*
G01X1439451Y140149D02*
X1437561D01*
X1416957Y160753D01*
Y169594D01*
X1417422Y170059D01*
X1419511D01*
G01X1451590Y138750D02*
X1458850Y146010D01*
X1460354D01*
G01Y148569D02*
X1462238D01*
X1463017Y147790D01*
Y142849D01*
X1465428Y140438D01*
X1477112D01*
X1479860Y143186D01*
X1490998D01*
X1493100Y145288D01*
Y150400D01*
X1495200Y152500D01*
X1497638D01*
X1497685Y152453D01*
X1504498D01*
X1504545Y152500D01*
X1504616D01*
X1509197Y157081D01*
X1513136D01*
G01X1450250Y161330D02*
Y156974D01*
X1446576Y153300D01*
X1445500D01*
G01X1447391Y142729D02*
X1450166D01*
X1451198Y143761D01*
G01X1447391Y142729D02*
X1445271D01*
X1441600Y146400D01*
G01X1434581Y117098D02*
X1436550Y115129D01*
X1462307D01*
X1470579Y106857D01*
X1470728D01*
X1470729Y106856D01*
X1472263D01*
X1472264Y106857D01*
X1479786D01*
X1487885Y114956D01*
Y124455D01*
X1493831Y130401D01*
X1502024D01*
X1502622Y130999D01*
X1518506D01*
X1518514Y130991D01*
G01X1511660Y138510D02*
X1510224Y137074D01*
X1500277D01*
X1496123Y132920D01*
X1493551D01*
X1485955Y125324D01*
Y115644D01*
X1479018Y108707D01*
X1471496D01*
X1462115Y118088D01*
X1438310D01*
X1432842Y123556D01*
X1429044D01*
X1428000Y124600D01*
G01X1444500Y126600D02*
X1466877D01*
X1468755Y128478D01*
G01X1454079Y157468D02*
X1462132D01*
X1467354Y152246D01*
Y151128D01*
G01X1419511Y163559D02*
Y161771D01*
X1429863Y151419D01*
X1433500D01*
G01D02*
X1444818D01*
X1444986Y151587D01*
X1446795D01*
X1446808Y151600D01*
X1447281D01*
X1451950Y156269D01*
Y158551D01*
X1452849Y159450D01*
X1458583D01*
X1459045Y159912D01*
X1460577D01*
G01X1502000Y147500D02*
X1501689Y147189D01*
Y146895D01*
X1494444Y139650D01*
X1481421D01*
X1477908Y136137D01*
X1459199D01*
X1457572Y134510D01*
G01X1419511Y173059D02*
X1417920D01*
X1415257Y170396D01*
Y160048D01*
X1442273Y133032D01*
X1456094D01*
X1457572Y134510D01*
G01X1457000Y108500D02*
X1453232D01*
X1452232Y109500D01*
G01X1457694Y96494D02*
X1455839Y94639D01*
X1453809D01*
G01X1458569Y192143D02*
X1453359D01*
X1450719Y189503D01*
X1442893D01*
X1442891Y189505D01*
X1442870D01*
X1439949Y192426D01*
X1425241D01*
X1423031Y190216D01*
X1421476D01*
X1419511Y188251D01*
Y186059D01*
G01X1458908Y187699D02*
X1459392Y188183D01*
X1462059D01*
G01X1468300Y184400D02*
X1465942Y186758D01*
X1465234D01*
G01X1468300Y184400D02*
Y188403D01*
X1467368Y189335D01*
X1464409D01*
X1463257Y188183D01*
X1462059D01*
G01X1415712Y213300D02*
X1415480Y213068D01*
Y198571D01*
X1416739Y197312D01*
X1419650D01*
X1421714Y199376D01*
X1438199D01*
X1440663Y201840D01*
Y210487D01*
X1439090Y212060D01*
X1432750D01*
G01Y214620D02*
X1428176D01*
X1427500Y213944D01*
Y212610D01*
X1428050Y212060D01*
X1432750D01*
G01X1456250Y206940D02*
X1451589D01*
X1438111Y220418D01*
X1428254D01*
X1421663Y227009D01*
Y230362D01*
X1420148Y231877D01*
Y255099D01*
X1407200Y268047D01*
Y269600D01*
G01X1432750Y206940D02*
X1438094D01*
X1438765Y206269D01*
Y201346D01*
X1437720Y200301D01*
X1421253D01*
X1419189Y198237D01*
X1417153D01*
X1416500Y198890D01*
Y202624D01*
X1417963Y204087D01*
Y206280D01*
G01X1456250Y217180D02*
X1462870D01*
X1465610Y214440D01*
G01X1467992Y205635D02*
X1468576D01*
X1469730Y204481D01*
Y200060D01*
X1467951Y198281D01*
X1449821D01*
X1447070Y195530D01*
X1445390D01*
X1443284Y197636D01*
X1443263D01*
X1442441Y198458D01*
X1439115D01*
X1439108Y198451D01*
X1422269D01*
X1420205Y196387D01*
X1414401D01*
X1411950Y198838D01*
G01X1456250Y212060D02*
X1466590D01*
X1467992Y210658D01*
Y205635D01*
G01X1460577Y163412D02*
Y165077D01*
X1463150Y167650D01*
Y170457D01*
X1462200Y171407D01*
X1457838D01*
G01X1457043Y161495D02*
X1458960Y163412D01*
X1460577D01*
G01X1466188Y171277D02*
X1463498Y173967D01*
X1457838D01*
G01X1434338Y171407D02*
X1429784D01*
X1429154Y170777D01*
Y167712D01*
X1432600Y164266D01*
Y161300D01*
G01X1426261Y166809D02*
X1427346D01*
X1428918Y165237D01*
Y162950D01*
X1430568Y161300D01*
X1432600D01*
G01X1426261Y173309D02*
X1428817D01*
X1429475Y173967D01*
X1434338D01*
G01X1456159Y188296D02*
Y187299D01*
X1457838Y185620D01*
Y184207D01*
G01X1481962Y185067D02*
X1480333D01*
X1479222Y186178D01*
Y191750D01*
X1476822Y194150D01*
X1470550D01*
X1467344Y197356D01*
X1450205D01*
X1447454Y194605D01*
X1445006D01*
X1444294Y195317D01*
X1444273D01*
X1442057Y197533D01*
X1439499D01*
X1439492Y197526D01*
X1423126D01*
X1420916Y195316D01*
X1411584D01*
X1406050Y200850D01*
G01X1463900Y205550D02*
Y206800D01*
X1465650Y208550D01*
Y209350D01*
G01D02*
X1463000D01*
X1462850Y209500D01*
X1456250D01*
G01X1451366Y165296D02*
Y162446D01*
X1450250Y161330D01*
G01X1451386Y173499D02*
X1451289D01*
Y173402D01*
X1445500Y167613D01*
Y163300D01*
G01X1464077Y163412D02*
Y159912D01*
G01X1466800Y156800D02*
X1465400D01*
X1464077Y158123D01*
Y159912D01*
G01X1434338Y179087D02*
X1428713D01*
X1427991Y179809D01*
X1426261D01*
G01X1434338Y181647D02*
X1429453D01*
X1428291Y182809D01*
X1426261D01*
G01X1419511Y179559D02*
X1415140D01*
X1412200Y182499D01*
Y188460D01*
X1417356Y193616D01*
X1421621D01*
X1423831Y195826D01*
X1440197D01*
X1440204Y195833D01*
X1441352D01*
X1444280Y192905D01*
X1448159D01*
X1450910Y195656D01*
X1466044D01*
X1466400Y195300D01*
Y195243D01*
G01X1457838Y179087D02*
X1464287D01*
X1466600Y181400D01*
X1468300D01*
G01X1415800Y188600D02*
X1419116Y191916D01*
X1422326D01*
X1424536Y194126D01*
X1440654D01*
X1443575Y191205D01*
X1450016D01*
X1452767Y193956D01*
X1459786D01*
X1462059Y191683D01*
G01X1415800Y188600D02*
Y185311D01*
X1418052Y183059D01*
X1419511D01*
G01X1457838Y181647D02*
X1464527D01*
X1465234Y182354D01*
Y183258D01*
G01X1423011Y179559D02*
Y176559D01*
G01Y179559D02*
Y180228D01*
X1421944Y181295D01*
X1416505D01*
X1415819Y181981D01*
G01X1426261Y176309D02*
X1424621D01*
X1424371Y176559D01*
X1423011D01*
G01Y186059D02*
Y183059D01*
G01Y186059D02*
Y188921D01*
X1424050Y189960D01*
X1425443D01*
G01D02*
X1427605D01*
X1428030Y189535D01*
Y186734D01*
X1427605Y186309D01*
X1426261D01*
G01X1423011Y166559D02*
Y163559D01*
G01D02*
Y160845D01*
X1424756Y159100D01*
X1427100D01*
G01X1426261Y163309D02*
Y161951D01*
X1427100Y161112D01*
Y159100D01*
G01X1426261Y169809D02*
X1423261D01*
X1423011Y170059D01*
G01Y173059D02*
Y170059D01*
G01Y173059D02*
Y174387D01*
X1422607Y174791D01*
X1415985D01*
G01X1443000Y248750D02*
Y250820D01*
X1443700Y251520D01*
Y253769D01*
G01D02*
Y259202D01*
X1440331Y262571D01*
Y280651D01*
X1442889Y283209D01*
X1444664D01*
X1446257Y284802D01*
Y285987D01*
X1447979Y287709D01*
X1449360D01*
X1450867Y286202D01*
X1451753D01*
G01X1443700Y253769D02*
X1443715D01*
G01X1449919Y252409D02*
Y247982D01*
X1447187Y245250D01*
X1446000D01*
G01D02*
Y244088D01*
X1446942Y243146D01*
Y243058D01*
X1447163Y242837D01*
Y236378D01*
X1440225Y229440D01*
X1434750D01*
G01X1448603Y286202D02*
Y285298D01*
X1443939Y280634D01*
Y266387D01*
X1441905Y264353D01*
Y262700D01*
X1444933Y259672D01*
Y256645D01*
X1445955Y255623D01*
X1449585D01*
X1451858Y257896D01*
G01D02*
X1453937Y255817D01*
Y253811D01*
X1454500Y253248D01*
Y251250D01*
G01Y247750D02*
X1451502D01*
X1450413Y246661D01*
G01D02*
X1448800Y245048D01*
Y235991D01*
X1439689Y226880D01*
X1434750D01*
G01X1446000Y248750D02*
X1445354Y249396D01*
Y252262D01*
X1447726Y254634D01*
X1452066D01*
X1452200Y254500D01*
G01X1471250Y223500D02*
X1472675D01*
X1474287Y221888D01*
Y217351D01*
X1474462Y217176D01*
Y215457D01*
X1473705Y214700D01*
X1471000D01*
X1468600Y217100D01*
X1466001D01*
X1464508Y218593D01*
X1457707D01*
X1457496Y218804D01*
X1448024D01*
X1443929Y222899D01*
X1429580D01*
X1424013Y228466D01*
Y231337D01*
X1422498Y232852D01*
Y245598D01*
X1431100Y254200D01*
X1433700D01*
G01X1430365Y262624D02*
X1427200D01*
X1423475Y266349D01*
Y269600D01*
G01D02*
Y275901D01*
X1441607Y294033D01*
X1449202D01*
X1453300Y289935D01*
Y288822D01*
X1454278Y287844D01*
X1455526D01*
X1456500Y288818D01*
Y289930D01*
X1457452Y290882D01*
X1483761D01*
X1488562Y295683D01*
X1496052D01*
X1499723Y299354D01*
Y300106D01*
G01X1458500Y245500D02*
Y243163D01*
X1458337Y243000D01*
Y243019D01*
X1458318D01*
Y243000D01*
G01X1458500Y245500D02*
X1452550D01*
X1450128Y243078D01*
Y236582D01*
X1452150Y234560D01*
X1458250D01*
G01X1467750Y220000D02*
Y221392D01*
X1467305Y221837D01*
X1466476D01*
X1465800Y222513D01*
Y224068D01*
X1462988Y226880D01*
X1458250D01*
G01X1459548Y221731D02*
X1461379Y219900D01*
X1465600D01*
X1465700Y220000D01*
X1467750D01*
G01X1458250Y229440D02*
X1463599D01*
X1466039Y227000D01*
X1467750D01*
G01X1467229Y240547D02*
X1464847D01*
X1463980Y239680D01*
X1458250D01*
G01X1464340Y247410D02*
Y244730D01*
X1467229Y241841D01*
Y240547D01*
G01X1426905Y267045D02*
X1435800Y275940D01*
Y284977D01*
X1436812Y285989D01*
G01X1440000Y248750D02*
Y250050D01*
X1437923Y252127D01*
Y253625D01*
X1436137Y255411D01*
Y258989D01*
X1437923Y260775D01*
Y269627D01*
G01D02*
Y283424D01*
X1442342Y287843D01*
X1442928D01*
X1443910Y288825D01*
Y290043D01*
X1444864Y290997D01*
X1449088D01*
X1450224Y289861D01*
Y288749D01*
X1451264Y287709D01*
X1452377D01*
X1453260Y286826D01*
Y284559D01*
X1451754Y283053D01*
G01X1458011Y264408D02*
X1455817D01*
X1454056Y266169D01*
G01X1438500Y255400D02*
X1438700D01*
X1441600Y258300D01*
G01X1469330Y249069D02*
X1467001D01*
X1465850Y250220D01*
X1464374D01*
X1462377Y248223D01*
Y246597D01*
X1463110Y245864D01*
Y243760D01*
X1460670Y241320D01*
X1453953D01*
X1453287Y240654D01*
Y237413D01*
X1453580Y237120D01*
X1458250D01*
G01X1434750Y234560D02*
X1439840D01*
X1440350Y234050D01*
X1442550D01*
X1443590Y235090D01*
Y239090D01*
X1443000Y239680D01*
Y245250D01*
G01X1434750Y234560D02*
X1425477D01*
X1425304Y234733D01*
G01X1425469Y239829D02*
X1428178Y237120D01*
X1434750D01*
G01X1440000Y245250D02*
Y238570D01*
X1438550Y237120D01*
X1434750D01*
G01X1448603Y267304D02*
Y265413D01*
X1449497Y264519D01*
G01X1448603Y270454D02*
X1447096Y268947D01*
Y266680D01*
X1447345Y266431D01*
Y260523D01*
G01X1457835Y261026D02*
X1460835D01*
G01X1462950Y267913D02*
Y264073D01*
X1460835Y261958D01*
Y261026D01*
G01X1461202Y273603D02*
X1462950Y271855D01*
Y267913D01*
G01X1454350Y262200D02*
Y262576D01*
X1450246Y266680D01*
Y267928D01*
X1451129Y268811D01*
X1451184D01*
X1451237Y268864D01*
X1451938D01*
X1452021Y268947D01*
X1452377D01*
X1453260Y269830D01*
Y270186D01*
X1453286Y270212D01*
Y281436D01*
X1454902Y283052D01*
G01X1458052Y276753D02*
X1459559Y275246D01*
X1464985D01*
X1467743Y272488D01*
Y268120D01*
X1467498Y267875D01*
Y265943D01*
X1468846Y264595D01*
Y256258D01*
X1470328Y254776D01*
X1471372D01*
X1472613Y253535D01*
Y251295D01*
X1474108Y249800D01*
X1476600D01*
X1477188Y249212D01*
X1479655D01*
X1481039Y250596D01*
X1483552D01*
X1484011Y250137D01*
X1485600D01*
X1486631Y251168D01*
X1495845D01*
X1497857Y253180D01*
X1499560D01*
X1501275Y254895D01*
Y271607D01*
X1496558Y276324D01*
X1496473D01*
X1492093Y280704D01*
Y282903D01*
X1495021Y285831D01*
Y289573D01*
X1502648Y297200D01*
X1517463D01*
X1527913Y286750D01*
Y286626D01*
X1529425Y285114D01*
X1529549D01*
X1531619Y283044D01*
X1538369D01*
X1544845Y289520D01*
X1547432D01*
X1560702Y276250D01*
X1562333D01*
X1562334Y276251D01*
X1562995D01*
X1564829Y274417D01*
X1568049D01*
X1574944Y267522D01*
X1587978D01*
X1597265Y258235D01*
X1610052D01*
X1619852Y248435D01*
X1629347D01*
X1637844Y239938D01*
X1651376D01*
X1654760Y236554D01*
X1655821D01*
G01X1444948Y264505D02*
X1445454Y265011D01*
Y267304D01*
G01X1465904Y271083D02*
Y272395D01*
X1464623Y273676D01*
X1464424D01*
G01X1465904Y271083D02*
Y267672D01*
X1464233Y266001D01*
Y263767D01*
X1464500Y263500D01*
Y262100D01*
G01X1458011Y267908D02*
X1456836D01*
X1454902Y269842D01*
Y270454D01*
G01X1439700Y300400D02*
Y302494D01*
X1442304Y305098D01*
G01X1505935Y306674D02*
X1501584D01*
X1499266Y308992D01*
X1494692D01*
X1489155Y303455D01*
X1485773D01*
X1484890Y302572D01*
Y298310D01*
X1483736Y297156D01*
X1482623D01*
X1481740Y296273D01*
Y295160D01*
X1478287Y291707D01*
X1456807D01*
X1456200Y291100D01*
X1453999D01*
X1450095Y295004D01*
Y296407D01*
X1449346Y297156D01*
X1444708D01*
X1443265Y295713D01*
X1441509D01*
X1427535Y281739D01*
X1423407D01*
G01X1405392Y284022D02*
X1407675Y281739D01*
X1423407D01*
G01X1436812Y285989D02*
X1441723Y290900D01*
X1443430D01*
X1445056Y292526D01*
X1445427D01*
G01X1432344Y289437D02*
X1440134Y297227D01*
X1442862D01*
X1443810Y298175D01*
Y299285D01*
X1444830Y300305D01*
X1452468D01*
X1453314Y299459D01*
Y297912D01*
X1453957Y297269D01*
X1455766D01*
X1456546Y296489D01*
Y296274D01*
X1456545Y296273D01*
Y295025D01*
X1459003Y292567D01*
X1475997D01*
X1478550Y295120D01*
Y300400D01*
X1480098Y301948D01*
G01X1410990Y334390D02*
X1410489Y334891D01*
Y337988D01*
G01X1438958Y329999D02*
X1442836Y326121D01*
X1445098D01*
X1447377Y323842D01*
X1465187D01*
X1466008Y323021D01*
X1468851D01*
X1469422Y323592D01*
X1470946D01*
X1471920Y322618D01*
Y321212D01*
X1471624Y320916D01*
Y318851D01*
X1472248Y318227D01*
Y313593D01*
X1472887Y312954D01*
X1474501D01*
X1475400Y312055D01*
Y306646D01*
X1476948Y305098D01*
G01X1438958Y329999D02*
X1435357Y333600D01*
X1417900D01*
X1416000Y335500D01*
G01X1461202Y314546D02*
X1460354D01*
X1458800Y316100D01*
X1454018D01*
X1453260Y315342D01*
Y313686D01*
X1452524Y312950D01*
X1448006D01*
X1445876Y315080D01*
X1443150D01*
G01D02*
X1443130Y315100D01*
X1438200D01*
G01X1464476Y315500D02*
Y313976D01*
X1462800Y312300D01*
Y309797D01*
X1464350Y308247D01*
G01X1443400Y285700D02*
X1444400D01*
X1448051Y289351D01*
X1448603D01*
G01X1464351Y311397D02*
X1467700D01*
G01X1470649D02*
X1470405D01*
X1466402Y315400D01*
Y316598D01*
X1465300Y317700D01*
Y321849D01*
X1464257Y322892D01*
X1461512D01*
X1460650Y322030D01*
X1432119D01*
X1431304Y321215D01*
X1427526D01*
X1422553Y326188D01*
G01X1444311Y324366D02*
X1434535D01*
X1431194Y327707D01*
G01D02*
X1426801Y332100D01*
X1416800D01*
X1416000Y332900D01*
G01X1467613Y306048D02*
X1465156Y303591D01*
X1463727D01*
X1462844Y304474D01*
Y305722D01*
X1461875Y306691D01*
X1460479D01*
X1459695Y307475D01*
Y308939D01*
X1458826Y309808D01*
X1454007D01*
X1450804Y306605D01*
X1441505D01*
X1440300Y305400D01*
X1439000D01*
G01X1435500Y308400D02*
Y305400D01*
G01D02*
Y295653D01*
X1434624Y294777D01*
G01X1435500Y311400D02*
Y312800D01*
X1435763Y313063D01*
X1445919D01*
X1447096Y311886D01*
Y310773D01*
X1447979Y309890D01*
X1452377D01*
X1453300Y310813D01*
Y311926D01*
X1454278Y312904D01*
X1458676D01*
X1459600Y311980D01*
Y310866D01*
X1463726Y306740D01*
X1464974D01*
X1465857Y307623D01*
Y308500D01*
X1466832Y309475D01*
X1468483D01*
X1468898Y309890D01*
X1471273D01*
X1472156Y310773D01*
Y312021D01*
X1471273Y312904D01*
X1470160D01*
X1469142Y313922D01*
Y315170D01*
X1469151Y315179D01*
Y317550D01*
X1469801Y318200D01*
G01X1439000Y311400D02*
Y308400D01*
G01D02*
X1440274D01*
X1441714Y309840D01*
X1443930D01*
G01D02*
X1446160D01*
X1447753Y308247D01*
X1448603D01*
G01X1416000Y338100D02*
X1425828Y347928D01*
G01X1456900Y387600D02*
X1460700D01*
X1461220Y387080D01*
X1471742D01*
X1472666Y386156D01*
X1477078D01*
X1482992Y392070D01*
X1485566D01*
X1486961Y393465D01*
Y394419D01*
X1488563Y396021D01*
X1491768D01*
X1493375Y394414D01*
G01X1489475D02*
Y393559D01*
X1484536Y388620D01*
X1483022D01*
X1482811Y388831D01*
X1480967D01*
X1478730Y386594D01*
Y382570D01*
X1477560Y381400D01*
X1474619D01*
X1473610Y382409D01*
X1471283D01*
X1469887Y381013D01*
X1465273D01*
X1465050Y380790D01*
X1462302D01*
X1460154Y382938D01*
G01X1456981Y384569D02*
X1458612Y382938D01*
X1460154D01*
G01X1453811Y369748D02*
Y369322D01*
X1457042Y366091D01*
X1462556D01*
X1464327Y364320D01*
X1466565D01*
X1466908Y364663D01*
X1470850D01*
X1471413Y365226D01*
Y366747D01*
X1475466Y370800D01*
X1477800D01*
G01X1460868Y373393D02*
X1462306D01*
X1463921Y371778D01*
X1469000D01*
X1470600Y373378D01*
Y378000D01*
X1471388Y378788D01*
X1479807D01*
X1482734Y381715D01*
G01X1460868Y373393D02*
Y374842D01*
X1457818Y377892D01*
X1456167D01*
X1454814Y379245D01*
G01X1463617Y357259D02*
X1463809D01*
X1464050Y357500D01*
X1466700D01*
G01X1413400Y361300D02*
X1429100D01*
G01D02*
X1429700Y360700D01*
X1456000D01*
G01X1453064Y362601D02*
X1453082Y362583D01*
X1457613D01*
X1458517Y361679D01*
Y359792D01*
X1462747Y355562D01*
X1469121D01*
X1470200Y356641D01*
Y357500D01*
G01X1469000Y345850D02*
X1467666D01*
X1462100Y351416D01*
Y353700D01*
X1461120Y354680D01*
X1457821D01*
X1453951Y358550D01*
X1436450D01*
X1425828Y347928D01*
G01X1464400Y382720D02*
X1465550Y383870D01*
X1468190D01*
G01X1416600Y524500D02*
X1412753D01*
X1409753Y521500D01*
X1407200D01*
G01X1417800D02*
X1417610D01*
X1413753Y517643D01*
X1407972D01*
X1404910Y514581D01*
Y511690D01*
X1405950Y510650D01*
G01X1438390Y527175D02*
Y523692D01*
X1432698Y518000D01*
X1424600D01*
X1424116Y518484D01*
G01D02*
X1422000Y520600D01*
Y523700D01*
G01X1439822Y537382D02*
X1437529Y539675D01*
Y539986D01*
X1436060Y541455D01*
G01X1438799Y542785D02*
X1436629Y544955D01*
X1436060D01*
G01X1419600Y531500D02*
X1416600Y528500D01*
Y528000D01*
G01X1425600Y527200D02*
X1422000D01*
G01X1423800Y534800D02*
X1422000Y533000D01*
Y527200D01*
G01X1519580Y81313D02*
X1515370D01*
X1513263Y79206D01*
Y41263D01*
X1509500Y37500D01*
Y31900D01*
G01X1473886Y35185D02*
X1480571Y28500D01*
X1495800D01*
X1497563Y26737D01*
Y5165D01*
X1506107Y-3379D01*
X1512087D01*
X1516141Y675D01*
X1533479D01*
X1545000Y-10846D01*
Y-15000D01*
G01X1471500Y20750D02*
Y19119D01*
X1473550Y17069D01*
Y14150D01*
G01D02*
Y13449D01*
X1466406Y6305D01*
Y-1200D01*
X1466800Y-1594D01*
Y-6953D01*
X1469511Y-9664D01*
X1487336D01*
X1492000Y-5000D01*
G01X1531200Y9659D02*
X1533295D01*
X1533900Y9054D01*
Y5825D01*
X1533375Y5300D01*
X1516200D01*
X1514400Y3500D01*
G01X1517200Y12200D02*
X1520500D01*
X1522195Y10505D01*
X1527979D01*
X1528825Y9659D01*
X1531200D01*
G01X1627250Y17000D02*
Y14950D01*
X1629163Y13037D01*
Y9404D01*
X1627335Y7576D01*
Y6074D01*
X1628063Y5346D01*
Y-5950D01*
X1621904Y-12109D01*
Y-14496D01*
X1617391Y-19009D01*
X1553475D01*
X1549550Y-15084D01*
Y-14087D01*
X1533863Y1600D01*
X1516568D01*
X1516567Y1601D01*
X1515758D01*
X1511703Y-2454D01*
X1506491D01*
X1498488Y5549D01*
Y23988D01*
X1500300Y25800D01*
X1506300D01*
X1511900Y31400D01*
Y34100D01*
G01X1509400Y3500D02*
X1507371Y1471D01*
X1503875D01*
X1499413Y5933D01*
Y23604D01*
X1500684Y24875D01*
X1506684D01*
X1516017Y34208D01*
Y38841D01*
G01X1521900Y27500D02*
Y37082D01*
X1517379Y41603D01*
Y71167D01*
X1521987Y75775D01*
Y83479D01*
X1525181Y86673D01*
X1530137D01*
X1533133Y83677D01*
X1540587D01*
X1543340Y86430D01*
Y88810D01*
X1544560Y90030D01*
X1545180D01*
X1545917Y90767D01*
Y98703D01*
X1535061Y109559D01*
G01X1569553Y32168D02*
X1568685Y31300D01*
X1537838D01*
X1531520Y24982D01*
Y21170D01*
X1528970Y18620D01*
X1524137D01*
X1521092Y21665D01*
G01X1468000Y17100D02*
Y20750D01*
G01X1524154Y28918D02*
X1524144D01*
Y36359D01*
X1518304Y42199D01*
Y61714D01*
X1521741Y65151D01*
G01X1515000Y-3242D02*
Y-15000D01*
G01X1525000D02*
Y-1587D01*
G01X1511900Y3500D02*
X1510200Y5200D01*
Y7082D01*
G01X1511900Y3500D02*
Y1100D01*
X1510500Y-300D01*
G01X1531200Y12218D02*
X1528482D01*
X1524000Y16700D01*
X1511100D01*
X1510200Y15800D01*
Y12200D01*
G01X1505400Y12541D02*
X1507159D01*
X1507500Y12200D01*
X1510200D01*
G01X1524200Y7100D02*
X1520700D01*
G01X1517200Y7082D02*
X1513700D01*
G01X1470862Y38209D02*
X1473886Y35185D01*
G01X1517162Y78784D02*
X1514688Y76310D01*
Y40672D01*
X1511900Y37884D01*
Y34100D01*
G01X1516017Y38841D02*
Y74583D01*
X1520314Y78880D01*
G01X1545250Y88360D02*
Y86929D01*
X1540956Y82635D01*
X1532866D01*
X1529753Y85748D01*
X1525565D01*
X1522912Y83095D01*
Y66322D01*
X1521741Y65151D01*
G01X1526000Y64500D02*
Y74540D01*
X1528630Y77170D01*
X1529820D01*
X1531137Y78487D01*
Y79279D01*
X1532638Y80780D01*
X1536125D01*
X1537030Y79875D01*
Y75453D01*
X1539299Y73184D01*
G01X1527233Y57198D02*
Y60767D01*
X1526000Y62000D01*
Y64500D01*
G01X1520904Y51355D02*
Y60941D01*
X1523844Y63881D01*
Y82714D01*
X1525760Y84630D01*
X1529560D01*
X1532480Y81710D01*
X1542364D01*
X1543119Y80955D01*
X1544784D01*
X1544814Y80985D01*
G01X1520887Y44028D02*
X1520904Y44045D01*
Y47855D01*
G01X1520887Y44028D02*
X1523865D01*
X1525204Y45367D01*
X1531959D01*
X1532353Y44973D01*
Y41018D01*
G01X1473354Y151039D02*
Y153246D01*
G01X1485210Y134837D02*
X1483655D01*
X1479138Y130320D01*
G01X1490178Y112315D02*
Y111282D01*
X1486193Y107297D01*
G01X1510184Y142614D02*
X1508514D01*
X1505405Y139505D01*
X1500083D01*
X1495530Y134952D01*
X1492965D01*
X1483913Y125900D01*
X1481729D01*
X1477734Y121905D01*
Y120154D01*
X1474105Y116525D01*
X1471135D01*
X1468635Y119025D01*
G01X1489000Y135955D02*
X1495002D01*
X1501533Y142486D01*
X1503466D01*
G01X1484800Y157800D02*
X1486900Y155700D01*
X1489200D01*
X1492066Y152834D01*
X1493069D01*
G01X1480354Y148479D02*
X1482591D01*
X1483017Y148905D01*
Y151899D01*
X1484842Y153724D01*
X1488226D01*
X1489252Y152698D01*
Y152111D01*
G01X1480354Y148479D02*
Y145919D01*
G01X1485150Y148500D02*
Y149952D01*
X1486338Y151140D01*
X1488281D01*
X1489252Y152111D01*
G01X1508700Y112400D02*
X1512930D01*
X1513879Y113349D01*
G01X1473354Y148479D02*
X1471925D01*
X1469276Y151128D01*
X1467354D01*
G01X1524284Y112773D02*
X1531853D01*
X1535061Y109565D01*
Y109559D01*
G01X1480988Y170177D02*
X1482651D01*
X1483300Y169528D01*
Y163701D01*
X1487001Y160000D01*
X1489703D01*
X1490327Y159376D01*
Y159164D01*
X1492013Y157478D01*
Y155610D01*
G01X1535338Y141386D02*
X1533117D01*
X1529652Y144851D01*
X1520305D01*
X1518936Y146220D01*
Y152527D01*
X1518937Y152528D01*
Y154062D01*
X1518936Y154063D01*
Y155151D01*
X1514120Y159967D01*
X1498433D01*
X1495577Y157111D01*
X1494975D01*
X1492027Y160059D01*
Y160081D01*
X1491025Y161083D01*
Y164284D01*
X1489100Y166209D01*
Y168500D01*
G01X1526337Y136439D02*
X1528480D01*
X1529449Y137408D01*
G01X1489780Y105820D02*
X1489098Y105138D01*
X1488302D01*
X1486961Y103797D01*
X1486193D01*
G01D02*
X1482397D01*
X1481100Y102500D01*
G01X1481300Y96900D02*
X1484218Y99818D01*
X1485546D01*
X1489053Y103325D01*
G01X1522837Y136439D02*
Y135563D01*
X1524744Y133656D01*
G01X1510298Y170328D02*
X1513522D01*
X1514250Y169600D01*
X1522539D01*
X1524561Y171622D01*
Y173360D01*
X1525313Y174112D01*
X1528065D01*
G01X1497600Y172250D02*
X1502100D01*
X1502151Y172199D01*
X1508199D01*
X1508750Y172750D01*
Y174000D01*
G01D02*
X1510413D01*
X1510866Y173547D01*
Y170896D01*
X1510298Y170328D01*
G01X1497600Y172250D02*
X1496251D01*
X1495185Y173316D01*
Y173709D01*
X1493670Y175224D01*
X1491300D01*
X1490837Y175687D01*
Y178010D01*
X1489015Y179832D01*
G01X1522479Y179889D02*
X1522690Y180100D01*
X1563897D01*
X1565067Y181270D01*
X1566486D01*
G01X1528065Y176672D02*
X1525708D01*
X1523136Y174100D01*
Y172213D01*
X1521523Y170600D01*
X1515650D01*
X1513700Y172550D01*
Y175770D01*
X1510018Y179452D01*
Y185193D01*
X1511100Y186275D01*
G01X1488900Y172576D02*
X1489504D01*
X1494080Y168000D01*
X1512500D01*
X1517075Y163425D01*
X1522909D01*
X1525003Y165519D01*
X1533497D01*
X1534716Y164300D01*
X1535065D01*
G01X1473942Y190269D02*
Y187269D01*
G01X1471800Y181400D02*
X1474008D01*
X1474883Y182275D01*
G01D02*
X1473942Y183216D01*
Y187269D01*
G01X1499000Y186570D02*
Y189000D01*
X1498500Y189500D01*
X1496500D01*
X1494200Y191800D01*
X1487700D01*
X1484425Y195075D01*
X1474925D01*
X1472400Y197600D01*
Y204009D01*
X1472887Y204496D01*
G01X1541628Y176772D02*
X1538992D01*
X1538656Y177108D01*
Y178135D01*
X1538318Y178473D01*
X1525121D01*
X1521711Y175063D01*
Y172804D01*
X1520932Y172025D01*
X1516241D01*
X1515125Y173141D01*
Y175788D01*
X1511319Y179594D01*
Y184011D01*
X1512815Y185507D01*
Y187186D01*
X1511796Y188205D01*
X1503705D01*
X1502070Y186570D01*
X1499000D01*
G01X1472887Y204496D02*
X1474439Y206048D01*
Y207621D01*
G01X1477500Y219350D02*
X1479219Y217631D01*
Y212737D01*
X1481206Y210750D01*
X1484750D01*
G01X1516616Y205537D02*
X1514615D01*
X1513352Y206800D01*
X1511700D01*
X1510650Y205750D01*
X1506250D01*
G01X1516750Y215000D02*
Y217098D01*
X1515848Y218000D01*
X1513900D01*
G01D02*
X1512004D01*
X1509754Y215750D01*
X1506250D01*
G01X1465610Y214440D02*
X1468200Y211850D01*
X1469700D01*
G01X1488300Y158300D02*
X1488137Y158463D01*
X1487037D01*
X1483883Y161617D01*
X1481500D01*
G01D02*
X1480029Y163088D01*
X1476623D01*
G01X1477988Y170177D02*
Y172388D01*
X1477388Y172988D01*
G01X1476623Y160088D02*
X1478286D01*
X1478386Y159988D01*
X1479112D01*
X1481400Y157700D01*
X1484700D01*
X1484800Y157800D01*
G01X1474988Y170177D02*
Y172621D01*
X1473888Y173721D01*
G01X1516000Y189200D02*
X1514683Y190517D01*
X1513516D01*
X1512978Y191055D01*
X1512945D01*
X1512944Y191056D01*
X1509544D01*
X1506750Y193850D01*
X1498148D01*
X1495100Y196898D01*
Y199201D01*
X1493401Y200900D01*
X1490600D01*
X1490450Y200750D01*
X1484750D01*
G01X1535425Y188016D02*
Y185726D01*
X1533589Y183890D01*
X1517241D01*
X1515665Y185466D01*
Y187164D01*
X1516000Y187499D01*
Y189200D01*
G01X1523400Y212400D02*
X1525400Y214400D01*
Y221776D01*
X1526848Y223224D01*
Y224896D01*
X1527870Y225918D01*
X1530426D01*
X1531935Y224409D01*
Y224160D01*
G01X1523400Y212400D02*
Y212050D01*
X1518550Y207200D01*
X1515300D01*
X1514500Y208000D01*
Y209750D01*
X1513500Y210750D01*
X1506250D01*
G01Y203250D02*
X1510850D01*
X1512700Y205100D01*
G01X1484750Y208250D02*
X1480025D01*
X1479000Y207225D01*
G01X1508750Y177000D02*
Y178000D01*
X1506000Y180750D01*
Y181450D01*
G01D02*
X1507950D01*
X1508500Y182000D01*
Y183500D01*
X1507990Y184010D01*
X1506000D01*
G01X1488300Y161700D02*
Y162408D01*
X1484700Y166008D01*
Y170200D01*
X1487237Y172737D01*
Y173265D01*
X1487300Y173328D01*
Y183000D01*
X1485500Y184800D01*
Y186450D01*
X1484324Y187626D01*
X1481962D01*
G01X1498022Y221900D02*
X1497359Y221237D01*
X1496041D01*
X1495406Y220602D01*
Y214404D01*
X1494981Y213979D01*
X1493322D01*
X1492700Y213357D01*
Y212476D01*
X1493322Y211854D01*
X1497428D01*
X1498050Y211232D01*
Y210351D01*
X1497428Y209729D01*
X1493322D01*
X1492700Y209107D01*
Y208226D01*
X1493322Y207604D01*
X1497428D01*
X1498050Y206982D01*
Y198698D01*
X1499911Y196837D01*
X1513037D01*
X1518400Y202200D01*
Y205000D01*
X1522049Y208649D01*
X1522651D01*
X1524399Y206901D01*
Y206299D01*
X1521900Y203800D01*
Y201400D01*
X1518000Y197500D01*
Y194500D01*
G01X1494000Y194000D02*
X1495050D01*
X1496650Y192400D01*
X1505600D01*
X1508370Y189630D01*
X1512387D01*
X1514240Y187777D01*
Y184543D01*
X1516318Y182465D01*
X1560578D01*
X1561200Y183087D01*
Y183968D01*
X1560578Y184590D01*
X1546625D01*
X1546200Y185015D01*
Y186290D01*
X1546625Y186715D01*
X1561985D01*
X1562780Y185920D01*
X1567299D01*
G01X1506250Y208250D02*
X1511831D01*
X1512525Y208944D01*
G01X1522717Y221027D02*
X1520890Y219200D01*
X1516409D01*
X1515009Y220600D01*
X1505151D01*
X1501000Y216449D01*
Y208898D01*
X1501648Y208250D01*
X1506250D01*
G01X1484750Y198250D02*
X1491261D01*
X1492136Y199125D01*
G01X1498478Y233675D02*
X1496656Y231853D01*
Y227170D01*
X1496637Y227151D01*
Y227036D01*
X1493860Y224259D01*
Y216560D01*
X1491100Y213800D01*
Y207800D01*
X1489050Y205750D01*
X1484750D01*
G01X1490500Y194000D02*
X1488072D01*
X1485572Y196500D01*
X1476500D01*
X1475564Y197436D01*
Y200130D01*
G01D02*
Y203664D01*
X1477300Y205400D01*
X1479550D01*
X1479900Y205750D01*
X1484750D01*
G01X1506250Y200750D02*
X1501750D01*
X1500700Y201800D01*
Y207100D01*
X1499500Y208300D01*
Y216965D01*
X1504635Y222100D01*
X1515700D01*
X1516584Y221216D01*
X1517608D01*
G01X1516598Y203037D02*
X1515561Y202000D01*
X1511650D01*
X1510400Y200750D01*
X1506250D01*
G01X1510638Y166240D02*
Y165862D01*
X1514500Y162000D01*
X1523500D01*
X1525594Y164094D01*
X1532906D01*
X1536000Y161000D01*
X1538500D01*
X1541500Y164000D01*
X1542000D01*
X1544500Y166500D01*
X1552400D01*
X1553500Y165400D01*
G01X1516872Y208863D02*
Y209527D01*
X1516168Y210231D01*
Y210831D01*
X1517267Y211931D01*
Y212531D01*
X1516664Y213134D01*
X1516064D01*
X1514965Y212034D01*
X1514365D01*
X1513149Y213250D01*
X1506250D01*
G01X1488962Y190185D02*
X1493315D01*
X1496000Y187500D01*
Y185450D01*
X1497440Y184010D01*
X1499000D01*
G01X1518979Y179889D02*
X1515968D01*
X1513779Y182078D01*
G01X1518798Y174078D02*
Y176441D01*
X1518979Y176622D01*
Y179889D01*
G01X1523500Y189000D02*
Y192800D01*
X1524400Y193700D01*
Y198675D01*
X1523975Y199100D01*
X1523000D01*
G01X1523500Y186000D02*
X1525420D01*
X1525500Y185920D01*
X1530149D01*
G01X1523500Y186000D02*
Y189000D01*
G01X1523000Y199100D02*
X1521925D01*
X1521500Y198675D01*
Y194500D01*
G01X1470223Y156988D02*
X1470035Y156800D01*
X1466800D01*
G01X1470223Y156988D02*
Y157924D01*
X1472387Y160088D01*
X1473123D01*
G01Y163088D02*
Y160088D01*
G01X1480988Y166677D02*
X1477988D01*
G01X1474988D02*
X1477988D01*
G01X1471988D02*
X1474988D01*
G01X1470500Y163700D02*
Y161900D01*
X1469800Y161200D01*
X1467288D01*
X1466188Y162300D01*
Y167777D01*
G01X1470500Y163700D02*
Y165189D01*
X1471988Y166677D01*
G01X1484750Y203250D02*
X1488650D01*
X1491300Y205900D01*
X1494100D01*
X1496550Y203450D01*
Y197626D01*
X1498786Y195390D01*
X1512118D01*
X1515060Y192448D01*
Y192443D01*
G01X1466400Y195243D02*
X1469193Y192450D01*
X1475851D01*
X1477442Y190859D01*
Y190269D01*
G01X1471250Y227000D02*
Y229369D01*
X1470950Y229669D01*
G01X1467750Y227000D02*
Y223500D01*
G01X1526150Y234300D02*
X1526600D01*
X1527024Y233876D01*
X1542868D01*
X1544877Y235885D01*
X1553037D01*
X1554667Y234255D01*
X1561104D01*
G01X1498387Y264666D02*
Y266322D01*
X1497044Y267665D01*
X1496030D01*
G01X1490310Y261140D02*
X1493450D01*
G01D02*
X1497456D01*
X1498387Y262071D01*
Y264666D01*
G01X1506950Y239750D02*
X1510420D01*
X1513170Y237000D01*
X1515250D01*
G01X1509814Y247215D02*
X1511956Y245073D01*
Y243257D01*
X1513451Y241762D01*
X1513479D01*
X1514453Y240788D01*
Y239807D01*
X1515555Y238705D01*
X1518095D01*
X1518750Y238050D01*
Y237000D01*
G01D02*
X1521560Y234190D01*
X1522210D01*
G01X1515312Y231532D02*
Y228149D01*
X1516450Y227011D01*
G01X1515312Y231532D02*
X1513414D01*
X1512696Y232250D01*
X1506950D01*
G01X1516549Y234278D02*
X1518107D01*
X1518812Y233573D01*
Y231532D01*
G01X1511440Y250974D02*
X1509373D01*
X1508100Y249701D01*
Y246814D01*
X1504953Y243667D01*
X1501740D01*
X1495231Y237158D01*
Y227874D01*
X1487765Y220408D01*
X1480782D01*
X1480090Y221100D01*
Y222360D01*
X1479600Y222850D01*
X1477500D01*
G01X1511440Y250974D02*
X1514610D01*
X1516203Y249381D01*
Y241066D01*
X1516613Y240656D01*
G01X1536000Y260500D02*
Y258041D01*
X1535318Y257359D01*
X1532976D01*
X1529147Y253530D01*
X1523070D01*
X1519400Y257200D01*
G01X1521962Y278650D02*
X1519400Y276088D01*
Y268480D01*
G01D02*
Y257200D01*
G01X1512790Y240099D02*
X1512551D01*
X1511500Y241150D01*
Y241151D01*
X1510401Y242250D01*
X1506950D01*
G01X1507003Y272249D02*
X1506340Y271586D01*
Y270340D01*
X1505500Y269500D01*
G01X1518006Y286706D02*
X1520632Y284080D01*
X1521120D01*
X1525800Y279400D01*
Y277300D01*
X1526508Y276592D01*
X1538724D01*
X1540086Y275230D01*
X1544781D01*
X1553051Y266960D01*
X1559146D01*
X1560977Y265129D01*
X1563154D01*
X1563155Y265128D01*
X1564198D01*
X1570100Y259226D01*
Y255224D01*
X1571737Y253587D01*
Y252599D01*
X1574033Y250303D01*
Y245644D01*
X1586977Y232700D01*
X1588041D01*
X1588152Y232589D01*
X1595695D01*
X1595806Y232700D01*
X1619409D01*
X1623284Y228825D01*
X1634984D01*
X1641634Y222175D01*
X1644055D01*
X1655231Y210999D01*
X1656895D01*
X1660661Y207233D01*
X1668137D01*
X1669579Y205791D01*
X1673729D01*
X1675756Y207818D01*
X1680893D01*
X1685245Y203466D01*
X1685296D01*
X1685802Y202960D01*
X1707750D01*
X1710960Y199750D01*
X1713736D01*
X1716191Y197295D01*
Y188465D01*
X1717406Y187250D01*
X1839000D01*
G01X1542690Y236050D02*
Y237063D01*
X1540851Y238902D01*
X1527168D01*
X1526159Y239911D01*
X1522365D01*
X1520768Y241508D01*
X1518509D01*
X1517636Y242381D01*
Y244475D01*
X1517628Y244483D01*
Y249972D01*
X1514264Y253336D01*
X1508485D01*
X1501309Y246160D01*
X1488192D01*
X1488189Y246163D01*
X1486811D01*
X1486808Y246160D01*
X1484217D01*
X1484146Y246231D01*
X1481547D01*
X1480416Y247362D01*
X1476420D01*
X1475832Y247950D01*
X1472432D01*
X1471313Y249069D01*
X1469330D01*
G01X1473798Y279902D02*
X1475305Y281409D01*
X1477438D01*
X1478456Y282427D01*
Y286691D01*
X1479474Y287709D01*
X1487069D01*
X1487904Y286874D01*
Y285282D01*
X1489102Y284084D01*
Y281645D01*
X1488039Y280582D01*
Y279278D01*
X1488922Y278395D01*
X1491746D01*
X1495000Y275141D01*
Y273001D01*
X1500350Y267651D01*
Y261863D01*
X1496848Y258361D01*
X1495696D01*
G01X1523150Y248700D02*
Y246586D01*
X1521807Y245243D01*
Y241891D01*
X1522781Y240917D01*
X1524159D01*
X1524479Y241237D01*
X1525567D01*
G01X1528750Y241500D02*
X1527003D01*
X1526740Y241237D01*
X1525567D01*
G01X1506950Y234750D02*
X1502463D01*
X1501400Y233687D01*
Y229783D01*
X1496082Y224465D01*
Y223064D01*
X1497246Y221900D01*
X1498022D01*
G01X1506950Y227250D02*
X1511196D01*
X1514226Y224220D01*
X1516435D01*
X1520590Y228375D01*
Y228967D01*
X1524074Y232451D01*
X1539138D01*
X1540298Y231291D01*
Y211622D01*
X1540920Y211000D01*
X1541801D01*
X1542423Y211622D01*
Y231291D01*
X1543045Y231913D01*
X1543926D01*
X1544548Y231291D01*
Y211622D01*
X1545170Y211000D01*
X1546051D01*
X1546673Y211622D01*
Y231291D01*
X1547295Y231913D01*
X1548176D01*
X1548798Y231291D01*
Y211622D01*
X1549420Y211000D01*
X1550301D01*
X1550923Y211622D01*
Y231291D01*
X1551545Y231913D01*
X1553532D01*
G01X1525422Y227625D02*
Y226222D01*
X1522717Y223517D01*
Y221027D01*
G01X1532650Y253713D02*
X1530990D01*
X1529490Y252213D01*
X1522184D01*
X1520873Y250902D01*
Y246769D01*
X1519300Y245196D01*
G01D02*
Y250800D01*
X1515900Y254200D01*
Y276200D01*
X1520300Y280600D01*
X1522500D01*
X1523700Y279400D01*
Y277100D01*
X1525633Y275167D01*
X1538133D01*
X1545563Y267737D01*
X1550163D01*
X1552500Y265400D01*
Y264000D01*
G01X1525422Y230625D02*
X1524264D01*
X1522015Y228376D01*
Y226815D01*
X1517608Y222408D01*
Y221216D01*
G01X1481000Y260000D02*
Y257473D01*
X1482673Y255800D01*
X1485612D01*
X1485959Y256147D01*
X1488651D01*
X1491098Y253700D01*
X1497210D01*
X1499070Y255560D01*
Y255934D01*
G01X1475000Y263500D02*
Y264947D01*
X1472824Y267123D01*
G01D02*
Y269076D01*
X1472250Y269650D01*
Y281504D01*
X1473798Y283052D01*
G01X1483247D02*
X1486305Y279994D01*
Y277792D01*
X1487904Y276193D01*
Y272979D01*
X1486886Y271961D01*
X1485773D01*
X1484890Y271078D01*
Y268660D01*
G01D02*
Y266390D01*
X1484000Y265500D01*
Y263500D01*
G01X1472000Y260000D02*
Y258400D01*
X1472400Y258000D01*
Y255591D01*
X1474588Y253403D01*
X1475209D01*
X1476183Y252429D01*
Y251808D01*
X1477654Y250337D01*
X1479189D01*
X1480652Y251800D01*
X1484700D01*
G01X1503842Y245678D02*
Y245887D01*
X1506137Y248182D01*
G01X1496812Y273718D02*
X1496482Y274048D01*
Y274983D01*
X1491053Y280412D01*
Y287008D01*
X1490044Y288017D01*
X1488354D01*
X1487020Y289351D01*
X1483247D01*
G01X1472000Y263500D02*
Y264500D01*
X1471200Y265300D01*
X1469307D01*
X1468322Y266285D01*
Y267533D01*
X1468567Y267778D01*
Y274595D01*
X1467469Y275693D01*
Y277500D01*
G01X1470649Y283052D02*
X1467469Y279872D01*
Y277500D01*
G01X1504461Y274426D02*
X1502200Y272165D01*
Y254511D01*
X1499944Y252255D01*
X1498241D01*
X1495686Y249700D01*
X1486472D01*
X1485984Y249212D01*
X1483627D01*
X1483168Y249671D01*
X1481423D01*
X1480039Y248287D01*
X1476804D01*
X1476216Y248875D01*
X1472816D01*
X1470659Y251032D01*
X1468517D01*
X1468438Y250953D01*
X1467008D01*
X1466787Y251174D01*
Y253839D01*
X1467400Y254452D01*
Y256944D01*
X1467040Y257304D01*
Y260357D01*
G01X1473798Y276753D02*
X1475350Y275201D01*
Y268050D01*
X1478000Y265400D01*
Y263500D01*
G01X1479000Y254500D02*
X1481984D01*
X1482512Y253972D01*
X1487078D01*
G01X1483247Y273603D02*
X1481644Y272000D01*
X1479100D01*
X1478500Y271400D01*
Y268700D01*
X1478400Y268600D01*
Y267500D01*
G01D02*
Y266600D01*
X1481000Y264000D01*
Y263500D01*
G01X1483247Y286202D02*
X1484856Y284593D01*
X1487169D01*
X1488161Y283601D01*
Y282061D01*
X1487215Y281115D01*
Y280925D01*
X1487214Y280924D01*
Y278753D01*
X1488407Y277560D01*
X1489680D01*
X1490963Y276277D01*
G01X1487230Y264650D02*
X1490300D01*
X1490310Y264640D01*
G01X1490963Y276277D02*
Y274002D01*
X1488039Y271078D01*
Y269561D01*
X1488653Y268947D01*
X1490253D01*
X1491090Y268110D01*
Y266500D01*
X1490310Y265720D01*
Y264640D01*
G01X1499900Y277100D02*
X1497969D01*
X1497082Y277987D01*
G01X1503496Y280694D02*
Y278896D01*
X1501700Y277100D01*
X1499900D01*
G01X1465830Y271083D02*
X1465904D01*
G01X1476531Y338695D02*
Y341847D01*
X1477934Y343250D01*
X1481000D01*
G01X1505923Y309510D02*
X1505603Y309830D01*
X1493564D01*
X1490474Y306740D01*
X1485773D01*
X1484890Y307623D01*
Y308735D01*
X1483825Y309800D01*
X1479564D01*
X1478591Y310773D01*
Y312098D01*
X1474838Y315851D01*
Y320916D01*
X1473371Y322383D01*
Y323728D01*
X1471568Y325531D01*
X1471562D01*
G01X1511710Y311070D02*
X1509739Y313041D01*
X1508455D01*
G01X1504200Y327060D02*
X1505630D01*
X1509235Y323455D01*
X1520445D01*
X1521350Y322550D01*
Y322417D01*
G01X1490500Y336000D02*
X1491164D01*
X1497538Y329626D01*
X1499414D01*
X1501980Y327060D01*
X1504200D01*
G01X1523935Y318901D02*
Y319832D01*
X1521350Y322417D01*
G01X1496800Y321940D02*
X1492959D01*
X1492499Y322400D01*
X1490500D01*
G01D02*
Y320737D01*
X1489963Y320200D01*
X1485925D01*
X1485337Y320788D01*
Y329000D01*
X1485763Y329426D01*
Y332037D01*
X1484700Y333100D01*
Y333899D01*
X1483336Y335263D01*
X1474626D01*
X1474163Y334800D01*
X1472500D01*
G01X1509560Y319170D02*
X1508170D01*
X1505400Y321940D01*
X1504200D01*
G01X1499350Y370850D02*
X1491681Y363181D01*
Y356983D01*
X1487813Y353115D01*
Y342719D01*
X1486195Y341101D01*
Y339723D01*
X1486340Y339578D01*
Y338520D01*
X1486150Y338330D01*
Y336749D01*
X1489136Y333763D01*
X1491993D01*
X1497056Y328700D01*
X1499010D01*
X1501500Y326210D01*
Y322401D01*
X1501961Y321940D01*
X1504200D01*
G01X1504217Y294890D02*
X1502690D01*
X1501550Y293750D01*
G01X1485850Y344600D02*
X1482585Y341335D01*
Y340856D01*
G01X1503538Y318068D02*
X1505256Y316350D01*
X1512390D01*
X1513370Y317330D01*
X1515050D01*
X1516960Y319240D01*
X1520760D01*
X1523810Y316190D01*
Y310860D01*
X1525992Y308678D01*
X1527625D01*
X1528599Y307704D01*
Y303514D01*
X1531621Y300492D01*
X1535008D01*
X1535570Y299930D01*
X1535595D01*
X1538584Y296941D01*
Y296916D01*
X1538742Y296758D01*
X1542972D01*
G01X1499987Y288487D02*
X1500769D01*
X1504276Y291994D01*
X1508094D01*
X1511080Y294980D01*
X1517065D01*
X1526062Y285983D01*
Y285859D01*
X1528658Y283263D01*
X1528782D01*
X1530851Y281194D01*
X1540612D01*
X1541596Y280210D01*
X1544781D01*
X1544797Y280194D01*
X1546381D01*
X1555025Y271550D01*
X1556603D01*
X1556605Y271548D01*
X1560503D01*
X1560504Y271549D01*
X1561047D01*
X1562879Y269717D01*
X1566099D01*
X1574688Y261128D01*
Y259195D01*
X1576326Y257557D01*
Y255657D01*
X1576325Y255656D01*
Y254501D01*
X1578622Y252204D01*
Y249495D01*
X1578621Y249494D01*
Y247546D01*
X1586352Y239815D01*
X1595629D01*
X1595665Y239851D01*
X1600165D01*
X1605088Y234928D01*
X1619143D01*
X1624320Y229751D01*
X1635367D01*
X1642017Y223101D01*
X1644438D01*
X1655615Y211924D01*
X1657279D01*
X1661045Y208158D01*
X1668521D01*
X1669963Y206716D01*
X1673345D01*
X1675372Y208743D01*
X1681521D01*
X1685700Y204564D01*
X1708922D01*
G01X1496628Y288440D02*
X1498508Y290320D01*
X1501293D01*
X1503892Y292919D01*
X1507619D01*
X1510605Y295905D01*
X1517449D01*
X1526987Y286367D01*
Y286243D01*
X1529041Y284189D01*
X1529165D01*
X1531235Y282119D01*
X1540996D01*
X1541980Y281135D01*
X1546749D01*
X1555409Y272475D01*
X1556987D01*
X1556989Y272473D01*
X1560119D01*
X1560120Y272474D01*
X1561431D01*
X1563263Y270642D01*
X1566483D01*
X1575613Y261512D01*
Y259579D01*
X1577252Y257940D01*
Y257174D01*
X1577251Y257173D01*
Y255273D01*
X1577250Y255272D01*
Y254885D01*
X1579547Y252588D01*
Y249111D01*
X1579546Y249110D01*
Y247930D01*
X1586736Y240740D01*
X1595245D01*
X1595281Y240776D01*
X1600785D01*
X1605208Y236353D01*
X1619734D01*
X1624859Y231228D01*
X1635199D01*
X1642401Y224026D01*
X1644822D01*
X1655999Y212849D01*
X1657664D01*
X1661430Y209083D01*
X1669103D01*
X1672311Y212291D01*
X1680452D01*
X1684143Y208600D01*
X1701500D01*
G01X1497997Y338546D02*
X1499853D01*
X1501120Y337279D01*
Y334700D01*
X1501606Y334214D01*
X1501611D01*
X1502425Y333400D01*
X1502850D01*
G01X1493600Y354020D02*
X1491700Y352120D01*
Y349195D01*
X1490418Y347913D01*
Y343235D01*
X1493180Y340473D01*
Y337229D01*
X1498489Y331920D01*
X1500660D01*
X1501610Y330970D01*
X1504370D01*
G01X1518060Y317520D02*
Y316340D01*
X1522220Y312180D01*
Y307877D01*
X1531131Y298966D01*
X1531132D01*
X1531593Y298505D01*
X1535004D01*
X1537158Y296351D01*
Y293142D01*
X1537500Y292800D01*
G01X1543400Y277900D02*
X1540661D01*
X1539661Y278900D01*
X1529900D01*
X1527832Y280968D01*
X1527708D01*
X1523768Y284908D01*
Y285032D01*
X1519100Y289700D01*
X1505227D01*
X1501720Y286193D01*
X1499093D01*
X1494376Y281476D01*
X1493700D01*
G01X1470649Y305098D02*
X1467542Y301991D01*
Y300987D01*
G01X1477393Y316431D02*
X1477000Y316824D01*
Y323500D01*
G01D02*
Y330784D01*
X1474647Y333137D01*
X1470911D01*
X1470276Y332502D01*
Y330774D01*
G01X1482996Y292960D02*
X1483708D01*
X1486397Y295649D01*
G01X1493268Y293943D02*
X1490243D01*
X1489600Y293300D01*
G01X1680500Y473325D02*
X1681074Y472751D01*
Y461013D01*
X1678891Y458830D01*
Y447496D01*
X1675754Y444359D01*
X1672660D01*
X1671625Y443324D01*
Y436727D01*
X1669690Y434792D01*
Y422642D01*
X1666228Y419180D01*
Y410550D01*
X1668072Y408706D01*
Y396377D01*
X1668046Y396351D01*
Y359099D01*
X1666141Y357194D01*
Y342763D01*
X1666900Y342004D01*
Y291288D01*
X1666250Y290638D01*
Y285486D01*
X1660732Y279968D01*
Y257154D01*
X1658805Y255227D01*
X1646773D01*
X1639404Y262596D01*
X1635651D01*
X1634170Y264077D01*
Y267137D01*
X1631202Y270105D01*
X1623178D01*
X1623098Y270185D01*
X1622167D01*
X1620931Y271334D01*
X1620930Y271335D01*
X1616035D01*
X1612148Y275222D01*
X1576192D01*
X1570672Y280742D01*
X1567452D01*
X1563204Y284990D01*
Y289119D01*
X1557467Y294856D01*
Y294988D01*
X1552488Y299967D01*
X1537574D01*
X1536186Y301355D01*
X1536161D01*
X1535598Y301918D01*
X1534418D01*
X1534417Y301917D01*
X1532531D01*
X1530024Y304424D01*
Y308295D01*
X1528216Y310103D01*
X1527409D01*
X1525677Y311835D01*
G01X1672606Y499820D02*
X1672481D01*
X1669387Y496726D01*
Y479387D01*
X1652538Y462538D01*
Y404538D01*
X1647500Y399500D01*
Y399464D01*
X1646800Y398764D01*
Y373215D01*
X1648817Y371198D01*
Y356183D01*
X1650500Y354500D01*
Y345334D01*
X1636166Y331000D01*
X1631313D01*
X1629075Y328762D01*
Y326551D01*
X1627752Y325228D01*
X1607591D01*
X1605275Y322912D01*
X1600188D01*
X1594984Y317708D01*
X1588588D01*
X1586042Y320254D01*
X1580271D01*
X1577017Y317000D01*
X1562433D01*
X1553146Y307713D01*
X1539970D01*
X1533960Y313723D01*
Y319130D01*
X1527230Y325860D01*
X1514772D01*
X1514739Y325827D01*
X1513361D01*
X1513328Y325860D01*
X1512130D01*
X1510584Y327406D01*
Y330640D01*
G01X1515183Y372400D02*
Y369390D01*
X1511730Y365937D01*
Y353517D01*
X1514350Y350897D01*
Y341200D01*
X1515790Y339760D01*
X1517470D01*
X1518952Y338278D01*
Y337082D01*
G01X1477500Y348750D02*
Y345360D01*
X1474227Y342087D01*
Y339277D01*
X1472450Y337500D01*
G01X1512000Y346100D02*
Y343300D01*
X1513390Y341910D01*
Y340354D01*
X1515952Y337792D01*
Y337082D01*
G01X1517150Y369051D02*
X1512580Y364481D01*
Y353840D01*
X1515189Y351231D01*
Y341811D01*
X1515760Y341240D01*
X1517794D01*
X1521952Y337082D01*
G01X1482200Y318600D02*
X1480500Y320300D01*
Y323500D01*
G01X1480281Y330195D02*
Y326719D01*
X1480500Y326500D01*
Y323500D01*
G01X1507500Y300606D02*
X1519160D01*
X1526900Y292866D01*
G01X1507500Y300606D02*
X1502233D01*
X1498156Y304683D01*
X1496862D01*
X1494835Y302656D01*
X1490254D01*
X1489546Y301948D01*
G01X1498430Y311510D02*
X1497057Y312883D01*
X1490683D01*
X1489546Y311746D01*
Y311397D01*
G01X1470649Y308247D02*
X1468450Y306048D01*
X1467613D01*
G01X1469801Y318200D02*
Y321473D01*
X1470257Y321929D01*
G01X1503496Y280694D02*
Y281977D01*
X1503519Y282000D01*
Y283694D01*
G01X1509800Y372300D02*
X1510012Y372088D01*
Y352122D01*
X1509320Y351430D01*
Y349930D01*
X1509975Y349275D01*
Y343625D01*
X1512514Y341086D01*
Y337520D01*
X1512952Y337082D01*
G01X1673550Y442696D02*
X1673050Y442196D01*
Y436136D01*
X1671115Y434201D01*
Y317571D01*
X1670212Y316668D01*
Y290568D01*
X1669100Y289456D01*
Y284304D01*
X1663582Y278786D01*
Y255972D01*
X1659987Y252377D01*
X1643067D01*
X1638938Y256506D01*
X1635236D01*
X1631320Y260422D01*
Y265955D01*
X1630020Y267255D01*
X1626541D01*
X1626123Y266837D01*
X1613779D01*
X1612176Y268440D01*
X1609010D01*
X1607201Y266631D01*
Y262325D01*
X1605753Y260877D01*
X1602995D01*
X1602643Y261229D01*
Y263003D01*
X1602200Y263446D01*
X1596354D01*
X1589736Y270064D01*
X1575727D01*
X1569024Y276767D01*
X1565804D01*
X1563970Y278601D01*
X1561676D01*
X1548220Y292057D01*
X1543513D01*
X1540656Y289200D01*
X1537030D01*
X1530620Y295610D01*
Y295870D01*
X1521365Y305125D01*
X1513755D01*
X1507450Y311430D01*
X1505500D01*
X1501630Y315300D01*
X1500109D01*
X1496109Y319300D01*
X1485141D01*
X1483506Y320935D01*
Y326061D01*
G01X1502850Y336900D02*
X1503269D01*
X1505847Y339478D01*
X1505948D01*
X1507100Y340630D01*
Y348140D01*
X1504633Y350607D01*
Y351299D01*
X1504540Y351392D01*
Y355910D01*
X1504900Y356270D01*
Y361368D01*
X1505900Y362368D01*
Y365795D01*
X1505887Y365808D01*
Y366747D01*
X1504600Y368034D01*
Y372200D01*
G01X1526660Y315900D02*
Y320460D01*
X1522740Y324380D01*
X1510240D01*
X1508900Y325720D01*
Y331340D01*
X1509870Y332310D01*
X1510705D01*
X1511270Y332875D01*
Y337020D01*
X1509025Y339265D01*
Y348874D01*
X1508306Y349593D01*
Y351806D01*
X1509000Y352500D01*
Y361600D01*
X1507800Y362800D01*
Y366600D01*
G01X1517700Y303082D02*
X1521392D01*
X1528563Y295911D01*
Y287409D01*
X1528837Y287135D01*
Y287011D01*
X1529809Y286039D01*
X1529933D01*
X1532003Y283969D01*
X1537441D01*
X1543932Y290460D01*
X1547801D01*
X1561086Y277175D01*
X1561949D01*
X1561950Y277176D01*
X1563379D01*
X1565213Y275342D01*
X1568433D01*
X1575136Y268639D01*
X1588762D01*
X1598091Y259310D01*
X1606202D01*
X1608627Y261735D01*
Y266041D01*
X1609601Y267015D01*
X1611375D01*
X1613206Y265184D01*
X1617869D01*
X1625380Y257673D01*
Y256211D01*
X1626510Y255081D01*
X1629156D01*
X1638216Y246021D01*
G01X1517700Y303082D02*
X1503160D01*
X1498234Y308008D01*
X1496512D01*
X1493500Y304996D01*
Y304400D01*
G01X1486397Y301948D02*
Y301903D01*
X1489200Y299100D01*
G01X1496800Y327060D02*
X1498149D01*
X1499990Y325219D01*
Y321372D01*
X1499177Y320559D01*
Y319181D01*
X1500151Y318207D01*
X1500393D01*
X1503790Y314810D01*
X1511440D01*
X1513990Y312260D01*
Y308630D01*
X1516300Y306320D01*
X1521761D01*
X1530540Y297541D01*
X1530541D01*
X1531745Y296337D01*
Y296077D01*
X1537322Y290500D01*
X1538918D01*
X1541600Y293182D01*
X1543047D01*
X1543048Y293183D01*
X1546473D01*
X1546474Y293182D01*
X1548091D01*
X1548092Y293183D01*
X1549022D01*
X1549023Y293182D01*
X1549118D01*
X1562574Y279726D01*
X1564436D01*
X1566270Y277892D01*
X1569490D01*
X1576092Y271290D01*
X1591610D01*
X1597000Y265900D01*
G01X1496800Y327060D02*
X1496680D01*
X1491640Y332100D01*
X1490000D01*
G01X1481000Y343250D02*
X1481750D01*
X1482750Y344250D01*
Y348751D01*
X1484499Y350500D01*
X1485850D01*
G01D02*
X1486000D01*
X1486800Y351300D01*
Y353700D01*
X1490142Y357042D01*
Y363874D01*
X1496834Y370566D01*
Y371134D01*
X1500134Y374434D01*
G01X1491802Y375643D02*
X1488699Y372540D01*
X1485799D01*
X1483658Y370399D01*
X1481999D01*
X1480355Y368755D01*
X1474931D01*
X1472565Y366389D01*
Y363495D01*
X1470100Y361030D01*
Y360500D01*
G01X1501360Y367320D02*
Y365819D01*
X1498246Y362705D01*
G01D02*
X1501040Y359911D01*
Y348210D01*
X1502000Y347250D01*
G01X1505075Y380894D02*
Y376575D01*
X1499350Y370850D01*
G01X1501175Y394414D02*
Y398363D01*
X1499988Y399550D01*
X1498279D01*
X1497906Y399177D01*
X1496602D01*
X1496034Y399745D01*
X1494532D01*
X1494074Y399287D01*
X1492601D01*
X1492182Y399706D01*
X1490734D01*
X1490289Y399261D01*
X1488555D01*
X1487981Y399835D01*
X1483476D01*
X1481411Y401900D01*
X1479200D01*
G01X1470467Y353465D02*
X1472331D01*
X1473537Y354671D01*
Y357088D01*
X1475199Y358750D01*
X1475500D01*
G01X1499225Y384274D02*
Y380571D01*
X1497235Y378581D01*
Y376035D01*
X1495300Y374100D01*
G01X1466967Y353465D02*
X1470467D01*
G01X1495300Y374100D02*
X1491705Y370505D01*
X1490827D01*
X1489703Y369381D01*
X1486713D01*
X1484675Y367343D01*
X1482616D01*
X1479166Y363893D01*
X1478436D01*
X1476589Y362046D01*
Y361704D01*
X1475578Y360693D01*
Y358750D01*
X1475500D01*
G01X1479000Y394900D02*
Y392900D01*
X1476100Y390000D01*
G01X1479000Y398400D02*
Y394900D01*
G01X1487525Y397794D02*
X1483334D01*
X1482923Y397383D01*
X1481313D01*
X1480296Y398400D01*
X1479000D01*
G01X1514265Y355542D02*
X1516603D01*
X1517028Y355117D01*
Y352838D01*
X1519119Y350747D01*
Y349351D01*
X1517000Y347232D01*
Y346650D01*
G01X1476150Y383860D02*
X1475980Y384030D01*
X1472940D01*
G01X1498309Y360005D02*
X1496529Y358225D01*
Y353509D01*
X1494337Y351317D01*
Y348587D01*
X1493000Y347250D01*
G01X1499457Y375093D02*
X1494932Y370568D01*
X1493881D01*
X1491000Y367687D01*
G01X1477500Y352250D02*
X1480890D01*
X1482140Y353500D01*
X1482967D01*
X1485913Y356446D01*
Y366413D01*
X1487187Y367687D01*
X1491000D01*
G01X1502970Y350610D02*
X1502810Y350770D01*
Y354747D01*
X1502800Y354757D01*
Y356420D01*
G01X1505000Y347250D02*
Y348580D01*
X1502970Y350610D01*
G01X1496000Y347250D02*
X1498246Y349496D01*
Y352305D01*
G01X1493600Y354020D02*
X1494023Y354443D01*
Y358353D01*
G01X1481164Y362887D02*
X1479829D01*
X1478612Y361670D01*
G01X1519500Y375000D02*
X1519000Y374500D01*
Y368146D01*
X1517521Y366667D01*
Y364695D01*
X1518245Y363971D01*
Y361300D01*
G01D02*
Y353530D01*
X1520000Y351775D01*
Y347250D01*
G01X1521050Y371700D02*
Y367860D01*
X1521500Y367410D01*
Y363872D01*
X1520517Y362889D01*
Y361163D01*
X1522092Y359588D01*
Y352853D01*
X1523000Y351945D01*
Y347250D01*
G01X1521050Y374500D02*
Y371700D01*
G01X1526000Y347250D02*
X1523891Y349359D01*
Y352477D01*
X1522917Y353451D01*
Y359915D01*
X1524300Y361298D01*
Y363141D01*
X1523700Y363741D01*
Y366200D01*
G01X1528475Y387654D02*
Y383901D01*
X1526500Y381926D01*
Y380000D01*
X1524500Y378000D01*
Y375300D01*
X1523700Y374500D01*
Y366200D01*
G01X1515183Y372400D02*
Y374643D01*
X1515860Y375320D01*
G01X1477500Y348750D02*
X1476798D01*
X1475437Y347389D01*
X1474049D01*
G01X1494023Y361853D02*
Y363393D01*
X1496035Y365405D01*
X1498183D01*
G01X1533000Y344250D02*
Y346500D01*
X1531567Y347933D01*
Y351723D01*
X1527873Y355417D01*
Y358627D01*
X1525783Y360717D01*
Y372872D01*
X1530425Y377514D01*
G01X1528339Y372339D02*
X1526962Y370962D01*
Y361129D01*
X1529522Y358569D01*
Y355359D01*
X1532883Y351998D01*
Y348617D01*
X1536000Y345500D01*
Y344250D01*
G01X1499000Y347250D02*
X1500000Y348250D01*
Y353010D01*
G01D02*
Y355751D01*
X1498246Y357505D01*
G01X1477800Y370800D02*
X1479959D01*
X1481125Y371966D01*
X1483136D01*
X1485789Y374619D01*
Y375791D01*
G01X1512000Y346100D02*
Y348600D01*
X1512847Y349447D01*
Y351191D01*
X1510870Y353168D01*
Y367212D01*
X1513250Y369592D01*
Y374794D01*
G01X1469750Y366500D02*
X1476403Y373153D01*
X1482118D01*
X1483497Y374532D01*
Y375917D01*
G01D02*
Y376500D01*
G01X1469750Y369500D02*
Y370950D01*
X1471424Y372624D01*
Y377424D01*
X1471964Y377964D01*
X1480215D01*
X1483552Y381301D01*
G01X1524746Y359217D02*
X1526448Y357515D01*
Y353890D01*
X1527478Y352860D01*
G01X1470200Y357500D02*
X1470500D01*
X1471075Y358075D01*
X1471106D01*
X1471112Y358081D01*
Y358093D01*
X1474626Y361607D01*
Y362517D01*
G01D02*
X1476112Y364003D01*
Y366827D01*
X1476514Y367229D01*
X1480918D01*
X1482560Y368871D01*
X1484218D01*
X1486425Y371078D01*
X1489031D01*
X1493449Y375496D01*
G01X1509800Y372300D02*
X1511800Y374300D01*
Y375089D01*
G01X1504600Y372200D02*
Y372768D01*
X1507880Y376048D01*
G01X1507800Y366600D02*
Y373698D01*
X1508507Y374405D01*
G01X1483867Y356753D02*
X1483024Y355910D01*
X1481401D01*
X1481081Y356230D01*
G01D02*
Y357772D01*
X1481164Y357855D01*
Y359387D01*
G01X1479255Y376254D02*
X1480654D01*
X1485294Y380894D01*
X1489475D01*
G01X1503878Y364717D02*
Y363177D01*
X1502800Y362099D01*
Y359920D01*
G01X1518350Y491628D02*
Y495551D01*
X1520747Y497948D01*
Y508200D01*
G01X1505714Y448145D02*
X1506800Y449231D01*
Y451000D01*
G01X1520300Y492331D02*
Y494000D01*
G01X1505075Y407934D02*
X1504155D01*
X1502302Y409787D01*
Y410686D01*
G01X1520747Y508200D02*
Y513547D01*
X1524300Y517100D01*
X1531264D01*
X1534020Y514344D01*
Y511930D01*
G01X1520300Y494000D02*
Y496199D01*
X1521806Y497705D01*
Y498636D01*
X1522870Y499700D01*
G01X1516158Y616032D02*
X1512484D01*
X1512100Y616416D01*
G01X1511204Y620056D02*
X1512100Y619160D01*
Y616416D01*
G01X1477800Y615500D02*
Y616870D01*
X1475883Y618787D01*
Y619217D01*
G01X1481778Y614716D02*
X1480994Y615500D01*
X1477800D01*
G01X1551834Y23856D02*
X1552700Y24722D01*
Y26660D01*
X1554395Y28355D01*
X1573560D01*
X1576073Y30868D01*
Y51147D01*
X1571853Y55367D01*
Y57423D01*
X1569551Y59725D01*
Y68201D01*
X1567788Y69964D01*
Y77522D01*
X1568740Y78474D01*
X1570919D01*
X1572223Y77170D01*
Y76181D01*
X1573076Y75328D01*
G01X1554434Y23856D02*
X1553725Y24565D01*
Y26090D01*
X1555065Y27430D01*
X1574012D01*
X1576998Y30416D01*
Y51531D01*
X1572778Y55751D01*
Y57983D01*
X1570476Y60285D01*
Y68585D01*
X1568713Y70348D01*
Y77124D01*
X1569138Y77549D01*
X1570535D01*
X1571298Y76786D01*
Y76183D01*
X1570511Y75396D01*
G01X1546800Y3400D02*
Y5130D01*
X1547716Y6046D01*
G01X1535000Y-15000D02*
Y-6220D01*
X1530367Y-1587D01*
G01X1647500Y16500D02*
X1650096D01*
X1650717Y15879D01*
Y13141D01*
X1638776Y1200D01*
X1636522D01*
X1622829Y-12493D01*
Y-14996D01*
X1618325Y-19500D01*
X1618248D01*
X1617723Y-20025D01*
X1566818D01*
X1566743Y-20100D01*
X1550100D01*
X1545000Y-15000D01*
G01X1586600Y-13300D02*
X1584700D01*
X1584000Y-14000D01*
Y-16100D01*
G01X1590100Y-13300D02*
Y-12400D01*
X1589337Y-11637D01*
X1583938D01*
X1583001Y-10700D01*
G01X1566000Y3400D02*
X1560700Y8700D01*
X1539100D01*
X1536641Y11159D01*
Y13695D01*
X1540346Y17400D01*
X1575869D01*
X1585800Y27331D01*
Y57100D01*
X1577437Y65463D01*
Y69689D01*
X1578000Y70252D01*
Y76498D01*
X1582821Y81319D01*
X1583374D01*
G01X1572586Y95639D02*
X1568891Y91944D01*
Y81123D01*
X1566863Y79095D01*
Y69580D01*
X1568626Y67817D01*
Y58877D01*
X1570763Y56740D01*
Y33378D01*
X1569553Y32168D01*
G01X1581409Y48148D02*
X1581260Y47999D01*
Y25917D01*
X1575443Y20100D01*
X1549183D01*
X1545111Y24172D01*
G01X1580398Y5400D02*
Y2300D01*
G01D02*
Y-600D01*
G01X1531200Y12218D02*
X1533608D01*
X1539890Y18500D01*
X1575413D01*
X1583256Y26343D01*
Y29400D01*
G01D02*
Y31856D01*
X1584700Y33300D01*
Y56644D01*
X1576337Y65007D01*
Y70145D01*
X1576900Y70708D01*
Y77800D01*
X1582400Y83300D01*
X1585100D01*
X1586200Y82200D01*
Y78688D01*
X1588962Y75926D01*
G01X1545572Y38188D02*
Y36908D01*
X1549380Y33100D01*
X1566600D01*
X1569838Y36338D01*
Y55730D01*
X1567201Y58367D01*
Y67708D01*
X1565938Y68971D01*
Y79479D01*
X1567966Y81507D01*
Y98268D01*
X1568950Y99252D01*
G01X1582407Y75841D02*
X1581652Y75086D01*
Y71208D01*
X1590293Y62567D01*
Y51938D01*
G01X1589623Y24528D02*
X1590582Y25487D01*
Y33489D01*
X1594338Y37245D01*
Y39287D01*
X1589268Y44357D01*
Y62283D01*
X1583861Y67690D01*
G01D02*
X1580664Y70887D01*
Y74984D01*
X1579807Y75841D01*
G01X1548547Y65716D02*
Y69744D01*
X1554055Y75252D01*
X1557248D01*
X1565565Y83569D01*
Y101116D01*
X1570708Y106259D01*
Y116519D01*
X1568352Y118875D01*
Y123477D01*
X1570610Y125735D01*
Y131310D01*
X1571083Y131783D01*
Y136505D01*
X1567981Y139607D01*
G01X1567968Y136682D02*
X1570158Y134492D01*
Y132167D01*
X1569684Y131693D01*
Y126118D01*
X1567427Y123861D01*
Y118491D01*
X1569783Y116135D01*
Y106643D01*
X1564640Y101500D01*
Y83953D01*
X1556864Y76177D01*
X1553671D01*
X1545987Y68493D01*
Y65716D01*
G01X1576506Y143416D02*
X1572049Y138959D01*
Y131440D01*
X1571535Y130926D01*
Y125351D01*
X1569277Y123093D01*
Y119315D01*
X1571633Y116959D01*
Y114091D01*
X1574344Y111380D01*
Y110243D01*
X1571777Y107676D01*
Y106019D01*
X1566674Y100916D01*
Y83344D01*
X1557640Y74310D01*
X1556281D01*
X1554900Y72929D01*
Y62689D01*
X1548747Y56536D01*
X1541153D01*
X1537352Y52735D01*
X1532826D01*
X1532353Y53208D01*
Y57198D01*
G01X1575018Y71213D02*
Y64481D01*
X1581409Y58090D01*
Y48148D01*
G01X1539299Y73184D02*
X1543427Y69056D01*
Y65716D01*
G01X1537249Y118153D02*
Y113703D01*
X1543872Y107080D01*
Y103115D01*
X1547838Y99149D01*
Y90088D01*
X1547030Y89280D01*
Y87370D01*
X1544707Y85047D01*
Y82405D01*
X1544814Y82298D01*
Y80985D01*
G01X1564100Y59266D02*
X1563674Y58840D01*
Y51711D01*
X1564710Y50675D01*
Y42643D01*
X1557501Y35434D01*
X1552102D01*
X1550030Y37506D01*
Y38425D01*
X1551050Y39445D01*
G01X1562909Y68218D02*
X1564032D01*
X1565270Y66980D01*
Y60436D01*
X1564100Y59266D01*
G01X1562909Y68218D02*
Y73583D01*
X1562850Y73642D01*
G01X1548547Y49536D02*
Y45448D01*
X1551050Y42945D01*
G01D02*
X1554231D01*
X1555623Y41553D01*
G01X1565637Y52524D02*
Y42027D01*
X1557744Y34134D01*
X1551975D01*
X1549004Y37105D01*
Y38491D01*
X1548050Y39445D01*
G01X1562575Y76231D02*
X1561179Y74835D01*
Y72198D01*
X1559909Y70928D01*
Y68218D01*
G01X1565637Y52524D02*
Y57570D01*
X1566276Y58209D01*
Y67324D01*
X1564572Y69028D01*
Y74272D01*
X1562613Y76231D01*
X1562575D01*
G01X1545987Y49536D02*
Y45008D01*
X1548050Y42945D01*
G01X1543200Y42303D02*
X1543842Y42945D01*
X1548050D01*
G01X1552350Y81200D02*
X1555450D01*
G01X1552350D02*
Y82997D01*
X1552100Y83247D01*
Y86000D01*
G01X1568950Y99252D02*
Y101883D01*
X1572702Y105635D01*
Y107252D01*
X1575269Y109819D01*
Y111876D01*
X1572558Y114587D01*
Y117343D01*
X1570202Y119699D01*
Y122709D01*
X1572460Y124967D01*
Y125925D01*
X1572476D01*
Y130558D01*
X1572974Y131056D01*
Y138465D01*
X1576253Y141744D01*
X1577186D01*
X1578169Y142727D01*
Y145169D01*
X1576288Y147050D01*
X1573442D01*
X1572337Y148155D01*
Y162989D01*
X1568631Y166695D01*
Y168141D01*
X1574339Y173849D01*
X1578933D01*
X1580993Y171789D01*
X1591551D01*
X1593373Y169967D01*
X1600223D01*
X1602146Y168044D01*
Y164283D01*
X1605238Y161191D01*
X1607974D01*
X1609012Y160153D01*
Y159026D01*
X1609965Y158073D01*
X1620666D01*
X1621637Y159044D01*
Y160171D01*
X1622564Y161098D01*
X1624702D01*
X1626339Y162735D01*
G01X1552171Y130471D02*
Y133000D01*
G01X1561900Y107380D02*
X1563880D01*
X1565500Y109000D01*
Y110500D01*
X1566500Y111500D01*
X1568000D01*
G01D02*
Y115020D01*
X1567820Y115200D01*
G01X1568488Y164058D02*
X1570388Y162158D01*
Y143267D01*
X1568725Y141604D01*
X1567626D01*
X1566305Y140283D01*
Y135993D01*
X1567279Y135019D01*
X1568207D01*
X1569233Y133993D01*
Y132551D01*
X1568758Y132076D01*
Y126501D01*
X1566393Y124136D01*
Y116627D01*
X1567820Y115200D01*
G01X1561709Y124081D02*
Y125024D01*
X1563108Y126423D01*
G01X1588000Y138500D02*
Y136301D01*
X1587620Y135921D01*
G01X1584599Y140038D02*
X1586561Y142000D01*
X1588000D01*
G01D02*
X1589901D01*
X1591430Y140471D01*
X1592510D01*
G01X1585000Y137000D02*
Y135598D01*
X1586344Y134254D01*
X1589283D01*
X1589880Y134851D01*
G01X1580950Y152600D02*
X1577950D01*
G01X1584450Y155600D02*
Y152600D01*
G01X1588600Y150500D02*
X1586500Y152600D01*
X1584450D01*
G01X1610645Y143783D02*
X1610017D01*
X1608451Y145349D01*
X1606649D01*
X1605173Y143873D01*
X1595247D01*
X1594176Y144944D01*
Y146919D01*
X1592041Y149054D01*
X1590046D01*
X1588600Y150500D01*
G01X1580950Y149200D02*
X1578089D01*
X1577770Y149519D01*
G01X1584450Y149200D02*
Y146100D01*
G01X1591700Y146200D02*
X1590224Y147676D01*
X1588490D01*
X1586966Y149200D01*
X1584450D01*
G01X1541390Y136498D02*
X1537498D01*
X1536000Y135000D01*
G01X1588847Y175137D02*
X1572876D01*
X1566825Y169086D01*
Y163000D01*
X1569463Y160362D01*
Y157287D01*
X1569442Y157266D01*
Y143630D01*
X1568422Y142610D01*
X1566260D01*
X1564597Y140947D01*
Y128609D01*
X1565652Y127554D01*
X1566381D01*
X1566481Y127454D01*
G01D02*
X1566536Y127399D01*
Y125588D01*
X1564313Y123365D01*
Y119626D01*
X1565165Y118774D01*
Y116226D01*
X1565130Y116191D01*
Y113223D01*
X1564407Y112500D01*
X1561900D01*
G01X1561000Y168500D02*
X1560034Y167534D01*
X1559533D01*
X1555148Y163149D01*
X1552625D01*
X1551081Y164693D01*
X1544709D01*
X1542591Y162575D01*
X1542581D01*
Y160919D01*
X1547400Y156100D01*
Y149700D01*
G01X1528346Y147595D02*
X1531390D01*
X1531985Y147000D01*
G01X1557520Y153300D02*
Y155500D01*
X1559520Y157500D01*
X1562500D01*
X1565500Y154500D01*
Y152500D01*
G01D02*
X1567000D01*
X1567500Y153000D01*
Y158100D01*
G01X1562500Y152500D02*
X1561000D01*
X1558500Y150000D01*
X1554000D01*
X1552400Y151600D01*
Y153300D01*
G01D02*
Y155500D01*
X1551000Y156900D01*
Y159500D01*
X1550000Y160500D01*
X1549000D01*
G01X1552400Y145900D02*
Y143600D01*
X1552857Y143143D01*
X1559168D01*
X1560052Y142259D01*
Y140893D01*
X1561509Y139436D01*
Y139011D01*
X1561693Y138827D01*
Y136074D01*
G01X1552400Y145900D02*
X1549413D01*
X1549113Y146200D01*
X1547400D01*
G01X1553500Y117500D02*
Y115386D01*
X1554500Y114386D01*
Y112500D01*
G01X1553500Y117500D02*
Y118648D01*
X1554352Y119500D01*
X1557474D01*
X1557811Y119837D01*
X1559189D01*
X1560046Y120694D01*
Y121855D01*
X1560163Y121972D01*
Y122189D01*
X1559913Y122439D01*
Y127778D01*
X1561693Y129558D01*
Y136074D01*
G01X1563506Y142982D02*
X1563672Y142816D01*
Y128225D01*
X1564771Y127126D01*
Y125147D01*
X1563388Y123764D01*
Y121500D01*
X1562469Y120581D01*
X1561709D01*
G01X1563502Y117500D02*
Y116345D01*
X1562294Y115137D01*
X1560800D01*
X1559213Y113550D01*
Y110585D01*
X1556008Y107380D01*
X1554500D01*
G01X1563506Y142982D02*
X1562518D01*
X1559600Y145900D01*
X1557520D01*
G01X1563502Y117500D02*
Y118788D01*
X1561709Y120581D01*
G01X1545500Y138500D02*
Y141623D01*
X1543169Y143954D01*
G01X1531678Y135284D02*
X1534602Y138208D01*
X1543547D01*
X1543839Y138500D01*
X1545500D01*
G01X1541434Y139871D02*
X1541387Y139824D01*
X1536900D01*
X1535338Y141386D01*
G01X1584599Y143038D02*
X1585227Y143666D01*
X1592144D01*
X1595060Y140750D01*
X1600774D01*
X1602724Y142700D01*
X1606441D01*
X1609965Y139176D01*
X1611613D01*
X1612103Y138686D01*
Y131920D01*
G01X1537249Y118153D02*
Y120155D01*
X1542000Y124906D01*
Y126246D01*
G01X1552171Y126971D02*
Y125391D01*
X1553353Y124209D01*
G01X1584250Y169000D02*
X1589700D01*
G01X1584250Y166000D02*
X1588000D01*
X1588622Y166622D01*
X1592448D01*
X1594830Y164240D01*
X1595194D01*
X1597302Y162132D01*
G01X1555800Y167300D02*
X1554300Y168800D01*
Y173000D01*
X1553088Y174212D01*
X1548628D01*
G01X1535065Y174112D02*
X1528065D01*
G01X1541628Y174212D02*
X1535165D01*
X1535065Y174112D01*
G01X1548628Y174212D02*
X1541628D01*
G01X1535065Y164300D02*
Y171552D01*
G01X1548628Y171652D02*
X1551650D01*
X1552051Y172053D01*
G01X1571501Y180031D02*
Y177437D01*
X1563830Y169766D01*
Y166330D01*
X1562743Y165243D01*
X1558743D01*
X1553500Y160000D01*
Y157000D01*
G01X1576679Y171209D02*
X1578541D01*
X1580750Y169000D01*
G01X1572817Y169910D02*
X1574116Y171209D01*
X1576679D01*
G01X1575600Y166000D02*
X1580750D01*
G01X1570294Y167384D02*
X1572316D01*
X1573700Y166000D01*
X1575600D01*
G01X1570317Y243681D02*
Y240968D01*
X1568140Y238791D01*
Y233518D01*
X1569318Y232340D01*
X1580976D01*
X1586962Y226354D01*
Y198962D01*
X1584476Y196476D01*
Y190143D01*
X1576916Y182583D01*
X1571583D01*
X1564283Y175283D01*
Y173416D01*
X1561500Y170633D01*
Y169000D01*
X1561000Y168500D01*
G01X1557979Y188844D02*
X1555514Y191309D01*
Y220357D01*
X1562157Y227000D01*
X1574500D01*
G01X1582627Y198617D02*
X1585537Y201527D01*
Y225343D01*
X1580095Y230785D01*
X1568679D01*
X1560937Y238527D01*
Y244982D01*
X1565601Y249646D01*
Y252767D01*
X1561118Y257250D01*
X1556000D01*
G01X1567299Y190920D02*
X1575420D01*
G01D02*
Y191410D01*
X1582627Y198617D01*
G01X1574600Y185400D02*
X1574080Y185920D01*
X1567299D01*
G01Y205920D02*
X1574320D01*
X1574500Y206100D01*
G01X1567299Y200920D02*
X1574520D01*
X1574700Y201100D01*
G01X1567299Y195920D02*
X1574820D01*
X1574900Y196000D01*
G01X1579700Y206200D02*
Y206430D01*
X1576040Y210090D01*
G01X1567299Y210920D02*
X1573547D01*
X1574377Y210090D01*
X1576040D01*
G01X1588799Y162838D02*
X1584099D01*
G01X1610591Y146987D02*
Y148209D01*
X1610175Y148625D01*
X1609965D01*
X1609278Y149312D01*
X1608110D01*
X1608109Y149313D01*
X1607559D01*
X1602997Y153875D01*
X1597222D01*
X1597221Y153876D01*
X1596676D01*
X1593500Y157052D01*
Y159105D01*
X1592767Y159838D01*
X1584099D01*
G01X1589954Y229054D02*
X1588204Y227304D01*
Y198665D01*
X1585599Y196060D01*
Y189454D01*
X1565822Y169677D01*
Y160832D01*
X1567500Y159154D01*
Y158100D01*
G01X1549000Y160500D02*
X1547975Y161525D01*
X1545173D01*
X1545023Y161675D01*
G01X1530149Y215920D02*
X1533519D01*
X1537840Y220241D01*
Y228548D01*
X1537150Y229238D01*
G01X1591606Y198319D02*
Y196057D01*
X1587549Y192000D01*
G01X1665500Y226000D02*
X1664338Y227162D01*
X1643297D01*
X1636380Y234079D01*
X1633791D01*
X1633790Y234078D01*
X1626041D01*
X1614719Y245400D01*
X1603741D01*
X1601967Y243626D01*
X1594099D01*
X1594063Y243590D01*
X1587918D01*
X1582699Y248809D01*
Y252646D01*
G01X1567000Y259560D02*
Y259860D01*
X1563860Y263000D01*
X1561400D01*
G01X1536000Y260500D02*
Y266500D01*
X1537425Y267925D01*
X1540217D01*
X1543800Y264342D01*
Y253897D01*
X1543375Y253472D01*
X1540650D01*
G01X1579867Y265445D02*
Y260666D01*
X1581027Y259506D01*
Y256449D01*
X1582242Y255234D01*
X1583772D01*
X1585287Y253719D01*
Y249286D01*
X1586132Y248441D01*
X1592053D01*
X1596212Y252600D01*
X1605152D01*
X1606477Y253925D01*
X1610379D01*
X1618444Y245860D01*
X1628279D01*
X1636776Y237363D01*
X1643466D01*
X1650892Y229937D01*
X1671344D01*
X1677453Y236046D01*
Y246245D01*
X1679123Y247915D01*
Y262833D01*
X1679124Y262834D01*
Y264284D01*
X1679123Y264285D01*
Y266521D01*
X1675989Y269655D01*
Y273289D01*
X1679100Y276400D01*
G01X1532850Y303950D02*
X1534421D01*
X1535028Y303343D01*
X1536189D01*
X1536752Y302780D01*
X1536777D01*
X1538165Y301392D01*
X1553079D01*
X1558893Y295578D01*
Y295446D01*
X1561141Y293198D01*
X1565002D01*
X1567000Y291200D01*
Y289270D01*
X1565555Y287825D01*
Y286469D01*
X1568932Y283092D01*
X1571647D01*
X1575276Y279463D01*
X1615555D01*
X1630855Y294763D01*
Y315365D01*
X1633382Y317892D01*
Y319376D01*
X1639739Y325733D01*
Y328791D01*
X1656816Y345868D01*
Y369839D01*
X1655381Y371274D01*
Y393465D01*
X1657424Y395508D01*
Y455732D01*
X1662594Y460902D01*
X1670113D01*
X1674879Y465668D01*
Y474665D01*
X1677103Y476889D01*
X1722011D01*
X1728700Y470200D01*
G01X1548199Y285830D02*
Y283717D01*
X1556591Y275325D01*
X1562612D01*
X1564445Y273492D01*
X1567665D01*
X1578464Y262693D01*
Y260760D01*
X1580102Y259122D01*
Y256065D01*
X1581858Y254309D01*
X1583388D01*
X1584362Y253335D01*
Y248902D01*
X1585748Y247516D01*
X1592656D01*
X1593680Y248540D01*
X1605431D01*
X1606755Y247216D01*
X1614919D01*
X1627100Y235035D01*
X1637349D01*
X1644297Y228087D01*
X1672600D01*
X1673026Y228513D01*
X1674500D01*
G01X1668735Y344282D02*
Y291107D01*
X1667675Y290047D01*
Y284895D01*
X1662157Y279377D01*
Y256563D01*
X1659396Y253802D01*
X1643658D01*
X1639529Y257931D01*
X1635827D01*
X1632745Y261013D01*
Y266546D01*
X1630611Y268680D01*
X1622191D01*
Y268760D01*
X1621606D01*
X1620369Y269910D01*
X1615444D01*
X1612326Y273028D01*
X1576370D01*
X1570081Y279317D01*
X1566861D01*
X1561778Y284400D01*
Y285580D01*
X1561779Y285581D01*
Y286721D01*
X1560546Y287954D01*
X1559116D01*
X1557837Y289233D01*
Y289963D01*
X1555452Y292348D01*
X1552052D01*
X1549793Y294607D01*
X1549614D01*
X1549613Y294608D01*
X1547501D01*
X1547500Y294607D01*
X1547065D01*
X1547064Y294608D01*
X1542457D01*
X1542456Y294607D01*
X1538707D01*
X1537500Y293400D01*
Y292800D01*
G01X1568120Y251710D02*
X1570317Y249513D01*
Y243681D01*
G01X1528750Y241500D02*
Y241815D01*
X1530149Y243214D01*
X1532959D01*
X1532973Y243200D01*
X1537300D01*
G01X1553532Y231913D02*
X1554776Y230669D01*
X1563994D01*
X1565386Y229277D01*
X1574075D01*
X1574500Y228852D01*
Y227000D01*
G01X1544300Y248318D02*
X1544987Y249005D01*
Y260395D01*
X1545510Y260918D01*
X1552508D01*
G01X1548996Y265700D02*
Y264430D01*
X1552508Y260918D01*
G01X1566260Y256040D02*
X1565337Y256963D01*
Y258563D01*
X1562982Y260918D01*
X1556008D01*
G01X1574900Y240900D02*
X1572600Y243200D01*
Y249720D01*
X1570312Y252008D01*
Y252996D01*
X1568808Y254500D01*
X1567800D01*
X1566260Y256040D01*
G01X1556000Y264000D02*
Y260926D01*
X1556008Y260918D01*
G01X1552500Y257250D02*
Y255750D01*
X1552850Y255400D01*
X1559000D01*
X1559350Y255050D01*
G01X1547650Y258590D02*
X1550156D01*
X1551496Y257250D01*
X1552500D01*
G01X1537300Y245759D02*
X1538829D01*
X1540040Y246970D01*
Y249270D01*
X1538308Y251002D01*
X1533075D01*
X1532650Y251427D01*
X1532652Y251429D01*
Y253711D01*
X1532650Y253713D01*
G01D02*
X1532616Y253747D01*
Y254946D01*
X1533320Y255650D01*
X1537836D01*
X1538217Y256031D01*
G01X1540650D02*
X1538217D01*
G01D02*
X1537806Y256442D01*
Y260997D01*
X1538395Y261586D01*
Y265323D01*
X1538443Y265371D01*
G01X1543400Y277900D02*
X1545430D01*
X1554074Y269256D01*
X1555652D01*
X1555654Y269254D01*
X1560097D01*
X1561928Y267423D01*
X1564105D01*
X1564106Y267422D01*
X1565149D01*
X1572394Y260177D01*
Y258244D01*
X1574031Y256607D01*
Y253550D01*
X1576327Y251254D01*
Y246595D01*
X1586436Y236486D01*
X1587500D01*
G01D02*
X1589103Y234883D01*
X1594744D01*
X1597201Y237340D01*
Y238188D01*
G01X1834103Y176021D02*
X1824224Y185900D01*
X1717069D01*
X1714443Y188526D01*
X1713839D01*
X1711548Y190817D01*
X1710032D01*
X1698814Y202035D01*
X1685418D01*
X1684912Y202541D01*
X1682000D01*
X1681494Y202035D01*
X1677804D01*
X1675255Y204584D01*
X1673847D01*
X1673846Y204583D01*
X1669478D01*
X1667753Y206308D01*
X1660244D01*
X1658190Y208362D01*
Y208395D01*
X1656511Y210074D01*
X1654778D01*
X1643602Y221250D01*
X1641250D01*
X1634600Y227900D01*
X1622900D01*
X1619100Y231700D01*
X1596115D01*
X1596079Y231664D01*
X1587768D01*
X1587732Y231700D01*
X1584900D01*
X1581500Y235100D01*
X1579600D01*
G01X1574560Y237660D02*
X1577120Y235100D01*
X1579600D01*
G01X1532526Y227200D02*
X1533301D01*
X1534300Y226201D01*
Y221401D01*
X1533819Y220920D01*
X1530149D01*
G01X1532526Y227200D02*
X1531425D01*
X1531000Y227625D01*
X1528922D01*
G01X1594500Y277500D02*
X1575930D01*
X1571263Y282167D01*
X1568043D01*
X1564630Y285580D01*
Y289890D01*
X1565000Y290260D01*
Y290500D01*
G01X1844110Y206600D02*
X1842136D01*
X1830098Y218638D01*
X1715837D01*
X1709624Y212425D01*
X1691870D01*
X1691869Y212426D01*
X1691227D01*
X1688239Y215414D01*
X1672109D01*
X1668319Y211624D01*
X1668236D01*
X1668045Y211433D01*
X1666667D01*
X1665579Y212521D01*
Y214616D01*
X1654458Y225737D01*
X1642706D01*
X1635790Y232653D01*
X1625450D01*
X1620323Y237780D01*
X1605797D01*
X1601376Y242201D01*
X1594690D01*
X1594654Y242165D01*
X1587327D01*
X1580972Y248520D01*
Y253179D01*
X1578676Y255475D01*
Y256582D01*
X1578677Y256583D01*
Y258531D01*
X1577038Y260170D01*
Y260921D01*
X1577039Y260922D01*
Y262102D01*
X1567074Y272067D01*
X1563854D01*
X1562021Y273900D01*
X1561360D01*
X1561359Y273899D01*
X1559529D01*
X1559528Y273898D01*
X1557580D01*
X1557578Y273900D01*
X1556207D01*
X1556194Y273914D01*
X1555986D01*
X1546379Y283521D01*
Y287579D01*
X1546550Y287750D01*
Y287812D01*
X1546612D01*
G01X1579900Y223500D02*
X1574500D01*
G01Y220500D02*
Y223500D01*
G01X1567299Y220920D02*
X1572080D01*
X1572500Y220500D01*
X1574500D01*
G01X1537150Y229238D02*
X1535763Y230625D01*
X1528922D01*
G01X1666500Y231900D02*
X1651052D01*
X1644664Y238288D01*
X1637160D01*
X1628663Y246785D01*
X1618828D01*
X1610762Y254851D01*
X1609996D01*
X1609995Y254850D01*
X1606861D01*
X1606860Y254851D01*
X1606094D01*
X1604768Y253525D01*
X1595828D01*
X1591669Y249366D01*
X1588851D01*
X1586950Y251267D01*
G01X1568365Y247761D02*
Y247396D01*
X1566817Y245848D01*
Y243681D01*
G01X1562900Y243600D02*
X1562981Y243681D01*
X1566817D01*
G01X1572336Y287063D02*
X1568497D01*
X1568230Y287330D01*
G01X1563000Y338250D02*
Y341000D01*
G01D02*
Y341300D01*
X1565500Y343800D01*
G01X1566000Y338250D02*
Y341000D01*
G01D02*
X1568600Y343600D01*
Y344050D01*
G01X1542972Y296758D02*
X1550242D01*
X1550800Y296200D01*
G01X1538206Y303741D02*
Y305794D01*
X1536900Y307100D01*
X1534700D01*
X1532080Y309720D01*
Y310820D01*
G01D02*
Y311880D01*
X1530160Y313800D01*
Y315900D01*
G01X1538200Y364700D02*
X1536734Y363234D01*
Y358777D01*
X1537811Y357700D01*
X1539024D01*
X1540644Y356080D01*
Y350134D01*
X1540953Y349825D01*
X1540957D01*
X1544250Y346532D01*
Y346528D01*
X1544824Y345954D01*
X1546688D01*
X1548779Y343863D01*
X1548789D01*
X1549763Y342889D01*
Y331267D01*
X1556831Y324199D01*
X1568826D01*
X1575957Y331330D01*
X1586376D01*
X1588553Y333507D01*
X1600573D01*
X1602776Y331304D01*
G01X1580365Y341293D02*
X1581000Y341928D01*
Y343750D01*
G01X1556500Y334750D02*
Y333371D01*
X1558311Y331560D01*
Y331089D01*
X1558340Y331060D01*
Y328532D01*
X1559335Y327537D01*
X1567578D01*
X1576241Y336200D01*
X1604894D01*
X1605090Y336004D01*
G01X1582659Y334237D02*
X1575587D01*
X1567962Y326612D01*
X1558139D01*
X1553058Y331693D01*
Y333058D01*
X1553500Y333500D01*
Y334750D01*
G01X1582659Y334237D02*
X1585090D01*
X1586128Y335275D01*
X1602972D01*
X1604656Y333591D01*
X1613217D01*
X1618235Y338609D01*
X1619870D01*
X1619897Y338636D01*
G01X1589000Y300560D02*
X1583500D01*
G01D02*
X1583425Y300485D01*
Y298875D01*
X1585000Y297300D01*
Y292500D01*
G01X1589000Y303120D02*
X1583500D01*
G01D02*
X1583320D01*
X1581837Y301637D01*
Y299013D01*
X1583963Y296887D01*
Y295311D01*
X1582000Y293348D01*
Y292500D01*
G01X1556500Y343750D02*
Y342200D01*
X1557600Y341100D01*
G01D02*
X1557550D01*
G01X1556500Y338250D02*
Y340000D01*
X1557600Y341100D01*
G01X1554800D02*
X1553500Y342400D01*
Y343750D01*
G01Y338250D02*
Y339800D01*
X1554800Y341100D01*
G01X1572820Y300560D02*
X1565618D01*
X1565244Y300934D01*
G01X1572820Y303120D02*
X1565849D01*
X1565235Y303734D01*
G01X1587300Y338400D02*
X1584161D01*
X1583794Y338767D01*
G01X1658482Y498975D02*
X1661276D01*
X1663462Y496789D01*
Y479306D01*
X1648863Y464707D01*
Y407037D01*
X1641814Y399988D01*
Y370794D01*
X1643789Y368819D01*
Y357205D01*
X1642815Y356231D01*
X1639131D01*
X1636203Y353303D01*
Y349098D01*
X1633840Y346735D01*
Y345357D01*
X1634429Y344768D01*
Y341424D01*
X1630770Y337765D01*
X1629030D01*
X1620316Y329051D01*
X1604466D01*
X1603931Y328516D01*
X1588708D01*
X1586978Y326786D01*
Y324551D01*
X1588576Y322953D01*
X1589476D01*
G01X1631015Y328350D02*
Y326904D01*
X1628414Y324303D01*
X1607992D01*
X1605465Y321776D01*
X1600361D01*
X1595368Y316783D01*
X1594290D01*
X1591269Y313762D01*
X1589523D01*
X1588549Y314736D01*
Y316024D01*
X1586203Y318370D01*
X1584461D01*
X1581891Y315800D01*
X1574400D01*
X1569400Y310800D01*
X1564710D01*
X1564427Y311083D01*
G01X1571293Y284755D02*
X1573171Y282877D01*
X1577461D01*
X1577471Y282867D01*
X1582407D01*
X1585276Y285736D01*
X1620519D01*
X1629930Y295147D01*
Y317824D01*
X1631419Y319313D01*
G01X1543864Y311399D02*
X1538481D01*
X1535540Y314340D01*
Y319920D01*
X1531565Y323895D01*
Y329435D01*
X1530110Y330890D01*
Y333680D01*
G01Y336680D02*
Y337710D01*
X1528000Y339820D01*
Y341400D01*
X1529000Y342400D01*
Y343750D01*
G01X1530110Y336680D02*
Y333680D01*
G01X1533000Y340750D02*
Y329353D01*
X1535813Y326540D01*
G01X1649336Y511502D02*
X1649455D01*
Y511622D01*
X1651168Y513335D01*
X1654780D01*
X1667962Y500153D01*
Y497962D01*
X1667500Y497500D01*
Y480000D01*
X1651113Y463613D01*
Y405613D01*
X1645375Y399875D01*
Y372624D01*
X1647392Y370607D01*
Y355592D01*
X1649075Y353909D01*
Y345925D01*
X1635650Y332500D01*
X1627598D01*
X1621751Y326653D01*
X1607000D01*
X1604684Y324337D01*
X1599597D01*
X1594393Y319133D01*
X1589180D01*
X1586118Y322195D01*
X1580196D01*
X1576701Y318700D01*
X1557269D01*
X1549969Y311400D01*
X1547143D01*
X1542243Y316300D01*
X1538500D01*
X1537190Y317610D01*
Y325163D01*
X1535813Y326540D01*
G01X1656197Y503552D02*
X1658495D01*
X1664587Y497460D01*
Y482315D01*
X1664588Y482314D01*
Y481384D01*
X1664587Y481383D01*
Y478840D01*
X1649988Y464241D01*
Y406311D01*
X1642939Y399262D01*
Y371260D01*
X1644914Y369285D01*
Y356739D01*
X1643281Y355106D01*
X1639597D01*
X1637328Y352837D01*
Y338356D01*
X1633328Y334356D01*
X1627212D01*
X1620782Y327926D01*
X1605850D01*
X1603754Y325830D01*
X1599499D01*
X1593927Y320258D01*
X1589646D01*
X1584334Y325570D01*
X1574786D01*
X1570340Y321124D01*
X1555386D01*
X1549331Y327179D01*
X1546366D01*
X1541563Y331982D01*
Y334763D01*
X1542000Y335200D01*
Y340750D01*
G01X1545000Y336900D02*
Y340750D01*
G01X1644651Y505500D02*
Y503198D01*
X1653617Y494232D01*
Y479560D01*
X1646580Y472523D01*
Y471509D01*
X1646578Y471507D01*
Y467232D01*
X1642936Y463590D01*
Y428414D01*
X1645439Y425911D01*
Y408878D01*
X1638189Y401628D01*
Y373499D01*
X1636940Y372250D01*
Y355631D01*
X1635078Y353769D01*
Y349935D01*
X1632714Y347571D01*
Y345715D01*
X1626903Y339904D01*
Y338230D01*
X1622849Y334176D01*
X1619327D01*
X1616304Y331153D01*
X1604977D01*
X1603465Y329641D01*
X1588242D01*
X1585296Y326695D01*
X1574320D01*
X1569874Y322249D01*
X1555852D01*
X1549797Y328304D01*
X1547114D01*
X1545212Y330206D01*
Y331436D01*
X1544303Y332345D01*
X1544215D01*
X1543241Y333319D01*
Y334697D01*
X1545000Y336456D01*
Y336900D01*
G01X1536000Y340750D02*
Y337052D01*
X1535966Y337018D01*
G01X1539000Y340750D02*
Y337000D01*
G01X1549532Y347696D02*
Y345454D01*
X1551785Y343201D01*
Y331105D01*
X1557407Y325483D01*
X1568142D01*
X1574899Y332240D01*
X1584932D01*
X1587042Y334350D01*
X1602588D01*
X1604660Y332278D01*
X1614149D01*
X1618007Y336136D01*
X1619897D01*
G01X1590176Y331844D02*
X1588854D01*
X1584830Y327820D01*
X1573854D01*
X1569408Y323374D01*
X1556321D01*
X1549997Y329698D01*
X1547311D01*
X1546337Y330672D01*
Y332762D01*
X1547398Y333823D01*
G01X1589000Y305680D02*
X1585120D01*
X1577468Y313332D01*
X1576168D01*
G01D02*
X1574337D01*
X1570105Y309100D01*
X1570000D01*
X1569926Y309026D01*
Y308064D01*
G01X1557534Y353400D02*
Y353566D01*
X1555100Y356000D01*
G01X1549303Y358875D02*
X1558837Y349341D01*
Y349311D01*
X1559500Y348648D01*
Y347250D01*
G01X1543300Y360900D02*
X1547278D01*
X1549303Y358875D01*
G01X1613717Y370711D02*
X1611817D01*
X1609603Y368497D01*
Y365677D01*
X1607909Y363983D01*
X1605851D01*
X1603565Y361697D01*
X1594196D01*
X1592746Y360247D01*
X1584873D01*
X1581822Y363298D01*
Y365770D01*
G01X1610370Y361890D02*
X1609702Y362558D01*
X1606442D01*
X1603984Y360100D01*
X1597119D01*
X1593708Y356689D01*
X1585320D01*
X1569584Y372425D01*
Y378002D01*
G01X1563575Y394414D02*
X1562383D01*
X1559966Y391997D01*
Y390632D01*
X1557742Y388408D01*
Y386983D01*
X1559673Y385052D01*
Y383629D01*
X1561819Y381483D01*
Y379883D01*
X1563321Y378381D01*
Y375606D01*
X1570926Y368001D01*
Y365591D01*
X1574154Y362363D01*
Y357881D01*
X1579159Y352876D01*
X1593639D01*
X1594000Y353237D01*
X1595076D01*
G01X1557725Y397794D02*
Y393852D01*
X1555519Y391646D01*
Y390008D01*
X1553646Y388135D01*
Y386847D01*
X1555714Y384779D01*
Y383530D01*
X1557508Y381736D01*
Y380409D01*
X1559497Y378420D01*
Y374628D01*
X1564477Y369648D01*
X1566466D01*
X1566467Y369649D01*
X1567149D01*
X1567150Y369648D01*
X1568036D01*
X1570101Y367583D01*
Y365107D01*
X1573229Y361979D01*
Y357497D01*
X1578870Y351856D01*
X1583221D01*
X1586277Y348800D01*
X1597900D01*
X1599300Y350200D01*
G01X1639113Y496734D02*
Y494921D01*
X1634643Y490451D01*
Y476707D01*
X1626100Y468164D01*
Y452804D01*
X1624626Y451330D01*
Y428128D01*
X1632352Y420402D01*
Y418333D01*
X1624626Y410607D01*
Y392326D01*
X1615527Y383227D01*
X1595116D01*
X1594451Y382562D01*
Y378186D01*
X1594026Y377761D01*
X1585349D01*
X1583635Y379475D01*
X1581525D01*
X1573346Y387654D01*
X1571375D01*
G01X1569425Y391034D02*
X1571159Y392768D01*
X1574111D01*
X1583866Y383013D01*
X1585298D01*
G01D02*
X1585811Y382500D01*
X1589250D01*
G01X1576305Y371122D02*
X1572484Y374943D01*
Y378157D01*
X1567941Y382700D01*
X1566232D01*
X1566193Y382661D01*
X1564857D01*
X1563912Y383606D01*
Y383615D01*
X1563868Y383659D01*
Y384446D01*
X1561643Y386671D01*
Y388468D01*
X1563344Y390169D01*
Y391509D01*
X1565182Y393347D01*
Y395211D01*
X1563851Y396542D01*
Y397840D01*
X1562290Y399401D01*
X1557060D01*
X1556009Y398350D01*
Y397706D01*
X1553909Y395606D01*
X1553067D01*
X1551875Y394414D01*
G01X1576305Y371122D02*
X1579561Y367866D01*
X1582345D01*
X1583689Y366522D01*
Y364843D01*
X1584078Y364454D01*
X1587780D01*
X1588750Y365424D01*
Y366015D01*
X1588852Y366117D01*
G01X1586500Y354900D02*
X1581433D01*
X1580029Y356304D01*
G01X1576129Y377952D02*
X1571931Y382150D01*
X1571700D01*
Y382230D01*
X1571585D01*
G01X1588852Y369117D02*
Y370780D01*
X1588750Y370882D01*
Y371250D01*
X1587574Y372426D01*
X1581655D01*
X1576129Y377952D01*
G01X1562500Y347300D02*
X1565500D01*
G01X1546350Y363400D02*
X1543300D01*
G01X1565500Y347300D02*
Y348500D01*
X1553100Y360900D01*
X1549600D01*
X1547100Y363400D01*
X1546350D01*
G01X1568600Y347550D02*
X1570098D01*
X1570348Y347800D01*
X1571800D01*
G01X1565188Y351991D02*
X1563169Y354010D01*
X1562190D01*
X1553593Y362607D01*
X1550417D01*
G01X1565188Y351991D02*
X1565205D01*
X1568600Y348596D01*
Y347550D01*
G01X1585600Y375200D02*
X1584620Y376180D01*
X1581643D01*
X1571776Y386047D01*
X1566809D01*
X1565868Y386988D01*
Y386989D01*
X1565525Y387332D01*
Y391034D01*
G01X1591852Y372117D02*
X1590193Y373776D01*
X1587024D01*
X1585600Y375200D01*
G01X1543651Y373807D02*
Y368755D01*
G01D02*
X1541325Y366429D01*
Y360451D01*
X1543201Y358575D01*
X1546801D01*
X1549213Y356163D01*
X1550706D01*
X1556500Y350369D01*
Y347250D01*
G01X1539800Y375960D02*
Y374000D01*
X1540300Y373500D01*
Y371800D01*
G01D02*
Y360876D01*
X1540299Y360875D01*
Y360027D01*
X1542733Y357593D01*
X1546431D01*
X1549056Y354968D01*
X1550592D01*
X1554333Y351227D01*
Y348631D01*
X1553500Y347798D01*
Y347250D01*
G01X1542000Y344250D02*
Y345600D01*
X1540025Y347575D01*
X1537474D01*
X1535500Y349549D01*
Y356206D01*
X1531719Y359987D01*
Y367280D01*
X1534000Y369561D01*
Y371500D01*
G01X1534679Y375405D02*
X1534000Y374726D01*
Y371500D01*
G01X1545000Y344250D02*
X1544937D01*
X1543125Y346062D01*
Y346066D01*
X1540491Y348700D01*
X1537952D01*
X1536815Y349837D01*
Y356719D01*
X1535534Y358000D01*
Y364223D01*
X1536800Y365489D01*
Y367300D01*
G01X1537286Y375714D02*
X1538000Y375000D01*
Y371653D01*
X1536800Y370453D01*
Y367300D01*
G01X1530814Y374814D02*
X1528339Y372339D01*
G01X1532278Y373078D02*
X1529400Y370200D01*
Y367200D01*
G01D02*
Y365000D01*
X1528166Y363766D01*
Y361530D01*
X1529490Y360206D01*
Y360192D01*
X1530683Y358999D01*
Y355789D01*
X1534375Y352097D01*
Y348875D01*
X1539000Y344250D01*
G01X1549532Y352846D02*
X1548800Y352114D01*
Y348928D01*
X1549532Y348196D01*
Y347696D01*
G01X1551875Y380894D02*
Y373578D01*
X1554150Y371303D01*
G01D02*
X1555986Y369467D01*
X1560493D01*
X1564131Y365829D01*
Y358860D01*
X1571991Y351000D01*
X1577250D01*
X1581000Y347250D01*
G01X1589250Y388500D02*
X1587600D01*
X1587099Y389001D01*
X1585650D01*
G01D02*
X1584580D01*
X1583275Y387696D01*
X1583269D01*
X1583266Y387693D01*
X1581934D01*
X1580700Y388927D01*
Y391905D01*
X1578718Y393887D01*
X1575785D01*
X1569290Y400382D01*
Y401984D01*
X1568189Y403085D01*
X1559194D01*
X1557725Y404554D01*
G01X1527478Y352860D02*
X1527986D01*
X1529869Y350977D01*
Y349067D01*
X1529000Y348198D01*
Y347250D01*
G01X1578750Y391060D02*
X1579706Y390104D01*
Y388527D01*
X1582733Y385500D01*
X1589250D01*
G01X1567475Y401174D02*
Y397084D01*
X1568534Y396025D01*
X1572254D01*
X1575675Y392604D01*
X1577206D01*
X1578750Y391060D01*
G01X1584000Y347250D02*
X1580839Y350411D01*
X1579006D01*
X1576017Y353400D01*
X1573633D01*
X1571598Y355435D01*
G01D02*
X1568998Y358035D01*
Y366633D01*
X1566808Y368823D01*
X1563088D01*
X1560766Y371145D01*
X1559224D01*
X1555733Y374636D01*
Y378303D01*
X1553665Y380371D01*
Y381619D01*
X1552066Y383218D01*
Y384877D01*
X1550096Y386847D01*
Y388485D01*
X1552015Y390404D01*
Y391485D01*
X1550000Y393500D01*
Y395500D01*
X1551875Y397375D01*
Y401174D01*
G01X1589250Y379500D02*
X1585273D01*
X1583731Y381042D01*
Y381830D01*
X1581861Y383700D01*
X1580253D01*
G01D02*
X1574526Y389427D01*
X1568760D01*
X1567818Y390369D01*
Y392469D01*
X1569763Y394414D01*
X1571375D01*
G01X1546182Y355446D02*
Y354682D01*
X1546032Y354532D01*
Y352846D01*
G01X1543528Y352446D02*
X1544369Y351605D01*
Y351572D01*
X1544758Y351183D01*
X1544791D01*
X1546032Y349942D01*
Y347696D01*
G01X1579500Y425250D02*
X1580595D01*
X1581939Y426594D01*
G01X1579000Y413250D02*
X1581250D01*
X1583208Y415208D01*
Y416752D01*
G01X1587238Y432593D02*
X1588074Y431757D01*
Y431743D01*
X1589317Y430500D01*
X1596800D01*
G01X1581000Y465400D02*
X1582810D01*
X1584200Y464010D01*
Y462610D01*
G01X1577782Y461336D02*
Y463682D01*
X1579500Y465400D01*
X1581000D01*
G01X1583060Y449320D02*
X1583280Y449100D01*
Y447080D01*
X1582300Y446100D01*
G01X1577782Y451536D02*
X1580844D01*
X1583060Y449320D01*
G01X1565525Y446926D02*
X1567298Y448699D01*
X1568141D01*
X1568182Y448740D01*
X1570668D01*
X1570709Y448699D01*
X1572041D01*
X1572082Y448740D01*
X1573350D01*
X1573877Y449267D01*
Y451641D01*
G01X1577782Y457836D02*
X1578490D01*
X1580370Y459716D01*
Y462090D01*
G01X1574377Y461441D02*
X1575659D01*
X1576100Y461000D01*
Y458261D01*
X1576525Y457836D01*
X1577782D01*
G01X1578069Y589228D02*
Y590794D01*
X1579407Y592132D01*
X1585830D01*
G01D02*
X1587751D01*
X1588667Y593048D01*
X1590968D01*
X1594530Y596610D01*
Y611090D01*
X1594110Y611510D01*
G01X1556630Y610070D02*
X1557039Y610479D01*
Y614627D01*
G01X1540700Y613700D02*
X1544900Y609500D01*
X1556060D01*
X1556630Y610070D01*
G01X1571080Y591445D02*
Y590130D01*
X1571982Y589228D01*
X1574569D01*
G01X1572950Y593950D02*
X1572074D01*
X1571080Y592956D01*
Y591445D01*
G01X1567300Y601700D02*
X1567437Y601563D01*
X1570660D01*
G01D02*
X1572923Y599300D01*
X1578000D01*
X1579200Y600500D01*
X1581000D01*
G01X1573260Y601600D02*
X1577133D01*
X1579033Y603500D01*
X1581000D01*
G01X1597244Y43700D02*
X1598707Y42237D01*
Y25634D01*
X1597800Y24727D01*
Y24300D01*
G01X1647500Y16500D02*
X1644806D01*
X1644000Y17306D01*
Y22250D01*
G01X1651250Y25941D02*
X1648087D01*
X1647182Y25036D01*
Y23022D01*
X1646410Y22250D01*
X1644000D01*
G01X1592829Y24460D02*
X1591607Y25682D01*
Y32792D01*
X1595477Y36662D01*
Y39457D01*
X1590293Y44641D01*
Y51938D01*
G01X1613000Y-14218D02*
X1610882D01*
X1610004Y-15096D01*
Y-17346D01*
G01X1613000Y-6218D02*
Y-10718D01*
G01D02*
X1610582D01*
X1608500Y-12800D01*
G01X1590100Y-13300D02*
X1591400D01*
X1592400Y-14300D01*
X1594600D01*
G01X1630750Y17000D02*
X1634250D01*
G01X1630750D02*
Y12950D01*
X1631500Y12200D01*
G01X1634250Y17000D02*
Y25400D01*
X1637000Y28150D01*
G01X1623900Y4600D02*
Y-2800D01*
X1623041Y-3659D01*
X1620000D01*
G01X1600004Y-17346D02*
X1598700Y-16042D01*
Y-12300D01*
X1599259Y-11741D01*
X1601600D01*
G01X1617050Y34700D02*
X1618050D01*
X1620000Y32750D01*
X1621500D01*
G01X1615968Y28300D02*
Y31368D01*
X1617050Y32450D01*
Y34700D01*
G01X1623400Y17500D02*
Y17900D01*
X1621500Y19800D01*
Y22250D01*
G01X1628500Y24400D02*
X1624800D01*
X1624400Y24000D01*
Y22700D01*
X1623950Y22250D01*
X1621500D01*
G01X1615968Y23800D02*
X1617750D01*
X1619300Y22250D01*
X1621500D01*
G01X1598602Y3437D02*
X1596700Y1535D01*
Y-6800D01*
X1597400Y-7500D01*
Y-15187D01*
X1596874Y-15713D01*
X1595587D01*
X1595004Y-16296D01*
Y-17346D01*
G01X1601502Y3437D02*
X1598602D01*
G01X1597244Y43700D02*
Y48056D01*
X1594350Y50950D01*
Y65518D01*
X1590952Y68916D01*
Y71406D01*
X1592026Y72480D01*
X1593180D01*
X1596050Y75350D01*
Y75400D01*
G01X1628250Y69000D02*
Y72000D01*
G01Y69000D02*
X1630092D01*
X1631166Y70074D01*
X1639627D01*
X1640900Y68801D01*
Y66900D01*
G01X1630826Y88087D02*
X1629500Y86761D01*
Y82400D01*
X1628500Y81400D01*
Y80300D01*
G01X1610853Y63861D02*
X1612692Y65700D01*
X1621076D01*
X1623614Y63162D01*
Y60086D01*
X1635841Y47859D01*
G01D02*
X1640700Y43000D01*
X1675100D01*
X1677250Y45150D01*
Y46000D01*
G01X1623200Y75800D02*
Y74928D01*
X1621122Y72850D01*
X1612650D01*
X1611000Y74500D01*
X1607425D01*
X1606533Y73608D01*
Y72076D01*
X1606606Y72003D01*
Y71926D01*
X1607000Y71532D01*
Y67716D01*
X1604984Y65700D01*
Y64984D01*
X1603000Y63000D01*
G01X1603800Y54950D02*
Y56500D01*
X1603550Y56750D01*
Y58200D01*
G01X1603000Y63000D02*
Y60172D01*
X1603550Y59622D01*
Y58200D01*
G01X1657400Y49371D02*
Y55100D01*
X1652279Y60221D01*
X1648400D01*
G01X1602000Y87250D02*
Y84500D01*
G01X1607050Y58200D02*
X1608860D01*
X1609000Y58060D01*
X1611900D01*
G01D02*
Y61400D01*
X1614000Y63500D01*
G01X1619300Y58060D02*
Y59700D01*
X1620450Y60850D01*
Y62950D01*
X1619750Y63650D01*
G01D02*
X1618851D01*
X1614852Y59651D01*
Y53576D01*
X1614216Y52940D01*
X1611900D01*
G01X1617727Y46763D02*
X1614638D01*
X1614559Y46684D01*
G01X1617727Y46763D02*
Y48575D01*
X1618152Y49000D01*
X1624000D01*
X1624500Y49500D01*
Y50890D01*
G01D02*
Y52300D01*
X1623860Y52940D01*
X1619300D01*
G01X1622750Y43311D02*
X1624310D01*
X1625799Y44800D01*
X1627330D01*
G01X1622750Y43311D02*
Y46250D01*
X1622237Y46763D01*
X1621227D01*
G01X1627330Y44800D02*
X1629000D01*
X1630386Y43414D01*
Y41448D01*
G01X1648900Y45621D02*
X1640880D01*
X1626040Y60461D01*
Y64168D01*
X1622495Y67713D01*
X1616429D01*
X1615115Y69027D01*
Y70786D01*
G01X1592715Y70817D02*
Y69357D01*
X1595937Y66135D01*
Y51413D01*
X1603900Y43450D01*
Y41300D01*
G01D02*
X1604550Y40650D01*
X1610749D01*
X1613550Y37849D01*
Y34700D01*
G01X1617050D02*
Y38150D01*
X1615400Y39800D01*
G01X1673750Y46000D02*
X1671750Y44000D01*
X1662299D01*
X1659516Y46783D01*
X1653944D01*
X1651042Y49685D01*
X1643522D01*
X1640000Y53207D01*
Y60000D01*
G01D02*
X1642662Y62662D01*
Y69638D01*
X1640529Y71771D01*
X1631194D01*
X1630263Y72702D01*
Y74763D01*
X1634200Y78700D01*
Y83670D01*
X1632789Y85081D01*
Y88900D01*
X1630000Y91689D01*
Y95851D01*
X1632020Y97871D01*
G01X1632000Y73500D02*
X1635000Y76500D01*
X1638580D01*
G01D02*
X1641400D01*
X1643587Y74313D01*
Y54059D01*
X1644600Y53046D01*
Y51035D01*
X1645025Y50610D01*
X1650658D01*
X1650659Y50611D01*
X1651425D01*
X1654328Y47708D01*
X1660000D01*
X1662708Y45000D01*
X1669399D01*
X1673663Y49264D01*
Y52687D01*
X1671700Y54650D01*
Y55800D01*
G01X1628788Y97800D02*
X1629075Y97513D01*
Y89175D01*
X1628100Y88200D01*
Y82986D01*
X1626833Y81719D01*
Y76725D01*
X1625826Y75718D01*
Y74745D01*
X1624750Y73669D01*
Y72000D01*
G01Y69000D02*
X1623000D01*
X1622400Y69600D01*
X1621100D01*
G01X1638500Y87500D02*
X1641600D01*
G01X1629400Y106131D02*
X1632215Y103316D01*
Y100320D01*
X1633874Y98661D01*
Y91245D01*
X1637619Y87500D01*
G01D02*
X1638500D01*
G01X1646000D02*
Y84800D01*
X1648700Y82100D01*
G01X1641600Y87500D02*
X1646000D01*
G01X1638500Y90500D02*
X1641600D01*
G01X1635384Y105507D02*
X1636008Y104883D01*
Y92592D01*
X1638100Y90500D01*
G01D02*
X1638500D01*
G01X1641600D02*
X1644000D01*
X1646000Y92500D01*
G01X1597302Y162132D02*
X1599334Y160100D01*
X1601100D01*
X1602902Y158298D01*
X1604568D01*
X1605804Y157062D01*
Y155779D01*
X1606732Y154851D01*
X1608149D01*
X1609052Y153948D01*
Y152348D01*
X1609700Y151700D01*
X1615328D01*
X1616891Y150137D01*
G01X1613741Y121790D02*
X1612229Y120278D01*
X1605378D01*
X1604400Y119300D01*
G01X1598477Y118900D02*
X1602337D01*
X1602737Y119300D01*
X1604400D01*
G01X1595250Y118500D02*
X1596600D01*
X1597000Y118900D01*
X1598477D01*
G01X1595300Y121500D02*
X1596700D01*
X1597600Y122400D01*
X1605913D01*
X1606815Y123302D01*
X1608067D01*
X1609579Y121790D01*
X1610591D01*
G01X1632638Y112341D02*
X1633326D01*
X1639440Y106227D01*
X1640732D01*
G01X1682750Y80000D02*
X1681968D01*
X1678405Y83563D01*
X1673799D01*
X1672113Y85249D01*
Y89195D01*
X1671645Y89663D01*
X1667087D01*
X1663670Y93080D01*
Y96064D01*
X1662063Y97671D01*
Y98353D01*
X1662064Y98354D01*
Y99481D01*
X1658882Y102663D01*
X1655149D01*
X1653812Y104000D01*
X1651009D01*
X1648782Y106227D01*
X1640732D01*
G01X1632638Y115491D02*
Y114878D01*
X1636758Y110758D01*
X1639711D01*
X1642869Y107600D01*
X1649000D01*
X1651575Y105025D01*
X1654093D01*
X1655631Y103487D01*
X1659224D01*
X1662888Y99823D01*
Y98012D01*
X1665600Y95300D01*
X1666693D01*
G01X1606500Y110000D02*
X1607430D01*
X1609771Y112341D01*
X1610591D01*
G01X1592510Y140471D02*
X1594173D01*
X1594718Y139926D01*
X1601116D01*
X1603066Y141876D01*
X1606099D01*
X1608953Y139022D01*
Y127272D01*
X1609774Y126451D01*
X1611354D01*
X1612192Y127289D01*
Y129036D01*
X1613101Y129945D01*
X1614330D01*
X1616186Y128089D01*
X1616891D01*
G01X1594600Y131600D02*
Y132300D01*
X1595712Y133412D01*
X1601526D01*
X1602850Y132088D01*
X1604939D01*
G01X1589880Y134851D02*
X1593131Y131600D01*
X1594600D01*
G01X1600148Y142262D02*
X1594738D01*
X1592699Y144301D01*
Y145201D01*
X1591700Y146200D01*
G01X1596865Y145871D02*
X1598252D01*
X1599345Y146964D01*
X1601261D01*
X1602129Y146096D01*
X1603804D01*
G01X1616900Y143880D02*
X1616720Y143700D01*
X1613878D01*
X1612187Y145391D01*
X1609909D01*
X1608913Y146387D01*
Y147787D01*
X1608241Y148459D01*
X1606775D01*
X1604412Y146096D01*
X1603804D01*
G01X1610591Y150137D02*
X1608304D01*
X1603741Y154700D01*
X1597364D01*
X1594800Y157264D01*
Y159808D01*
X1591770Y162838D01*
X1588799D01*
G01X1596865Y149371D02*
Y150303D01*
X1595390Y151778D01*
G01X1604939Y128588D02*
X1605970D01*
X1609058Y125500D01*
Y124262D01*
X1609931Y123389D01*
X1611386D01*
X1612144Y124147D01*
Y125683D01*
X1613741Y127280D01*
Y128089D01*
G01X1630300Y101900D02*
X1628788Y100388D01*
Y97800D01*
G01X1601939Y128600D02*
X1604000Y126539D01*
Y124750D01*
G01D02*
X1607252D01*
X1607441Y124939D01*
G01X1677740Y152650D02*
X1675960D01*
G03X1675655Y152594I0J-857D01*
G03X1675242Y152038I168J-556D01*
G01Y151560D01*
G02X1673317I-962J0D01*
G01Y151995D01*
G03X1671392I-962J0D01*
G01Y151346D01*
G02X1669467I-962J0D01*
G01Y151544D01*
G03X1669042Y151969I-425J0D01*
G01X1667251D01*
G03X1666675Y151730I0J-813D01*
G01X1665986Y151038D01*
G02X1665020Y150638I-966J966D01*
G01X1664352D01*
G03X1663386Y150238I0J-1366D01*
G01X1662386Y149238D01*
G02X1662151Y149036I-1449J1448D01*
G01X1662066Y148951D01*
G02X1661190Y148588I-876J876D01*
G01X1653800D01*
G02X1652829Y149137I0J1133D01*
G01X1650519Y152988D01*
G02X1652312Y154064I896J538D01*
G01X1654686Y150138D01*
G01X1631094Y107673D02*
X1633218D01*
X1635384Y105507D01*
G01X1646200Y103800D02*
Y100414D01*
X1646000Y100214D01*
Y97500D01*
G01X1638500Y102500D02*
X1641600D01*
G01X1629489Y112341D02*
X1631061Y110769D01*
X1633731D01*
X1635718Y108782D01*
Y107924D01*
X1638500Y105142D01*
Y102500D01*
G01X1641600D02*
X1642600D01*
X1644488Y104388D01*
X1645612D01*
X1646200Y103800D01*
G01X1673415Y94797D02*
X1671203D01*
X1668956Y97044D01*
X1667972D01*
X1666477Y98539D01*
Y99777D01*
X1665458Y100796D01*
X1663081D01*
X1659316Y104561D01*
X1656020D01*
X1654431Y106150D01*
X1653410D01*
X1653409Y106151D01*
X1652149D01*
X1649109Y109191D01*
X1648387D01*
G01X1612103Y131920D02*
Y131913D01*
X1610591Y130401D01*
Y128089D01*
G01X1637870Y195077D02*
X1635800Y197147D01*
Y198448D01*
X1633994Y200254D01*
G01X1589700Y169000D02*
X1595400D01*
X1599438Y164962D01*
Y163369D01*
X1603222Y159585D01*
X1607442D01*
G01X1626339Y162735D02*
X1624830Y164244D01*
Y165253D01*
X1624826Y165257D01*
Y166386D01*
X1624789Y166423D01*
Y166425D01*
X1623714Y167500D01*
X1622897D01*
X1622037Y168360D01*
Y170937D01*
X1622523Y171423D01*
X1625593D01*
X1626479Y172309D01*
Y176034D01*
X1626910Y176465D01*
Y179903D01*
X1629003Y181996D01*
Y183996D01*
X1626074Y186925D01*
Y214380D01*
X1629419Y217725D01*
X1629595D01*
G01X1626124Y225250D02*
X1626045D01*
X1622524Y221729D01*
X1619166D01*
X1613095Y227800D01*
X1598204D01*
X1590525Y220121D01*
Y217033D01*
G01X1624064Y174709D02*
X1625000Y175645D01*
Y177808D01*
G01X1679250Y179511D02*
X1683562D01*
X1685921Y181870D01*
Y188067D01*
X1687846Y189992D01*
Y194636D01*
X1683847Y198635D01*
X1669091D01*
X1668600Y199126D01*
X1659751D01*
X1658777Y200100D01*
Y201164D01*
X1657033Y202908D01*
X1632123D01*
X1630836Y201621D01*
Y197560D01*
G01X1627326Y182759D02*
X1626451D01*
X1625000Y181308D01*
G01X1653496Y167799D02*
Y165596D01*
X1652200Y164300D01*
X1650900D01*
X1649950Y163350D01*
Y161171D01*
X1651536Y159585D01*
G01X1623750Y169500D02*
X1625561Y167689D01*
X1627684D01*
X1629489Y165884D01*
G01X1613500Y188500D02*
Y185396D01*
X1613053Y184949D01*
G01D02*
X1611000Y182896D01*
Y173400D01*
X1611500Y172900D01*
G01X1610500Y188500D02*
Y184931D01*
X1610554Y184877D01*
G01X1610500Y188500D02*
X1608100D01*
X1601400Y195200D01*
X1597809D01*
X1595800Y193191D01*
Y189960D01*
X1596730Y189030D01*
G01D02*
X1604031Y181729D01*
Y178923D01*
X1603493Y178385D01*
Y170271D01*
X1610591Y163173D01*
Y162735D01*
G01X1622217Y177809D02*
Y182393D01*
X1623872Y184048D01*
Y185576D01*
X1625149Y186853D01*
Y201452D01*
X1619958Y206643D01*
G01D02*
X1615362Y211239D01*
Y213507D01*
G01X1588847Y175137D02*
X1590637D01*
X1595800Y180300D01*
G01X1613002Y169672D02*
X1614406D01*
X1615734Y171000D01*
X1616700D01*
X1617679Y171979D01*
Y173161D01*
X1616527Y174313D01*
X1615562D01*
X1613925Y175950D01*
X1613250D01*
X1612000Y177200D01*
Y178564D01*
X1615553Y182117D01*
Y184908D01*
G01X1613741Y165885D02*
Y166447D01*
X1613002Y167186D01*
Y169672D01*
G01X1615553Y184908D02*
X1616500Y185855D01*
Y188500D01*
G01X1623346Y188276D02*
Y189806D01*
X1623281Y189871D01*
Y191683D01*
G01D02*
Y199820D01*
X1611770Y211331D01*
Y213507D01*
X1611761D01*
G01X1618940Y179280D02*
X1615480D01*
X1614000Y177800D01*
G01X1641800Y184400D02*
X1640200Y182800D01*
X1637500D01*
X1636649Y181949D01*
Y179288D01*
G01X1639649D02*
Y179949D01*
X1644433Y184733D01*
Y185415D01*
G01X1636649Y175788D02*
Y174014D01*
X1634170Y171535D01*
Y168900D01*
G01D02*
Y162017D01*
X1634993Y161194D01*
X1636700D01*
X1638309Y159585D01*
X1638938D01*
G01Y162735D02*
Y163262D01*
X1637396Y164804D01*
Y171243D01*
X1637825Y171672D01*
G01D02*
X1639649Y173496D01*
Y175788D01*
G01X1635788Y165885D02*
Y165061D01*
X1637421Y163428D01*
Y161879D01*
X1638118Y161182D01*
X1639715D01*
X1640500Y161967D01*
Y167052D01*
X1641114Y167666D01*
X1641731D01*
X1642439Y168374D01*
Y168376D01*
X1643288Y169225D01*
Y170089D01*
X1645606Y172407D01*
Y183605D01*
X1646100Y184099D01*
Y186700D01*
X1644950Y187850D01*
Y189600D01*
G01X1640910Y192600D02*
X1644950D01*
G01D02*
Y189600D01*
G01X1656599Y189608D02*
Y187505D01*
X1655574Y186480D01*
X1653926D01*
X1651619Y184173D01*
X1647624D01*
X1646600Y183149D01*
Y170397D01*
X1645395Y169192D01*
G01D02*
X1642088Y165885D01*
G01X1641375Y170017D02*
X1638938Y167580D01*
Y165884D01*
G01X1642649Y175788D02*
X1641375Y174514D01*
Y170017D01*
G01X1616286Y176515D02*
X1617021Y175780D01*
X1618940D01*
G01X1608731Y180819D02*
X1606538Y178626D01*
Y173091D01*
G01X1626935Y217775D02*
X1624163Y215003D01*
X1616987D01*
X1613387Y218603D01*
X1610993D01*
X1609130Y216740D01*
Y207100D01*
X1606388Y204358D01*
X1605358D01*
X1604326Y203326D01*
G01D02*
X1601550Y200550D01*
X1599740D01*
G01X1613741Y159585D02*
X1614385D01*
X1616000Y161200D01*
X1617493D01*
X1617515Y161222D01*
X1617517D01*
X1618492Y162197D01*
Y163379D01*
X1617499Y164372D01*
X1616264D01*
X1616263Y164373D01*
X1614369D01*
X1614368Y164372D01*
X1613114D01*
X1613113Y164373D01*
X1612625D01*
X1612200Y164798D01*
Y166500D01*
X1611303Y167397D01*
X1609967D01*
X1609670Y167100D01*
X1607877D01*
X1604625Y170352D01*
Y177938D01*
X1605219Y178532D01*
Y186871D01*
X1599669Y192421D01*
X1598006D01*
G01X1611761Y216250D02*
X1611016D01*
X1610098Y215332D01*
Y206198D01*
X1602080Y198180D01*
X1595700D01*
X1590058Y192538D01*
Y189008D01*
X1592267Y186799D01*
X1595181D01*
X1600563Y181417D01*
Y175496D01*
X1602668Y173391D01*
Y169795D01*
X1602977Y169486D01*
Y169457D01*
X1604275Y168159D01*
Y164859D01*
G01D02*
X1604559Y164575D01*
X1607925D01*
X1609000Y163500D01*
Y161900D01*
X1609800Y161100D01*
X1614499D01*
X1616134Y162735D01*
X1616890D01*
G01X1648450Y192600D02*
X1650076D01*
X1652120Y194644D01*
Y197620D01*
X1654200Y199700D01*
X1656200D01*
G01X1593020Y215129D02*
Y213205D01*
X1594225Y212000D01*
X1596082D01*
G01X1617078Y169100D02*
Y167981D01*
X1618428Y166631D01*
Y165292D01*
X1619382Y164338D01*
X1620689D01*
X1621649Y163378D01*
Y162141D01*
X1620040Y160532D01*
Y159585D01*
G01X1619846Y188276D02*
X1617600Y186030D01*
Y183980D01*
X1618275Y183305D01*
X1619672D01*
X1620663Y182314D01*
Y174562D01*
X1619724Y173623D01*
Y171910D01*
X1617078Y169264D01*
Y169100D01*
G01X1619781Y191683D02*
Y193779D01*
X1618373Y195187D01*
Y198793D01*
X1617166Y200000D01*
X1605648D01*
X1603337Y197689D01*
Y197666D01*
X1602346Y196675D01*
X1596943D01*
X1593218Y192950D01*
Y191776D01*
G01X1651064Y171331D02*
Y169287D01*
X1649898Y168121D01*
Y164698D01*
X1648326Y163126D01*
Y162674D01*
G01X1648349Y175788D02*
X1651064Y173073D01*
Y171331D01*
G01X1599580Y205480D02*
X1602580D01*
X1607430Y210330D01*
Y217445D01*
X1610288Y220303D01*
X1614197D01*
X1617797Y216703D01*
X1623299D01*
X1626184Y219588D01*
X1634112D01*
X1649092Y204608D01*
X1657738D01*
X1658838Y203508D01*
X1666623D01*
X1667248Y202883D01*
X1674551D01*
X1677099Y200335D01*
X1682199D01*
X1682705Y200841D01*
X1684207D01*
X1684713Y200335D01*
X1698109D01*
X1709327Y189117D01*
X1710647D01*
X1712951Y186813D01*
X1713751D01*
X1716364Y184200D01*
X1819750D01*
X1829750Y174200D01*
X1841900D01*
G01X1598641Y212000D02*
Y206419D01*
X1599580Y205480D01*
G01X1596240Y200550D02*
X1593837D01*
X1591606Y198319D01*
G01X1649621Y236279D02*
X1646787Y239113D01*
X1637502D01*
X1629005Y247610D01*
X1619214D01*
X1611149Y255675D01*
X1611105D01*
X1611104Y255676D01*
X1609654D01*
X1609653Y255675D01*
X1607203D01*
X1607202Y255676D01*
X1605752D01*
X1605751Y255675D01*
X1605064D01*
X1603739Y254350D01*
X1595486D01*
X1592656Y251520D01*
X1590544D01*
X1589592Y252472D01*
G01X1649621Y236279D02*
X1651672Y234228D01*
X1672383D01*
X1675179Y237024D01*
Y246447D01*
X1677373Y248641D01*
Y264820D01*
X1673839Y268354D01*
Y276039D01*
X1679100Y281300D01*
Y281593D01*
G01X1605200Y263833D02*
Y265581D01*
X1604775Y266006D01*
X1600810D01*
G01X1636914Y270900D02*
X1632963Y274851D01*
Y281685D01*
X1632287Y282361D01*
Y314781D01*
X1634808Y317302D01*
Y318786D01*
X1638990Y322968D01*
X1639847D01*
X1641055Y324176D01*
G01X1654937Y338572D02*
X1653927Y337562D01*
X1652542D01*
X1643216Y328236D01*
Y323416D01*
X1639749Y319949D01*
Y318975D01*
X1638775Y318001D01*
X1637536D01*
X1633712Y314177D01*
Y282952D01*
X1634388Y282276D01*
Y275968D01*
X1635541Y274815D01*
X1636684D01*
G01X1643750Y279500D02*
Y283050D01*
X1644300Y283600D01*
Y288050D01*
G01X1643750Y267900D02*
Y279500D01*
G01X1624798Y241937D02*
X1625179Y241556D01*
Y238972D01*
X1628191Y235960D01*
X1637733D01*
X1644681Y229012D01*
X1672216D01*
X1672642Y229438D01*
X1672649D01*
X1678300Y235089D01*
Y235584D01*
X1678378Y235662D01*
Y245861D01*
X1680117Y247600D01*
Y267931D01*
X1677437Y270611D01*
Y272237D01*
X1679100Y273900D01*
G01X1665900Y447000D02*
X1664299D01*
X1661699Y444400D01*
Y408720D01*
X1664122Y406297D01*
Y382664D01*
X1661258Y379800D01*
Y375383D01*
X1662191Y374450D01*
Y341610D01*
X1658758Y338177D01*
Y335883D01*
X1657750Y334875D01*
X1653427D01*
X1645741Y327189D01*
Y317542D01*
X1642598Y314399D01*
X1636700D01*
X1635137Y312836D01*
Y285770D01*
X1636059Y284848D01*
X1638655D01*
X1639217Y284286D01*
Y269984D01*
X1638190Y268957D01*
X1635922D01*
X1629289Y275590D01*
X1625264D01*
X1623447Y273773D01*
Y273273D01*
G01X1679100Y289500D02*
Y289273D01*
X1675450Y285623D01*
Y281486D01*
X1671164Y277200D01*
Y267244D01*
X1674369Y264039D01*
Y249422D01*
X1672504Y247557D01*
Y239200D01*
X1670681Y237377D01*
X1662046D01*
X1656598Y242825D01*
X1637728D01*
X1630150Y250403D01*
X1621900D01*
X1620318Y251985D01*
Y254673D01*
X1620250Y254741D01*
G01X1620240Y257660D02*
Y257083D01*
X1618587Y255430D01*
Y255038D01*
X1618000Y254451D01*
Y251928D01*
X1620568Y249360D01*
X1629731D01*
X1638228Y240863D01*
X1657248D01*
X1661892Y236219D01*
X1670832D01*
X1673429Y238816D01*
Y247173D01*
X1675294Y249038D01*
Y264423D01*
X1672089Y267628D01*
Y276765D01*
X1672887Y277563D01*
Y277614D01*
X1676375Y281102D01*
Y284770D01*
X1678198Y286593D01*
X1679100D01*
G01X1641296Y299000D02*
X1639058D01*
X1638633Y298575D01*
Y292368D01*
X1640318Y290683D01*
Y283831D01*
X1640317Y283830D01*
Y269528D01*
X1638645Y267856D01*
X1637735D01*
X1637734Y267857D01*
X1635466D01*
X1631793Y271530D01*
X1623769D01*
X1623689Y271610D01*
X1622758D01*
X1621784Y272584D01*
Y272760D01*
X1621522D01*
X1616782Y277500D01*
X1594500D01*
G01X1593250Y245553D02*
X1595803D01*
X1596600Y246350D01*
G01X1644700Y260900D02*
X1647100Y263300D01*
Y282515D01*
X1646300Y283315D01*
Y287050D01*
X1647300Y288050D01*
G01X1637269Y264421D02*
X1641179D01*
X1644700Y260900D01*
G01X1589954Y229054D02*
X1620445D01*
X1622586Y226913D01*
X1627029D01*
X1628624Y225318D01*
G01X1610290Y265352D02*
X1611427Y264215D01*
X1617355D01*
X1624150Y257420D01*
Y253909D01*
X1626426Y251633D01*
X1630229D01*
X1638112Y243750D01*
X1656982D01*
X1661833Y238899D01*
X1670161D01*
X1671579Y240317D01*
Y248005D01*
X1672485Y248911D01*
Y264614D01*
X1670239Y266860D01*
Y277685D01*
X1674475Y281921D01*
Y287227D01*
X1679100Y291852D01*
Y292000D01*
G01X1610550Y222670D02*
X1610250D01*
X1608670Y221090D01*
X1605760D01*
G01X1601200Y219000D02*
X1604930D01*
X1605760Y219830D01*
Y221090D01*
G01X1598641Y219000D02*
Y221427D01*
X1599076Y221862D01*
X1600724D01*
X1601200Y221386D01*
Y219000D01*
G01X1605760Y221090D02*
X1603942D01*
X1601470Y223562D01*
X1596561D01*
X1592870Y219871D01*
Y217900D01*
G01X1604222Y268107D02*
X1600421D01*
X1598214Y265900D01*
X1597000D01*
G01X1652991Y329059D02*
X1651259D01*
X1648911Y326711D01*
G01X1646250Y311000D02*
X1649575D01*
X1650473Y311898D01*
Y319500D01*
G01X1648911Y326711D02*
X1647942Y325742D01*
Y320400D01*
X1648842Y319500D01*
X1650473D01*
G01X1613000Y337900D02*
X1618023Y342923D01*
X1620292D01*
X1620717Y343348D01*
Y344591D01*
G01X1641055Y324176D02*
X1641791Y324912D01*
Y328827D01*
X1658241Y345277D01*
Y370430D01*
X1656806Y371865D01*
Y392874D01*
X1658849Y394917D01*
Y446060D01*
X1670574Y457785D01*
Y459290D01*
X1676304Y465020D01*
Y474074D01*
X1677694Y475464D01*
X1715729D01*
X1719089Y472104D01*
G01X1644300Y288050D02*
X1642450D01*
X1641296Y289204D01*
Y296441D01*
G01X1605090Y336004D02*
X1606296Y334798D01*
X1612974D01*
X1619312Y341136D01*
X1619897D01*
G01X1651867Y484741D02*
X1651026Y483900D01*
X1645346D01*
X1643676Y482230D01*
Y478873D01*
X1644228Y478321D01*
Y478320D01*
X1644229Y478319D01*
Y475481D01*
X1644228Y475480D01*
Y468207D01*
X1636912Y460891D01*
Y460173D01*
X1636911Y460172D01*
Y459406D01*
X1636912Y459405D01*
Y429243D01*
X1643089Y423066D01*
Y410199D01*
X1635839Y402949D01*
Y374705D01*
X1634502Y373368D01*
Y356518D01*
X1632728Y354744D01*
Y350910D01*
X1630718Y348900D01*
X1628455D01*
X1626675Y347120D01*
Y343774D01*
X1623498Y340597D01*
X1620436D01*
X1619897Y341136D01*
G01X1651926Y482197D02*
X1651248Y482875D01*
X1645630D01*
X1644601Y481846D01*
Y479257D01*
X1645153Y478705D01*
Y478704D01*
X1645154Y478703D01*
Y475097D01*
X1645153Y475096D01*
Y472866D01*
X1645154Y472865D01*
Y472099D01*
X1645153Y472098D01*
Y467823D01*
X1637837Y460507D01*
Y429627D01*
X1644014Y423450D01*
Y409815D01*
X1636764Y402565D01*
Y374180D01*
X1635427Y372843D01*
Y356134D01*
X1633653Y354360D01*
Y350526D01*
X1630936Y347809D01*
X1628814D01*
X1627700Y346695D01*
Y343349D01*
X1622348Y337997D01*
X1620536D01*
X1619897Y338636D01*
G01X1589000Y300560D02*
X1593090D01*
X1595903Y303373D01*
Y313762D01*
X1600977Y318836D01*
X1625565D01*
X1635879Y329150D01*
X1636968D01*
X1654990Y347172D01*
Y368567D01*
X1651493Y372064D01*
Y375983D01*
X1651163Y376313D01*
Y384645D01*
G01X1649530Y375170D02*
Y371988D01*
X1654065Y367453D01*
Y347556D01*
X1636584Y330075D01*
X1635495D01*
X1625281Y319861D01*
X1600552D01*
X1594878Y314187D01*
Y304810D01*
X1593188Y303120D01*
X1589000D01*
G01X1631419Y319313D02*
X1635355Y323249D01*
Y324228D01*
G01X1648296Y301559D02*
X1650441D01*
X1651100Y300900D01*
Y292050D01*
X1651500Y291650D01*
G01X1647300Y288050D02*
X1647950D01*
X1652250Y283750D01*
Y283250D01*
G01X1654750Y314750D02*
Y313029D01*
X1650634Y308913D01*
X1643235D01*
X1639413Y312735D01*
G01X1660934Y387883D02*
X1659656Y386605D01*
Y373100D01*
X1661091Y371665D01*
Y342072D01*
X1657658Y338639D01*
Y336921D01*
X1656873Y336136D01*
X1653132D01*
X1644641Y327645D01*
Y321142D01*
X1642022Y318523D01*
G01D02*
X1639842Y316343D01*
X1639040D01*
G01X1591471Y311952D02*
Y309230D01*
X1593100Y307601D01*
Y306105D01*
X1592675Y305680D01*
X1589000D01*
G01X1624900Y377400D02*
Y376300D01*
X1626100Y375100D01*
Y373700D01*
G01X1620717Y365591D02*
X1618293D01*
X1617989Y365895D01*
Y367892D01*
X1618248Y368151D01*
X1620717D01*
G01X1626100Y373700D02*
X1624700D01*
X1623900Y372900D01*
Y368800D01*
X1623251Y368151D01*
X1620717D01*
G01Y355091D02*
X1625891D01*
X1626600Y355800D01*
Y356893D01*
G01X1620717Y357651D02*
X1618306D01*
X1617994Y357339D01*
Y355356D01*
X1618259Y355091D01*
X1620717D01*
G01X1626600Y356893D02*
Y358700D01*
X1626217Y359083D01*
Y360391D01*
G01X1613717Y360211D02*
X1608096D01*
X1607412Y360895D01*
G01X1620717Y347151D02*
X1623451D01*
X1623950Y347650D01*
Y351513D01*
X1624487Y352050D01*
X1626200D01*
G01X1620717Y344591D02*
X1618256D01*
X1618085Y344762D01*
Y346762D01*
X1618474Y347151D01*
X1620717D01*
G01X1608850Y343835D02*
X1607363Y345322D01*
Y349750D01*
X1607788Y350175D01*
X1610434D01*
X1610898Y349711D01*
X1613717D01*
G01Y368151D02*
X1611453D01*
X1611028Y367726D01*
Y362548D01*
X1610370Y361890D01*
G01X1595076Y353237D02*
X1616124D01*
X1616550Y353663D01*
Y356940D01*
X1615839Y357651D01*
X1613717D01*
G01X1610140Y358350D02*
Y358076D01*
X1610565Y357651D01*
X1613717D01*
G01X1609271Y348166D02*
X1610286Y347151D01*
X1613717D01*
G01X1599300Y350200D02*
X1600700Y351600D01*
X1615515D01*
X1616380Y350735D01*
Y348687D01*
X1614844Y347151D01*
X1613717D01*
G01X1588852Y366117D02*
X1591852D01*
G01X1671050Y481000D02*
Y479582D01*
X1653748Y462280D01*
Y404403D01*
X1648600Y399255D01*
Y376100D01*
X1649530Y375170D01*
G01X1588852Y369117D02*
X1591852D01*
G01X1643150Y348692D02*
X1642995D01*
X1642887Y348800D01*
X1640000D01*
G01X1629300Y385400D02*
X1632413Y388513D01*
Y402387D01*
X1631700Y403100D01*
X1630000D01*
X1629000Y404100D01*
Y405827D01*
X1630059Y406886D01*
X1632314D01*
X1638838Y413410D01*
Y420938D01*
X1632638Y427138D01*
Y466828D01*
X1635568Y469758D01*
Y490067D01*
X1641465Y495964D01*
X1641963D01*
G01X1630550Y401300D02*
X1628026Y403824D01*
Y406472D01*
X1629265Y407711D01*
X1631592D01*
X1638013Y414132D01*
Y420596D01*
X1631813Y426796D01*
Y428352D01*
X1628439Y431726D01*
Y439800D01*
G01X1630300Y395300D02*
Y396200D01*
X1626326Y400174D01*
Y407177D01*
X1628560Y409411D01*
X1630330D01*
X1632590Y411671D01*
X1632587Y411674D01*
Y414023D01*
X1636313Y417749D01*
Y419891D01*
X1633004Y423200D01*
X1631959D01*
X1626326Y428833D01*
Y450625D01*
X1627800Y452099D01*
Y464899D01*
X1633075Y470174D01*
G01X1651486Y500217D02*
X1655317Y496386D01*
Y480265D01*
X1655318Y480264D01*
Y478856D01*
X1648281Y471819D01*
Y470805D01*
X1648278Y470802D01*
Y466527D01*
X1644636Y462885D01*
Y429119D01*
X1647139Y426616D01*
Y407765D01*
X1639889Y400515D01*
Y370902D01*
X1640001Y370790D01*
G01X1628843Y411524D02*
Y412399D01*
X1630386Y413942D01*
G01X1596800Y430500D02*
X1602000D01*
X1602500Y430000D01*
X1605250D01*
G01X1628439Y439800D02*
Y450239D01*
X1630300Y452100D01*
G01X1629913Y463000D02*
X1630200Y462713D01*
Y457175D01*
G01X1630750Y404800D02*
X1632073D01*
X1639663Y412390D01*
Y421644D01*
X1633486Y427821D01*
Y427855D01*
X1633463Y427878D01*
Y462288D01*
X1640802Y469627D01*
Y476900D01*
X1640250Y477452D01*
Y483650D01*
X1644543Y487943D01*
Y496757D01*
X1637100Y504200D01*
Y515200D01*
X1639900Y518000D01*
X1719500D01*
X1723000Y521500D01*
Y555500D01*
G01X1622700Y461900D02*
Y459510D01*
X1623300Y458910D01*
G01X1626283Y419548D02*
X1629459D01*
X1630120Y418887D01*
G01X1615061Y463157D02*
Y466433D01*
X1615307Y466679D01*
G01X1621000Y452000D02*
X1621612D01*
X1623527Y453915D01*
G01X1612500Y411800D02*
Y414700D01*
G01X1648330Y504544D02*
X1650544Y502330D01*
X1653141D01*
X1656496Y498975D01*
X1658482D01*
G01X1656197Y503552D02*
X1651647Y508102D01*
X1643169D01*
X1641470Y506403D01*
G01X1649545Y515215D02*
X1649998Y514762D01*
X1654944D01*
X1667790Y501916D01*
X1674286D01*
X1685447Y490755D01*
X1712354D01*
X1715489Y493890D01*
G01X1650944Y505166D02*
X1649708Y506402D01*
X1647624D01*
X1646517Y505295D01*
Y503793D01*
X1650093Y500217D01*
X1651486D01*
G01X1641756Y558000D02*
Y561600D01*
X1643803Y563647D01*
Y570630D01*
G01X1645256Y558000D02*
Y563618D01*
X1646756Y565118D01*
G01X1600950Y618250D02*
X1605677Y622977D01*
X1707705D01*
X1714475Y616207D01*
Y586652D01*
X1716596Y584531D01*
Y562654D01*
X1719200Y560050D01*
Y545591D01*
X1721507Y543284D01*
Y532641D01*
X1719200Y530334D01*
Y530193D01*
X1716213Y527206D01*
X1700355D01*
X1699425Y526276D01*
Y520628D01*
X1699861Y520192D01*
G01X1603550Y618250D02*
Y619438D01*
X1606064Y621952D01*
X1707280D01*
X1713450Y615782D01*
Y592247D01*
X1713513Y592184D01*
Y586269D01*
X1715671Y584111D01*
Y562129D01*
X1718150Y559650D01*
Y545332D01*
X1720582Y542900D01*
Y533025D01*
X1715788Y528231D01*
X1699930D01*
X1698400Y526701D01*
Y521331D01*
X1697261Y520192D01*
G01X1661250Y16500D02*
X1656500D01*
G01D02*
Y18500D01*
X1656000Y19000D01*
Y30634D01*
X1656425Y31059D01*
X1658750D01*
G01X1656500Y16500D02*
X1653356D01*
X1652300Y15444D01*
Y12300D01*
X1653100Y11500D01*
G01X1651250Y25941D02*
X1653941D01*
X1654500Y26500D01*
Y32038D01*
X1657462Y35000D01*
X1659183D01*
X1660944Y36761D01*
G01X1759525Y56400D02*
Y43875D01*
X1761663Y41737D01*
Y29509D01*
X1758140Y25986D01*
X1733024D01*
X1728887Y21849D01*
Y20293D01*
X1734242Y14938D01*
Y11169D01*
X1730186Y7113D01*
X1695163D01*
X1691050Y3000D01*
X1691000D01*
G01X1673500Y-16850D02*
X1679720Y-10630D01*
X1683210D01*
G01D02*
X1690330D01*
X1699788Y-20088D01*
X1758762D01*
X1761872Y-16978D01*
Y-7220D01*
G01X1704824Y90049D02*
Y83744D01*
X1712420Y76148D01*
Y76140D01*
X1717050Y71510D01*
Y69210D01*
X1718990Y67270D01*
X1722220D01*
X1722450Y67500D01*
X1729077D01*
X1731119Y69542D01*
X1750108D01*
X1753700Y65950D01*
Y46986D01*
X1757659Y43027D01*
X1757676D01*
X1760038Y40665D01*
Y30183D01*
X1757466Y27611D01*
X1732350D01*
X1727262Y22523D01*
Y19619D01*
X1732617Y14264D01*
Y11843D01*
X1729512Y8738D01*
X1694439D01*
X1691523Y5822D01*
X1682993D01*
X1680034Y2863D01*
G01X1661563Y72028D02*
X1661658D01*
Y70219D01*
X1665127Y66750D01*
X1673500D01*
X1674250Y66000D01*
X1676400D01*
G01D02*
X1678201D01*
X1681040Y63161D01*
X1685661D01*
G01X1700130Y77700D02*
X1704600D01*
X1707750Y74550D01*
Y72000D01*
G01X1700130Y77700D02*
X1698521Y76091D01*
X1696290D01*
X1693900Y73701D01*
Y73300D01*
G01X1666693Y95300D02*
X1668550D01*
X1673078Y90772D01*
Y85593D01*
X1674183Y84488D01*
X1679758D01*
X1681246Y83000D01*
X1682750D01*
G01X1654685Y112341D02*
X1656237Y110789D01*
Y108651D01*
X1658679Y106209D01*
X1660000D01*
X1663765Y102444D01*
X1665458D01*
X1665459Y102445D01*
X1666141D01*
X1666142Y102444D01*
X1666456D01*
X1668247Y100653D01*
G01X1697800Y92200D02*
X1700800D01*
G01X1697800Y94612D02*
Y92200D01*
G01X1688350Y71000D02*
Y68000D01*
G01X1678000Y81600D02*
Y79232D01*
X1679147Y78085D01*
G01D02*
X1680682Y76550D01*
X1685929D01*
X1688350Y74129D01*
Y71000D01*
G01X1692285Y94612D02*
Y94603D01*
X1692243Y94561D01*
X1692225D01*
X1691800Y94136D01*
Y92200D01*
G01D02*
X1694800D01*
G01X1708610Y85121D02*
Y81691D01*
X1718400Y71901D01*
Y69600D01*
X1719500Y68500D01*
X1721713D01*
X1724513Y71300D01*
X1728460D01*
G01X1680736Y47039D02*
X1678289D01*
X1677250Y46000D01*
G01X1675200Y55800D02*
Y59300D01*
G01X1670500Y64500D02*
X1670775D01*
X1675200Y60075D01*
Y59300D01*
G01X1682638Y54311D02*
X1680603Y56346D01*
X1677346D01*
X1676800Y55800D01*
X1675200D01*
G01X1691655Y77991D02*
Y78545D01*
X1688700Y81500D01*
X1687750D01*
X1686250Y80000D01*
G01X1694155Y77991D02*
Y78545D01*
X1689700Y83000D01*
X1686250D01*
G01X1703250Y49880D02*
X1694630D01*
X1693750Y49000D01*
G01D02*
X1693650Y48900D01*
Y45050D01*
X1694200Y44500D01*
G01X1703250Y52440D02*
X1697500D01*
X1695940Y54000D01*
X1693250D01*
G01X1703250Y57560D02*
X1698373D01*
X1695772Y60161D01*
G01X1694070Y64800D02*
Y63480D01*
X1695772Y61778D01*
Y60161D01*
G01X1703727Y74152D02*
X1702882Y74997D01*
X1696647D01*
X1695605Y73955D01*
Y67305D01*
X1697891Y65019D01*
Y60984D01*
X1698755Y60120D01*
X1703250D01*
G01X1703727Y74152D02*
X1704558Y73321D01*
Y69656D01*
X1705714Y68500D01*
X1707750D01*
G01X1662600Y49000D02*
X1665699D01*
X1667497Y47202D01*
G01X1662600Y49000D02*
X1660719D01*
X1660348Y49371D01*
X1657400D01*
G01X1663000Y76400D02*
X1665300D01*
X1670500Y81600D01*
G01X1656900Y63971D02*
X1660469D01*
X1661575Y62865D01*
Y61409D01*
X1662500Y60484D01*
Y58800D01*
G01X1656900Y63971D02*
Y66099D01*
X1654700Y68299D01*
Y74484D01*
X1656616Y76400D01*
X1663000D01*
G01X1667000Y56000D02*
X1669500Y53500D01*
Y51500D01*
G01X1656600Y73614D02*
Y69856D01*
X1663000Y63456D01*
Y62000D01*
X1665677Y59323D01*
Y57323D01*
X1667000Y56000D01*
G01X1680750Y44000D02*
Y42650D01*
X1681850Y41550D01*
X1696150D01*
X1697100Y42500D01*
X1743001D01*
X1743600Y43099D01*
Y43900D01*
G01X1678974Y51626D02*
X1679377Y51223D01*
X1682625D01*
G01X1678627Y54616D02*
Y51973D01*
X1678974Y51626D01*
G01X1684248Y56746D02*
X1682864D01*
X1681939Y57671D01*
Y59736D01*
X1682158Y59955D01*
G01D02*
X1682364Y60161D01*
X1685661D01*
G01X1676400Y69500D02*
X1678400D01*
X1680958Y66942D01*
G01X1690500Y73950D02*
Y67071D01*
X1689129Y65700D01*
X1682200D01*
X1680958Y66942D01*
G01X1686138Y54311D02*
Y51236D01*
X1686125Y51223D01*
G01X1686138Y54311D02*
X1687383D01*
X1687694Y54000D01*
X1689750D01*
G01X1692470Y69740D02*
Y67730D01*
X1689161Y64421D01*
Y63161D01*
G01Y60161D02*
Y63161D01*
G01X1692272Y60161D02*
X1689161D01*
G01X1711250Y68500D02*
Y72000D01*
G01D02*
X1713600D01*
X1715100Y70500D01*
G01X1684236Y47039D02*
Y44014D01*
X1684250Y44000D01*
G01D02*
X1684350Y43900D01*
X1688060D01*
G01D02*
X1688500D01*
X1689300Y44700D01*
Y48050D01*
X1690250Y49000D01*
G01X1665876Y62596D02*
X1669172Y59300D01*
X1671700D01*
G01X1659196Y70291D02*
Y69276D01*
X1665876Y62596D01*
G01X1735914Y104850D02*
X1733277Y102213D01*
G03Y100851I681J-681D01*
G01X1733716Y100412D01*
G02X1732354Y99050I-681J-681D01*
G01X1731915Y99489D01*
G03X1730553Y98127I-681J-681D01*
G01X1730946Y97734D01*
G02X1729584Y96372I-681J-681D01*
G01X1728978Y96978D01*
G03X1728042I-468J-468D01*
G01X1727799Y96735D01*
G02X1726562Y95605I-13121J13121D01*
G02X1720287Y93006I-6275J6275D01*
G01X1707186D01*
G02X1704639Y94061I0J3602D01*
G01X1697896Y100804D01*
G03X1696998Y101176I-898J-898D01*
G01X1685985D01*
G02X1682030Y102814I0J5593D01*
G01X1677000Y107844D01*
G02X1675544Y111358I3514J3515D01*
G01Y112081D01*
G03X1674481Y114647I-3629J0D01*
G01X1673296Y115832D01*
G01X1673415Y94797D02*
X1675557D01*
X1679312Y91042D01*
Y89438D01*
X1682750Y86000D01*
G01X1672222Y98726D02*
X1673024D01*
X1682750Y89000D01*
G01X1656000Y88000D02*
X1652500D01*
X1652000Y87500D01*
G01X1659000Y88000D02*
X1656000D01*
G01X1661900Y92400D02*
X1661400Y91900D01*
X1657900D01*
X1657000Y91000D01*
X1656000D01*
G01X1652000Y92500D02*
X1654199D01*
X1655699Y91000D01*
X1656000D01*
G01X1682750Y95000D02*
Y96315D01*
X1681969Y97096D01*
X1679345D01*
X1678846Y97595D01*
G01X1678845D02*
X1674992Y101448D01*
X1668618D01*
X1666797Y103269D01*
X1665881D01*
X1662675Y106475D01*
G01X1657835Y109191D02*
X1659603Y107423D01*
X1661727D01*
X1662675Y106475D01*
G01X1681586Y141438D02*
G02X1679250Y140322I-2748J2750D01*
G02X1678838Y140300I-413J3865D01*
G01X1670733D01*
G01D02*
X1668993D01*
G03X1667468Y139668I0J-2156D01*
G01X1667466Y139666D01*
G02X1666100Y139100I-1366J1365D01*
G01X1664500D01*
G03X1661167Y137720I-1J-4713D01*
G01X1660986Y137538D01*
G01X1706065Y141740D02*
X1702746Y145059D01*
G03X1699780Y146288I-2966J-2965D01*
G01X1699183D01*
G02X1698221Y147250I0J962D01*
G01Y148358D01*
G03X1696296I-962J0D01*
G01Y147251D01*
G02X1694371I-962J0D01*
G01Y148404D01*
G03X1692446I-962J0D01*
G01Y147251D01*
G02X1690521I-962J0D01*
G01Y148404D01*
G03X1688596I-962J0D01*
G01Y147250D01*
G02X1686671I-962J0D01*
G01Y148404D01*
G03X1684746I-963J0D01*
G01Y147250D01*
G02X1683784Y146288I-962J0D01*
G01X1679019D01*
G02X1677710Y146830I0J1851D01*
G03X1676880Y147174I-830J-830D01*
G01X1668491D01*
G03X1665666Y146004I0J-3995D01*
G03X1664747Y144362I1007J-1642D01*
G02X1663018I-865J0D01*
G01Y145094D01*
G02X1663563Y146413I1868J0D01*
G01X1664186Y147038D01*
G01X1706065Y141740D02*
X1708897Y138908D01*
X1709984Y137820D01*
G03X1711422Y137225I1437J1438D01*
G02X1712880Y136621I0J-2062D01*
G01X1713059Y136442D01*
G03X1714488Y135850I1429J1429D01*
G01X1727823D01*
G03X1728789Y136250I0J1366D01*
G01X1706296Y158650D02*
X1708713D01*
G02X1710089Y158080I0J-1946D01*
G01X1718501Y149668D01*
G02Y147501I-1083J-1083D01*
G01X1718500Y147500D01*
G03X1718000Y146293I1207J-1207D01*
G01Y146292D01*
G03X1720042Y144250I2042J0D01*
G01X1720072D01*
G03X1721400Y144800I0J1878D01*
G01X1721875Y145275D01*
G02X1723264Y145850I1389J-1390D01*
G01X1651536Y146988D02*
Y146509D01*
G03X1651838Y145780I1031J0D01*
G03X1652664Y145438I826J826D01*
G01X1660879D01*
G03X1662086Y145938I0J1707D01*
G01X1662162Y146013D01*
G03X1662586Y147038I-1027J1025D01*
G01Y147414D01*
G02X1662886Y148138I1024J0D01*
G02X1663972Y148588I1086J-1086D01*
G01X1675002D01*
G03X1675746Y148896I0J1053D01*
G01X1676899Y150049D01*
G02X1678471Y150700I1572J-1572D01*
G01X1679028D01*
G02X1679585Y150143I0J-557D01*
G01Y149183D01*
G03X1681510I962J0D01*
G01Y150142D01*
G02X1682660Y151292I1150J0D01*
G01X1684033D01*
G03X1684995Y152254I0J962D01*
G01Y152265D01*
G02X1686920I962J0D01*
G01Y152254D01*
G03X1688845I963J0D01*
G01Y152265D01*
G02X1690770I962J0D01*
G01Y152254D01*
G03X1691732Y151292I962J0D01*
G01X1697694D01*
G01D02*
X1700098D01*
G02X1700400Y151168I1J-427D01*
G01X1713324Y138242D01*
G03X1716202Y137050I2878J2878D01*
G01X1727102D01*
G03X1727958Y137906I0J856D01*
G01Y138402D01*
G03X1727579Y139317I-1294J0D01*
G03X1727258Y139450I-321J-321D01*
G01X1726539D01*
G01X1720164Y139500D02*
Y140120D01*
G03X1719234Y141050I-930J0D01*
G01X1717047D01*
G02X1715893Y141528I0J1632D01*
G01X1702960Y154461D01*
G03X1701289Y155153I-1671J-1672D01*
G01X1696238D01*
G03X1695276Y154191I0J-962D01*
G01Y154180D01*
G02X1693351I-962J0D01*
G01Y154191D01*
G03X1692389Y155153I-962J0D01*
G01X1683823D01*
G03X1683289Y154932I0J-755D01*
G01X1681411Y153054D01*
G02X1680435Y152650I-976J977D01*
G01X1677740D01*
G01X1691596Y162922D02*
X1691552Y162966D01*
X1686813D01*
G03X1684256Y161907I0J-3616D01*
G01X1682849Y160500D01*
G02X1681977I-436J436D01*
G01X1681140Y161337D01*
G03X1679772Y159969I-684J-684D01*
G01X1680445Y159297D01*
G02Y158095I-601J-601D01*
G01X1679599Y157248D01*
Y157249D01*
X1679598D01*
G02X1677550Y156400I-2049J2048D01*
G01X1671160D01*
G03X1670010Y155923I1J-1627D01*
G01X1669586Y155500D01*
G02X1668188Y154921I-1398J1398D01*
G01X1666859D01*
G03X1665000Y154151I0J-2629D01*
G01X1664135Y153286D01*
G01X1707042Y147319D02*
Y147311D01*
X1716094Y138259D01*
G03X1716840Y137950I746J746D01*
G01X1720589D01*
G03X1722595Y138781I0J2837D01*
G01X1723314Y139500D01*
G01X1701455Y153083D02*
G03X1701580Y152782I426J1D01*
G01X1707042Y147319D01*
G01X1693586Y142438D02*
X1699206D01*
G02X1699561Y142291I0J-502D01*
G01X1706280Y135570D01*
G03X1713322Y132653I7042J7042D01*
G01X1714027D01*
G02X1715000Y132250I0J-1376D01*
G03X1716449Y131650I1449J1449D01*
G01X1724815D01*
G03X1725119Y131776I0J430D01*
G01X1726464Y133121D01*
Y133200D01*
G01X1673296Y115832D02*
X1671503Y117625D01*
G03X1668799Y118745I-2704J-2704D01*
G01X1668105D01*
G02X1666526Y119399I0J2233D01*
G01X1664135Y121790D01*
G01X1723314Y104850D02*
Y104470D01*
G03X1723962Y103822I648J0D01*
G01X1728416D01*
G03Y105748I0J963D01*
G01X1725579D01*
G02Y107674I0J963D01*
G01X1727490D01*
G03Y109600I0J963D01*
G01X1717297D01*
G02X1715253Y110447I0J2890D01*
G01X1710520Y115180D01*
G03X1707519Y116423I-3001J-3002D01*
G01X1697872D01*
G01X1660985Y128089D02*
Y126916D01*
G03X1661463Y126438I478J0D01*
G01X1667420D01*
G03X1668386Y126838I0J1366D01*
G01X1668594Y127046D01*
G02X1670491Y127832I1897J-1897D01*
G02X1670783Y127819I2J-3233D01*
G01X1677617D01*
G02X1678755Y127347I-1J-1610D01*
G01X1678914Y127189D01*
G03X1679250Y126974I657J656D01*
G03X1679570Y126917I320J871D01*
G01X1683161D01*
G02X1685674Y125876I0J-3554D01*
G01X1690993Y120557D01*
G02Y119347I-606J-605D01*
G01X1690992Y119346D01*
G03Y118136I606J-605D01*
G01X1691144Y117984D01*
G03X1692354I605J606D01*
G01X1692355Y117985D01*
G02X1693565I605J-606D01*
G01X1694841Y116709D01*
G03X1695531Y116423I690J689D01*
G01X1697872D01*
G01X1690970Y103101D02*
X1686507D01*
G02X1683182Y104478I-1J4701D01*
G01X1679250Y108412D01*
X1679246Y108416D01*
G02X1677510Y112607I4191J4191D01*
G01Y112611D01*
G03X1676113Y115983I-4768J0D01*
G01X1674085Y118011D01*
G02X1673613Y118893I1222J1221D01*
G01Y119035D01*
G03X1672751Y121116I-2943J0D01*
G03X1667024Y123338I-5727J-6269D01*
G01X1660232D01*
G03X1658788Y122740I0J-2042D01*
G01X1658736Y122688D01*
G02X1657835Y121790I-269701J269701D01*
G01X1690970Y103101D02*
X1697166D01*
G02X1699222Y102249I0J-2908D01*
G01X1705561Y95910D01*
G03X1707635Y95051I2074J2074D01*
G01X1719811D01*
G03X1725196Y97282I-1J7616D01*
G01X1735914Y108000D01*
G01X1667284Y131239D02*
Y132023D01*
G03X1666238Y133069I-1046J0D01*
G01X1660822D01*
G02Y134995I0J963D01*
G01X1666854D01*
G03X1667156Y135120I0J427D01*
G01X1668755Y136719D01*
G02X1672511Y138275I3756J-3755D01*
G01X1676372D01*
G01X1726464Y120600D02*
X1726902Y121037D01*
G03X1726441Y122150I-461J461D01*
G01X1718776D01*
G02X1717950Y122976I0J826D01*
G01Y124227D01*
G03X1716777Y125400I-1173J0D01*
G01X1708698D01*
G02X1705687Y126647I0J4259D01*
G01X1704187Y128147D01*
G03X1702827I-680J-680D01*
G01X1701873Y127193D01*
G02X1700513I-680J680D01*
G01X1700511Y127195D01*
G02Y128555I680J680D01*
G01X1701556Y129600D01*
G03Y130778I-589J589D01*
G01X1701224Y131110D01*
G03X1700604Y131367I-620J-620D01*
G01X1693869D01*
G02X1692353Y131995I0J2144D01*
G02X1691786Y133364I1369J1369D01*
G01Y134332D01*
G02X1692385Y135778I2045J0D01*
G01X1692806Y136199D01*
G03Y137188I-495J494D01*
G01X1692562Y137432D01*
G03X1691444I-559J-560D01*
G01X1691244Y137232D01*
G02X1690522I-361J360D01*
G01X1690162Y137592D01*
G03X1688513Y138275I-1649J-1649D01*
G01X1676372D01*
G01X1723314Y120601D02*
X1723681D01*
G02X1724256Y119215I1J-812D01*
G02X1723858Y119050I-398J398D01*
G01X1719150D01*
G02X1718211Y119439I0J1328D01*
G01X1714712Y122938D01*
G03X1714041Y123216I-671J-671D01*
G01X1706100D01*
G02X1705236Y124080I0J864D01*
G03X1704372Y124944I-864J0D01*
G01X1704175D01*
G03X1703311Y124080I0J-864D01*
G02X1702447Y123216I-864J0D01*
G01X1702250D01*
G02X1701386Y124080I0J864D01*
G03X1700522Y124944I-864J0D01*
G01X1700325D01*
G03X1699461Y124080I0J-864D01*
G02X1698597Y123216I-864J0D01*
G01X1698091D01*
G02X1697577Y123429I0J727D01*
G01X1697058Y123948D01*
X1697061Y123947D01*
X1697064Y123954D01*
X1695597Y125421D01*
G02Y126781I680J680D01*
G01X1696528Y127712D01*
G03Y129072I-680J680D01*
G01X1696526Y129074D01*
G03X1695166I-680J-680D01*
G01X1694235Y128143D01*
G02X1692875I-680J680D01*
G01X1688947Y132071D01*
G02Y133431I680J680D01*
G01X1689474Y133958D01*
G03Y135318I-680J680D01*
G01X1689472Y135320D01*
G03X1688112I-680J-680D01*
G01X1687585Y134793D01*
G02X1686225I-680J680D01*
G01X1685517Y135501D01*
G03X1683749Y136233I-1768J-1768D01*
G01X1682141D01*
G01D02*
X1680286D01*
G03X1679422Y135369I0J-864D01*
G01Y135363D01*
G02X1679250Y134848I-857J0D01*
G02X1678564Y134505I-686J515D01*
G01X1678361D01*
G02X1677497Y135369I0J864D01*
G03X1676633Y136233I-864J0D01*
G01X1674636D01*
G03X1673068Y134665I0J-1568D01*
G01Y131230D01*
G02X1671142I-963J0D01*
G01Y133622D01*
G03X1669216I-963J0D01*
G01Y130634D01*
G02X1668220Y129638I-996J0D01*
G01X1664701D01*
G03X1664135Y129072I0J-566D01*
G01Y128089D01*
G01X1705138Y114470D02*
X1692692D01*
G02X1691302Y115046I0J1966D01*
G01X1688104Y118244D01*
G02X1687979Y118546I302J302D01*
G01Y120422D01*
G03X1686053I-963J0D01*
G01Y118066D01*
G03X1686461Y117081I1393J0D01*
G01X1688124Y115418D01*
G02X1686751Y114045I-687J-686D01*
G01X1685091Y115705D01*
G02X1684127Y118033I2328J2328D01*
G01Y122523D01*
G03X1683210Y124737I-3131J0D01*
G03X1682701Y124948I-509J-509D01*
G01X1679352D01*
G02X1679250Y124952I0J1297D01*
G02X1677606Y125710I206J2609D01*
G01X1677604Y125712D01*
G03X1675236Y126693I-2368J-2368D01*
G01X1673385D01*
G03X1672540Y126343I0J-1195D01*
G03X1672349Y125663I1117J-681D01*
G01Y125662D01*
G02X1671931Y124687I-1425J34D01*
G02X1670550I-690J691D01*
G03X1669157Y125264I-1393J-1393D01*
G01X1661770D01*
G03X1660985Y124939I0J-1110D01*
G01X1720164Y104850D02*
X1719210D01*
G03X1718785Y104425I0J-425D01*
G01Y103896D01*
G03X1719367Y103314I582J0D01*
G01X1720695D01*
G03X1721476Y103538I-1J1475D01*
G03X1721738Y104171I-633J633D01*
G01Y105719D01*
G03X1721541Y106195I-673J0D01*
G03X1720925Y106450I-616J-616D01*
G01X1716791D01*
G02X1715951Y106798I0J1188D01*
G01X1709192Y113557D01*
G03X1706986Y114471I-2206J-2205D01*
G01X1705139D01*
X1705138Y114470D01*
G01X1717014Y142650D02*
G03X1716663Y143496I-1197J-1D01*
G01X1710613Y149548D01*
G02Y150908I680J680D01*
G01X1711843Y152138D01*
G03Y153498I-680J680D01*
G01X1711841Y153500D01*
G03X1710481I-680J-680D01*
G01X1709251Y152270D01*
G02X1707891I-680J680D01*
G01X1707889Y152272D01*
G02Y153632I680J680D01*
G01X1709119Y154862D01*
G03Y156222I-680J680D01*
G01X1709117Y156224D01*
G03X1707757I-680J-680D01*
G01X1706527Y154994D01*
G02X1705167I-680J680D01*
G01X1704167Y155994D01*
G03X1701446Y157121I-2721J-2721D01*
G01X1699466D01*
G02X1698449Y157495I0J1568D01*
G02X1698019Y158425I791J930D01*
G01Y159668D01*
G03X1696094I-962J0D01*
G01Y158467D01*
G02X1694168I-963J0D01*
G01Y159470D01*
G03X1692243I-962J0D01*
G01Y158707D01*
G02X1691814Y158278I-429J0D01*
G01X1688002D01*
G02X1687347Y158933I0J655D01*
G01Y159503D01*
G03X1685422I-962J0D01*
G01Y158833D01*
G02X1684589Y158000I-833J0D01*
G01X1683805D01*
G03X1682857Y157607I0J-1340D01*
G01X1681092Y155842D01*
G02X1679250Y154772I-2938J2937D01*
G02X1678155Y154625I-1095J4007D01*
G01X1673132D01*
G01X1654686Y153288D02*
Y154252D01*
G02X1655244Y154810I558J0D01*
G01X1660131D01*
G02X1660614Y154610I0J-683D01*
G02X1660921Y153869I-741J-741D01*
G01Y153187D01*
G03X1662370Y151738I1449J0D01*
G01X1664179D01*
G03X1665386Y152238I0J1707D01*
G01X1665629Y152481D01*
G02X1668070Y153492I2441J-2441D01*
G01X1669128D01*
G03X1670639Y154118I0J2137D01*
G01X1670642Y154121D01*
G02X1671859Y154625I1217J-1217D01*
G01X1673132D01*
G01X1657836Y140688D02*
Y141759D01*
G02X1658277Y142200I441J0D01*
G01X1665602D01*
G03X1666452Y143050I0J850D01*
G01Y144070D01*
G02X1667982Y145600I1530J0D01*
G01X1675160D01*
G02Y143674I0J-963D01*
G01X1669027D01*
G03Y141749I0J-962D01*
G01X1676378D01*
G03X1678803Y142754I0J3429D01*
G01X1678805Y142756D01*
G02X1679250Y143153I3700J-3699D01*
G01X1679271Y143174D01*
G02X1680369Y143629I1098J-1098D01*
G01X1683895D01*
G02X1685164Y142360I0J-1269D01*
G01Y141163D01*
G03X1687089I962J0D01*
G01Y143326D01*
G02X1688126Y144363I1037J0D01*
G01X1692944D01*
G01X1723314Y133200D02*
X1722142Y134373D01*
G03X1720989Y134850I-1153J-1155D01*
G01X1716356D01*
G03X1715557Y134676I-1J-1919D01*
G01X1713211D01*
G02X1707726Y136948I0J7757D01*
G01X1700988Y143686D01*
G03X1699354Y144363I-1634J-1633D01*
G01X1692944D01*
G01X1672222Y98726D02*
X1668694D01*
X1665800Y101620D01*
X1663423D01*
X1659658Y105385D01*
X1656859D01*
X1655269Y106975D01*
X1653752D01*
X1651536Y109191D01*
G01X1656000Y101000D02*
X1655500D01*
X1654800Y100300D01*
G01X1660400Y98500D02*
Y99979D01*
X1659379Y101000D01*
X1656000D01*
G01X1657835Y118640D02*
Y118238D01*
X1654875Y115278D01*
G01X1897000Y209200D02*
X1896068Y210132D01*
X1892732D01*
X1891200Y208600D01*
X1879899D01*
X1878912Y209587D01*
X1876335D01*
X1872640Y205892D01*
X1864007D01*
X1861687Y208212D01*
X1855288D01*
X1852962Y210538D01*
X1846134D01*
X1834672Y222000D01*
X1713882D01*
X1706667Y214785D01*
X1705163D01*
X1705162Y214786D01*
X1691362D01*
X1680148Y226000D01*
X1665500D01*
G01X1713137Y213138D02*
X1710999Y211000D01*
X1687500D01*
X1685038Y213462D01*
X1672173D01*
X1668910Y210199D01*
X1668827D01*
X1668636Y210008D01*
X1663720D01*
X1661553Y212175D01*
Y212233D01*
X1661513Y212273D01*
Y214801D01*
X1661494Y214820D01*
Y215876D01*
X1660131Y217239D01*
X1654015D01*
G01X1653849Y175788D02*
Y174125D01*
X1653496Y173772D01*
Y167799D01*
G01X1660679Y179278D02*
Y175778D01*
G01Y179278D02*
Y181779D01*
X1660800Y181900D01*
G01X1842000Y187250D02*
Y188750D01*
X1841280Y189470D01*
X1720330D01*
X1719690Y188830D01*
X1718310D01*
X1717330Y189810D01*
Y189818D01*
X1717116Y190032D01*
Y197679D01*
X1714120Y200675D01*
X1712811D01*
X1708922Y204564D01*
G01X1845000Y187250D02*
Y199499D01*
X1828212Y216287D01*
X1719297D01*
X1711610Y208600D01*
X1701500D01*
G01X1719080Y232852D02*
Y228611D01*
X1719132Y228559D01*
X1706283Y215710D01*
X1705547D01*
X1705546Y215711D01*
X1691746D01*
X1678944Y228513D01*
X1674500D01*
G01X1651536Y156435D02*
X1653126Y158025D01*
Y162574D01*
X1653173Y162621D01*
Y163361D01*
X1654059Y164247D01*
X1654799D01*
X1655373Y164821D01*
Y165600D01*
X1655374Y165601D01*
Y167435D01*
X1656700Y168761D01*
Y171014D01*
G01X1656599Y192608D02*
Y189608D01*
G01X1708600Y182800D02*
X1709900Y184100D01*
Y187300D01*
G01X1656200Y199700D02*
X1656577D01*
X1657577Y198700D01*
X1658868D01*
X1659367Y198201D01*
X1668216D01*
X1668708Y197709D01*
X1669474D01*
X1669475Y197710D01*
X1669885D01*
X1673595Y194000D01*
X1683433D01*
X1686183Y191250D01*
G01X1677558Y189941D02*
X1677417Y189800D01*
X1676400D01*
X1669416Y196784D01*
X1668324D01*
X1667832Y197276D01*
X1658983D01*
X1658559Y197700D01*
X1654266D01*
X1653099Y196533D01*
Y192608D01*
G01X1683484Y190908D02*
X1678525D01*
X1677558Y189941D01*
G01X1891880Y204370D02*
X1891120Y205130D01*
X1881680D01*
X1877613Y201063D01*
X1867187D01*
X1866322Y200198D01*
X1860754D01*
X1859189Y201763D01*
X1857717D01*
X1849877Y209603D01*
X1845353D01*
X1835493Y219463D01*
X1715495D01*
X1709532Y213500D01*
X1691320D01*
X1688484Y216336D01*
X1669579D01*
X1667356Y214113D01*
Y213096D01*
G01X1700836Y161268D02*
Y161178D01*
X1702692Y159322D01*
G03X1704263Y158671I1571J1570D01*
G03X1704719Y158650I455J4915D01*
G01X1706296D01*
G01X1703610Y161214D02*
X1703930Y160894D01*
X1709317D01*
G02X1710620Y160354I0J-1842D01*
G01X1716202Y154772D01*
X1716228D01*
G01X1726464Y145800D02*
G03X1724475Y149025I-7797J-2583D01*
G01X1717117Y156383D01*
G02X1716049Y158962I2580J2579D01*
G01Y160346D01*
G03X1715802Y160942I-842J0D01*
G01X1714050Y162694D01*
G03X1713748Y162819I-302J-302D01*
G01X1706113D01*
G02X1705067Y163865I0J1046D01*
G01Y167572D01*
G03X1703142I-963J0D01*
G01Y164774D01*
G02X1701217I-962J0D01*
G01Y167424D01*
G03X1699292I-962J0D01*
G01Y163707D01*
G02X1698255Y162670I-1037J0D01*
G01X1693699D01*
G02X1693235Y162862I0J656D01*
G03X1692945Y162922I-291J-676D01*
G01X1691596D01*
G01X1681632Y233665D02*
Y233234D01*
X1681800Y233066D01*
Y227289D01*
X1692453Y216636D01*
X1705900D01*
X1716083Y226819D01*
Y236830D01*
X1719053Y239800D01*
X1794227D01*
X1795358Y238669D01*
G01X1684300Y233579D02*
Y226204D01*
X1692904Y217600D01*
X1705500D01*
X1715043Y227143D01*
Y237205D01*
X1718638Y240800D01*
X1798820D01*
X1800700Y238920D01*
X1800728D01*
G01X1680520Y445012D02*
Y440034D01*
X1673640Y433154D01*
Y316524D01*
X1672737Y315621D01*
Y289521D01*
X1671625Y288409D01*
Y283257D01*
X1666609Y278241D01*
Y260970D01*
X1666968Y260611D01*
G01X1661186Y245352D02*
X1659038Y247500D01*
X1656500D01*
G01X1727896Y246175D02*
X1725194Y243473D01*
X1714805D01*
X1712941Y245337D01*
Y248576D01*
X1708561Y252956D01*
X1692469D01*
X1690565Y251052D01*
G01X1689019Y253510D02*
X1686113Y250604D01*
G01X1720651Y246141D02*
X1718942Y244432D01*
X1715155D01*
X1713866Y245721D01*
Y249091D01*
X1708986Y253971D01*
X1689480D01*
X1689019Y253510D01*
G01X1678303Y442765D02*
Y439833D01*
X1672215Y433745D01*
Y317115D01*
X1671312Y316212D01*
Y290112D01*
X1670200Y289000D01*
Y283848D01*
X1665000Y278648D01*
Y254000D01*
G01D02*
Y248678D01*
X1664324Y248002D01*
G01X1668648Y265000D02*
Y278264D01*
X1673050Y282666D01*
Y287818D01*
X1674162Y288930D01*
Y315030D01*
X1675065Y315933D01*
Y432563D01*
X1682817Y440315D01*
Y450182D01*
X1681215Y451784D01*
Y451786D01*
G01X1667667Y257920D02*
X1667800Y258053D01*
Y258357D01*
X1669300Y259857D01*
Y261901D01*
X1668648Y262553D01*
Y265000D01*
G01X1666345Y241987D02*
X1668223D01*
X1669348Y240862D01*
G01X1655821Y236554D02*
X1658946D01*
X1660206Y235294D01*
X1671216D01*
X1674354Y238432D01*
Y246789D01*
X1676219Y248654D01*
Y264807D01*
X1673014Y268012D01*
Y276381D01*
X1673813Y277180D01*
Y277231D01*
X1677300Y280718D01*
Y283000D01*
X1678393Y284093D01*
X1679100D01*
G01Y278924D02*
X1674664Y274488D01*
Y268696D01*
X1678198Y265162D01*
Y263901D01*
X1678199Y263900D01*
Y263218D01*
X1678198Y263217D01*
Y248299D01*
X1676104Y246205D01*
Y236782D01*
X1671222Y231900D01*
X1666500D01*
G01X1664762Y438035D02*
X1662799Y436072D01*
Y409176D01*
X1665222Y406753D01*
Y382208D01*
X1662358Y379344D01*
Y375839D01*
X1663291Y374906D01*
Y341021D01*
X1661872Y339602D01*
Y338515D01*
G01D02*
Y335799D01*
X1663963Y333708D01*
Y318681D01*
X1658207Y312925D01*
Y309911D01*
X1659407Y308711D01*
X1661248D01*
G01X1654937Y338572D02*
X1659666Y343301D01*
Y371021D01*
X1658231Y372456D01*
Y392283D01*
X1662697Y396749D01*
Y405706D01*
X1660274Y408129D01*
Y445469D01*
X1672000Y457195D01*
Y458700D01*
X1677729Y464429D01*
Y472933D01*
X1678001Y473205D01*
G01X1679100Y302100D02*
X1677437Y303763D01*
Y313537D01*
X1678891Y314991D01*
Y431755D01*
X1683182Y436046D01*
X1706018D01*
X1713449Y443477D01*
Y445623D01*
X1714169Y446343D01*
Y452993D01*
X1718436Y457260D01*
X1726186D01*
X1729625Y453821D01*
Y449991D01*
X1736154Y443462D01*
X1839862D01*
X1845875Y449475D01*
X1849084D01*
X1851599Y451990D01*
Y456199D01*
X1850412Y457386D01*
Y470701D01*
X1859711Y480000D01*
X1863000D01*
G01X1859600Y476200D02*
X1857220D01*
X1851337Y470317D01*
Y457770D01*
X1852524Y456583D01*
Y451606D01*
X1849468Y448550D01*
X1846259D01*
X1840246Y442537D01*
X1735770D01*
X1728699Y449608D01*
Y451142D01*
X1728700Y451143D01*
Y453437D01*
X1725802Y456335D01*
X1718820D01*
X1715094Y452609D01*
Y445959D01*
X1714374Y445239D01*
Y443093D01*
X1706402Y435121D01*
X1683566D01*
X1679916Y431471D01*
Y314117D01*
X1678490Y312691D01*
Y305310D01*
X1679100Y304700D01*
G01X1664453Y308557D02*
X1665388Y309492D01*
Y341500D01*
X1664716Y342172D01*
Y360024D01*
X1666621Y361929D01*
Y396942D01*
X1666647Y396968D01*
Y407639D01*
X1664803Y409483D01*
Y434008D01*
X1669076Y438281D01*
G01X1651500Y291650D02*
X1652050D01*
X1652700Y292300D01*
Y297143D01*
X1653584Y298027D01*
X1655526D01*
G01X1662526Y300586D02*
X1661248Y301864D01*
Y305211D01*
G01X1659500Y317250D02*
Y316000D01*
X1658250Y314750D01*
X1654750D01*
G01X1662300Y327300D02*
Y332400D01*
X1661600Y333100D01*
G01X1659500Y317250D02*
X1660750D01*
X1662300Y318800D01*
Y327300D01*
G01X1684435Y456832D02*
X1684481D01*
X1685222Y456091D01*
Y439395D01*
X1677415Y431588D01*
Y314958D01*
X1676512Y314055D01*
Y302088D01*
X1679100Y299500D01*
G01Y297000D02*
X1675587Y300513D01*
Y314439D01*
X1676490Y315342D01*
Y431972D01*
X1684297Y439779D01*
Y453964D01*
X1681336Y456925D01*
Y457690D01*
G01X1671050Y483600D02*
X1672713Y481937D01*
Y479936D01*
X1654673Y461896D01*
Y403861D01*
X1651163Y400351D01*
Y384645D01*
G01X1668735Y344282D02*
Y357772D01*
X1669690Y358727D01*
Y417110D01*
X1668100Y418700D01*
G01X1654809Y401645D02*
X1655598Y402434D01*
Y461512D01*
X1673736Y479650D01*
X1725684D01*
X1732536Y472798D01*
Y451007D01*
X1737305Y446238D01*
X1765410D01*
X1765411Y446237D01*
X1766789D01*
X1766790Y446238D01*
X1803310D01*
X1803311Y446237D01*
X1804689D01*
X1804690Y446238D01*
X1838400D01*
X1844462Y452300D01*
X1848016D01*
X1848848Y453132D01*
Y455057D01*
X1847037Y456868D01*
Y481796D01*
X1844349Y484484D01*
Y489500D01*
X1844512Y489663D01*
Y489680D01*
X1846000Y491168D01*
Y496000D01*
G01X1681154Y449286D02*
X1680520Y448652D01*
Y445012D01*
G01X1669816Y448953D02*
X1667863Y447000D01*
X1665900D01*
G01X1681336Y457690D02*
Y458206D01*
X1682551Y459421D01*
X1684435D01*
G01X1665047Y467257D02*
Y468377D01*
X1668427Y471757D01*
X1672774D01*
X1673954Y472937D01*
Y475049D01*
X1676719Y477814D01*
X1723438D01*
X1730550Y470702D01*
Y450393D01*
X1736543Y444400D01*
X1839201D01*
X1845201Y450400D01*
X1848699D01*
X1850674Y452375D01*
Y455815D01*
X1849487Y457002D01*
Y475977D01*
X1851150Y477640D01*
G01X1705683Y584727D02*
Y589300D01*
G01D02*
Y589317D01*
X1700267D01*
X1696500Y585550D01*
Y578850D01*
X1691047Y573397D01*
Y570630D01*
G01X1694000Y565118D02*
Y566946D01*
X1697700Y570646D01*
Y581130D01*
X1701960Y585390D01*
G01D02*
X1703490Y583860D01*
Y581257D01*
X1704020Y580727D01*
X1705683D01*
G01X1694000Y580079D02*
Y588854D01*
X1700646Y595500D01*
X1703500D01*
G01Y604500D02*
X1693694D01*
X1691047Y607147D01*
Y615512D01*
G01X1703500Y600000D02*
X1697236D01*
X1696685Y600551D01*
X1691047D01*
G01X1759093Y9310D02*
X1764863Y3540D01*
Y-18550D01*
X1767320Y-21007D01*
X1774853D01*
X1779504Y-16356D01*
Y-15000D01*
G01X1769504D02*
X1774372Y-10132D01*
Y-1040D01*
X1772700Y632D01*
Y7100D01*
X1769730Y10070D01*
G01X1773100Y15200D02*
X1771100D01*
X1769730Y13830D01*
Y10070D01*
G01X1728460Y71300D02*
X1731600D01*
X1732070Y70830D01*
X1749430D01*
X1752210Y73610D01*
Y75110D01*
X1753040Y75940D01*
X1756750D01*
G01X1767250Y94500D02*
X1761880D01*
X1760461Y93081D01*
G01X1770250Y89500D02*
X1767250D01*
G01D02*
X1764199D01*
X1762373Y87674D01*
X1760379D01*
G01X1741044Y65498D02*
X1734957D01*
X1734089Y64630D01*
Y63639D01*
G01X1726750Y62680D02*
X1733130D01*
X1734089Y63639D01*
G01X1766333Y59116D02*
X1769949Y55500D01*
X1779258D01*
X1786765Y47993D01*
X1787969D01*
G01X1759525Y56400D02*
Y58225D01*
X1762100Y60800D01*
X1767250D01*
X1770550Y57500D01*
X1780929D01*
X1783468Y60039D01*
Y63968D01*
X1784341Y64841D01*
G01X1742594Y47106D02*
X1743600Y46100D01*
Y43900D01*
G01X1750400Y47400D02*
X1747300D01*
X1745900Y48800D01*
X1741700D01*
X1737600Y44700D01*
X1736600D01*
G01D02*
X1733500D01*
X1732500Y45700D01*
Y48800D01*
X1731420Y49880D01*
X1726750D01*
G01Y52440D02*
X1720500D01*
G01X1726750D02*
X1731060D01*
X1733050Y50450D01*
X1735050D01*
X1735850Y49650D01*
G01X1726750Y57560D02*
X1732060D01*
X1732650Y58150D01*
G01X1726750Y60120D02*
X1732120D01*
X1732650Y60650D01*
G01X1735150Y78450D02*
Y88035D01*
X1733965Y89220D01*
X1731280D01*
G01X1731960Y83830D02*
Y81920D01*
X1729540Y79500D01*
X1723500D01*
G01X1731280Y89220D02*
X1730855D01*
X1730430Y88795D01*
Y86470D01*
X1731960Y84940D01*
Y83830D01*
G01X1742150Y87950D02*
X1739700D01*
X1739100Y87350D01*
Y74213D01*
X1740783Y72530D01*
X1748717D01*
X1750500Y74313D01*
Y77150D01*
X1751578Y78228D01*
X1758726D01*
X1761558Y81060D01*
X1763250D01*
G01X1769250Y81070D02*
X1767587D01*
X1767577Y81060D01*
X1763250D01*
G01X1769250Y81070D02*
X1773450D01*
X1776380Y84000D01*
X1778000D01*
G01X1745650Y87950D02*
Y85950D01*
X1743650Y83950D01*
Y82200D01*
G01X1745650Y87950D02*
Y91850D01*
G01X1764900Y91800D02*
X1773200D01*
X1773750Y91250D01*
Y89500D01*
G01X1790100Y154000D02*
X1796600D01*
X1800476Y150124D01*
X1807007D01*
X1808979Y148152D01*
Y146184D01*
X1806421Y143626D01*
Y140721D01*
X1803363Y137663D01*
Y132737D01*
X1805787Y130313D01*
X1808260D01*
X1809322Y129251D01*
Y125522D01*
X1809831Y125013D01*
Y123331D01*
X1803863Y117363D01*
X1802006D01*
X1792635Y107992D01*
Y102896D01*
X1794078Y101453D01*
Y78746D01*
X1788137Y72805D01*
Y68139D01*
X1786652Y66654D01*
X1783590D01*
X1781768Y64832D01*
Y61804D01*
X1780514Y60550D01*
X1774159D01*
X1772314Y62395D01*
X1768628D01*
G01X1719750Y88000D02*
X1721101D01*
X1722201Y89100D01*
X1723681D01*
G01X1727860Y93920D02*
X1726421D01*
X1723681Y91180D01*
Y89100D01*
G01X1727860Y93920D02*
X1729570D01*
X1731350Y92140D01*
G01X1756961Y93081D02*
Y90985D01*
X1757772Y90174D01*
G01X1757395Y84794D02*
X1756879Y85310D01*
Y87674D01*
G01X1753370Y88520D02*
X1754216Y87674D01*
X1756879D01*
G01X1770250Y94500D02*
X1767250D01*
G01X1759158Y145798D02*
Y150866D01*
G03X1757389I-885J0D01*
G01Y149950D01*
X1756189Y148750D01*
X1751889D01*
X1750989Y147850D01*
Y143450D01*
X1748589Y141050D01*
X1747300D01*
G01X1764172Y145798D02*
X1759158D01*
G01X1747300Y141050D02*
X1737464D01*
X1735914Y139500D01*
G01X1723189Y165719D02*
X1724781D01*
X1725489Y165011D01*
Y158590D01*
X1724349Y157450D01*
X1722839D01*
X1722539Y157150D01*
Y155900D01*
X1726089Y152350D01*
X1728389D01*
X1729189Y151550D01*
Y150153D01*
G01D02*
Y144750D01*
X1726689Y142250D01*
X1723714D01*
X1723314Y142650D01*
G01X1764220Y136750D02*
X1759158D01*
G01X1735989Y133250D02*
X1734689D01*
X1734389Y133550D01*
Y135950D01*
X1734789Y136350D01*
X1736789D01*
X1738689Y134450D01*
X1740089D01*
X1740889Y135250D01*
Y136850D01*
X1741189Y137150D01*
X1742289D01*
X1742689Y136750D01*
Y135450D01*
G03X1744689I1000J0D01*
G01Y136550D01*
X1745089Y136950D01*
X1749089D01*
X1750253Y135786D01*
G01D02*
X1751489Y134550D01*
X1758489D01*
X1759158Y135219D01*
Y136750D01*
G01X1728789Y136250D02*
X1730100Y137561D01*
Y141072D01*
X1734078Y145050D01*
Y156050D01*
X1735678Y157650D01*
X1737749D01*
X1738989Y158890D01*
Y165164D01*
X1738434Y165719D01*
X1736689D01*
G01X1735989Y149050D02*
X1735663Y149376D01*
Y155050D01*
G02X1737589I963J0D01*
G01Y150450D01*
G03X1739514I962J0D01*
G01Y156490D01*
X1740674Y157650D01*
X1741419D01*
G01X1726539Y139450D02*
X1727350Y140261D01*
X1727700D01*
X1732589Y145150D01*
Y154350D01*
X1731989Y154950D01*
X1730449D01*
X1729689Y155710D01*
Y156450D01*
X1730539Y157300D01*
X1732551D01*
X1734389Y159138D01*
Y165211D01*
X1733881Y165719D01*
X1732189D01*
G01X1745689D02*
X1747120D01*
X1747989Y164850D01*
Y158250D01*
X1747389Y157650D01*
X1745589D01*
X1743989Y156050D01*
X1741489D01*
X1740889Y155450D01*
Y151176D01*
G01D02*
Y148350D01*
X1740389Y147850D01*
X1738389D01*
X1737489Y146950D01*
X1736189D01*
X1735689Y146450D01*
Y145650D01*
X1736989Y144350D01*
Y143450D01*
X1736289Y142750D01*
X1734989D01*
G01X1720164Y139500D02*
X1721739Y141075D01*
Y143288D01*
X1722651Y144200D01*
X1727139D01*
X1728189Y145250D01*
Y147950D01*
X1720889Y155250D01*
Y164962D01*
X1720132Y165719D01*
X1718689D01*
G01X1750189D02*
X1752070D01*
X1752789Y165000D01*
Y159550D01*
X1749089Y155850D01*
X1747654D01*
G01D02*
X1746089D01*
X1744689Y154450D01*
X1742989D01*
X1742589Y154050D01*
Y148250D01*
X1743789Y147050D01*
Y144850D01*
X1743189Y144250D01*
X1740664D01*
X1739064Y142650D01*
G01X1720164Y145800D02*
G03X1720915Y147613I-1814J1813D01*
G01Y148650D01*
G03X1719900Y151100I-3466J0D01*
G01X1716228Y154772D01*
G01X1727689Y165719D02*
X1729280D01*
X1729889Y165110D01*
Y159038D01*
X1727189Y156338D01*
Y154450D01*
X1727689Y153950D01*
X1729289D01*
X1730689Y152550D01*
Y144750D01*
X1726989Y141050D01*
X1724864D01*
X1723314Y139500D01*
G01X1759158Y127750D02*
Y126081D01*
X1761189Y124050D01*
Y122550D01*
X1760439Y121800D01*
X1757639D01*
X1755389Y119550D01*
X1752589D01*
X1751189Y120950D01*
Y123542D01*
G01X1764220Y127750D02*
X1759158D01*
G01X1751189Y123542D02*
Y125950D01*
X1749889Y127250D01*
X1745589D01*
X1743639Y125300D01*
X1740664D01*
X1739064Y126900D01*
G01X1759158Y132250D02*
Y130519D01*
X1758689Y130050D01*
X1750889D01*
X1750289Y130650D01*
Y133050D01*
X1749689Y133650D01*
X1748689D01*
X1748089Y133050D01*
Y129350D01*
X1747389Y128650D01*
X1744689D01*
X1744089Y129250D01*
Y132750D01*
X1743789Y133050D01*
X1740779D01*
G01X1764220Y132250D02*
X1759158D01*
G01X1740779Y133050D02*
X1738489D01*
X1737939Y132500D01*
Y131175D01*
X1739064Y130050D01*
G01X1748550Y148138D02*
Y149565D01*
X1748279Y149836D01*
Y151165D01*
G01D02*
Y152825D01*
X1747854Y153250D01*
X1746189D01*
G01X1744600Y150900D02*
Y148700D01*
X1745162Y148138D01*
X1748550D01*
G01X1759158Y141250D02*
X1756858Y138950D01*
X1740689D01*
X1739689Y137950D01*
X1732889D01*
X1729489Y134550D01*
X1727245D01*
X1727088Y134707D01*
X1724821D01*
X1723314Y133200D01*
G01X1764220Y141250D02*
X1759158D01*
G01X1764900Y97000D02*
X1773000D01*
X1773750Y96250D01*
Y94500D01*
G01X1713137Y213138D02*
X1717212Y217213D01*
X1829507D01*
X1842620Y204100D01*
X1850885D01*
X1859985Y195000D01*
X1874900D01*
X1877530Y197630D01*
X1885200D01*
X1885580Y197250D01*
X1893120D01*
X1895070Y199200D01*
X1901130D01*
X1904030Y196300D01*
X1909350D01*
G01X1721850Y198700D02*
Y197050D01*
X1725250Y193650D01*
Y191500D01*
G01X1721000Y193706D02*
X1723206Y191500D01*
X1725250D01*
G01X1719000Y190500D02*
Y191706D01*
X1721000Y193706D01*
G01X1723189Y169675D02*
Y165719D01*
G01X1736689Y169675D02*
Y165719D01*
G01X1741189D02*
X1742770D01*
X1743489Y165000D01*
Y158650D01*
X1742489Y157650D01*
X1741419D01*
G01X1741189Y169675D02*
Y165719D01*
G01X1732189Y169675D02*
Y165719D01*
G01X1745689Y169675D02*
Y165719D01*
G01X1718689Y169675D02*
Y165719D01*
G01X1750189Y169675D02*
Y165719D01*
G01X1727689Y169675D02*
Y165719D01*
G01X1795377Y126231D02*
Y127377D01*
X1797136Y129136D01*
Y133576D01*
X1796482Y134230D01*
X1789604D01*
X1784912Y138922D01*
Y158000D01*
X1787500Y160588D01*
Y164500D01*
X1786000Y166000D01*
X1784500D01*
X1783500Y167000D01*
Y170729D01*
X1785330Y172559D01*
Y181096D01*
X1783926Y182500D01*
X1715500D01*
X1713000Y185000D01*
G01X1718820Y249032D02*
Y259361D01*
X1721834Y262375D01*
X1800025D01*
X1806032Y256368D01*
G01X1715078Y250231D02*
Y259537D01*
X1720766Y265225D01*
X1800382D01*
X1810991Y254616D01*
X1820341D01*
G01X1755900Y243400D02*
X1753304D01*
X1746900Y249804D01*
G01X1755900Y246400D02*
X1752800D01*
X1751900Y247300D01*
Y249700D01*
G01X1742420Y228410D02*
X1738460D01*
X1738430Y228440D01*
G01X1742420Y228410D02*
Y234659D01*
X1742398Y234681D01*
G01X1718587Y444550D02*
X1717571Y443534D01*
Y440224D01*
X1721493Y436302D01*
X1844402D01*
X1853200Y445100D01*
X1855000D01*
G01X1718900Y448000D02*
Y444863D01*
X1718587Y444550D01*
G01X1721990Y444521D02*
Y441531D01*
X1725794Y437727D01*
X1843811D01*
X1852609Y446525D01*
X1853297D01*
X1856422Y449650D01*
Y456400D01*
G01X1724590Y444521D02*
X1727999Y441112D01*
X1844065D01*
X1848511Y445558D01*
G01X1718230Y452955D02*
Y450447D01*
X1716730Y448947D01*
Y445243D01*
X1716037Y444550D01*
G01D02*
Y439742D01*
X1720902Y434877D01*
X1845877D01*
X1852500Y441500D01*
X1855000D01*
G01X1768200Y505700D02*
X1766600D01*
X1765500Y506800D01*
X1759900D01*
G01X1768200Y505700D02*
X1769755D01*
X1776695Y512640D01*
G01X1715489Y493890D02*
X1728399Y506800D01*
X1752900D01*
G01X1750800Y516100D02*
X1752900Y514000D01*
Y511918D01*
G01X1762715Y521085D02*
X1765000Y518800D01*
Y517000D01*
G01X1759900Y511918D02*
X1761918D01*
X1762700Y512700D01*
Y515700D01*
X1764000Y517000D01*
X1765000D01*
G01X1771502Y501944D02*
X1773900Y504342D01*
Y507300D01*
X1778200Y511600D01*
X1779300D01*
G01X1773300Y567650D02*
X1768979D01*
X1767529Y566200D01*
G01X1773300Y571695D02*
X1771530Y569925D01*
X1766225D01*
X1765250Y570900D01*
X1764300D01*
G01X1752480Y569942D02*
X1751242D01*
X1749800Y568500D01*
X1744400D01*
X1743200Y567300D01*
G01X1738088Y551000D02*
X1751500D01*
X1752500Y550000D01*
X1759559D01*
X1761500Y551941D01*
Y555000D01*
X1760354Y556146D01*
Y557738D01*
G01X1743100Y561700D02*
X1741500Y563300D01*
Y565092D01*
X1740437Y566155D01*
Y567163D01*
X1740037Y567563D01*
Y575512D01*
X1741025Y576500D01*
X1746000D01*
X1747700Y574800D01*
X1756584D01*
X1758386Y572998D01*
Y569942D01*
G01X1728537Y589342D02*
X1727937D01*
X1725095Y586500D01*
X1724299D01*
X1723186Y585387D01*
Y583342D01*
X1725694Y580834D01*
Y575914D01*
G01X1733368Y579868D02*
Y580518D01*
X1733950Y581100D01*
Y582504D01*
G01X1733368Y579868D02*
X1735928D01*
X1737760Y581700D01*
X1738500D01*
G01X1733369Y575914D02*
X1738114D01*
X1739069Y576869D01*
Y581131D01*
X1738500Y581700D01*
G01X1772550Y588100D02*
Y585000D01*
G01X1775900Y588400D02*
X1772850D01*
X1772550Y588100D01*
G01X1776200Y578650D02*
X1772750D01*
X1772500Y578900D01*
G01X1757792Y581471D02*
Y582603D01*
X1759067Y583878D01*
Y586743D01*
G01X1783200Y597400D02*
X1781200D01*
X1777400Y593600D01*
X1767500D01*
X1765016Y591116D01*
Y588550D01*
X1763209Y586743D01*
X1759067D01*
G01X1776400Y583900D02*
Y583500D01*
X1774800Y581900D01*
X1772500D01*
G01X1750792Y578912D02*
X1748561D01*
X1747900Y578251D01*
X1746292D01*
G01X1750792Y578912D02*
X1754735D01*
X1754897Y578750D01*
G01X1754448Y557738D02*
Y553948D01*
X1754000Y553500D01*
G01X1730950Y582500D02*
Y580136D01*
X1730774Y579960D01*
G01X1730814Y575914D02*
Y579920D01*
X1730774Y579960D01*
G01X1725694Y571814D02*
X1728254Y569254D01*
Y565314D01*
G01X1726850Y559000D02*
X1723000D01*
G01X1726850D02*
Y561350D01*
X1728254Y562754D01*
Y565314D01*
G01X1743000Y570000D02*
X1749000D01*
X1751500Y572500D01*
X1753500D01*
X1754448Y571552D01*
Y569942D01*
G01X1767500Y559800D02*
X1766309D01*
X1765300Y560809D01*
X1762519D01*
G01X1765300Y574700D02*
X1764900Y574300D01*
X1761300D01*
X1760354Y573354D01*
Y569942D01*
G01X1743500Y564500D02*
X1745793Y566793D01*
X1750315D01*
G01X1758386Y557738D02*
Y555614D01*
X1759500Y554500D01*
G01X1752480Y557738D02*
Y555482D01*
X1752133Y555135D01*
Y552272D01*
X1752905Y551500D01*
X1757944D01*
X1759500Y553056D01*
Y554500D01*
G01X1743500Y564500D02*
X1742624Y565376D01*
Y565524D01*
X1741537Y566611D01*
Y567763D01*
X1741137Y568163D01*
Y571911D01*
X1741925Y572699D01*
X1744801D01*
X1746500Y571000D01*
X1748500D01*
X1751000Y573500D01*
X1754000D01*
X1754085Y573415D01*
X1755084D01*
X1756417Y572082D01*
Y569942D01*
G01X1741200Y559200D02*
X1740009D01*
X1738697Y557888D01*
G01X1756417Y557738D02*
Y554583D01*
X1756500Y554500D01*
G01X1738600Y565100D02*
Y563300D01*
X1741200Y560700D01*
Y559200D01*
G01X1725694Y565314D02*
Y568814D01*
G01X1757319Y606953D02*
Y610581D01*
X1754300Y613600D01*
G01X1757057Y598292D02*
X1754108D01*
X1753625Y598775D01*
Y603064D01*
X1757319Y606758D01*
Y606953D01*
G01X1757057Y598292D02*
Y596700D01*
X1756508Y596151D01*
Y593743D01*
G01X1721808Y601455D02*
X1719813Y603450D01*
X1716950D01*
G01X1725133Y614896D02*
X1727035Y616798D01*
X1737498D01*
X1739400Y618700D01*
X1742000D01*
G01X1740270Y594419D02*
X1739176D01*
X1738116Y593359D01*
X1736097D01*
G01D02*
Y591315D01*
X1734124Y589342D01*
X1728537D01*
G01X1721808Y597955D02*
X1719363Y600400D01*
X1716438D01*
G01X1718037Y594684D02*
X1716817D01*
X1715900Y595601D01*
Y599862D01*
X1716438Y600400D01*
G01X1772500Y591100D02*
X1777551D01*
X1778675Y592224D01*
G01X1766400Y596000D02*
Y599400D01*
G01X1770600Y600800D02*
X1771650Y599750D01*
X1774900D01*
G01X1770600Y600800D02*
X1769900Y601500D01*
Y604900D01*
X1767100Y607700D01*
X1762700D01*
X1757900Y612500D01*
Y614500D01*
X1756241Y616159D01*
X1754300D01*
G01X1748100Y607000D02*
Y614000D01*
X1750259Y616159D01*
X1754300D01*
G01X1742000Y616141D02*
X1744891D01*
X1750250Y621500D01*
X1757940D01*
X1760722Y618718D01*
X1761300D01*
G01D02*
X1764912D01*
G01X1728341Y614851D02*
X1729610Y613582D01*
X1735000D01*
G01X1739179Y592070D02*
X1740370D01*
X1742000Y593700D01*
X1744700D01*
G01X1782900Y9500D02*
Y7600D01*
X1789504Y996D01*
Y-5000D01*
G01X1780915Y15168D02*
Y11650D01*
X1782900Y9665D01*
Y9500D01*
G01X1822400Y28200D02*
Y33300D01*
X1822923Y33823D01*
X1827103D01*
X1828070Y34790D01*
X1835128D01*
X1837268Y32650D01*
X1862590D01*
X1864706Y34766D01*
G01X1797000Y16600D02*
Y7200D01*
X1801200Y3000D01*
X1807100D01*
X1814301Y-4201D01*
Y-7300D01*
X1816505Y-9504D01*
X1824858D01*
X1828874Y-13520D01*
G01X1825870Y21587D02*
X1825700Y21757D01*
Y26250D01*
G01X1822400Y24700D02*
X1820700D01*
X1819837Y23837D01*
Y21700D01*
G01X1777685Y12830D02*
Y16285D01*
X1779568Y18168D01*
X1780915D01*
G01X1777685Y12830D02*
Y7615D01*
X1785408Y-108D01*
Y-8608D01*
X1786832Y-10032D01*
X1814536D01*
X1819504Y-15000D01*
G01X1807127Y26918D02*
X1808909Y28700D01*
X1810700D01*
X1811500Y27900D01*
Y19219D01*
X1813894Y16825D01*
X1818325D01*
X1820575Y14575D01*
Y8425D01*
X1822613Y6387D01*
X1834387D01*
X1834900Y6900D01*
X1844400D01*
X1845300Y7800D01*
X1847142D01*
X1852492Y13150D01*
X1858780D01*
X1861947Y16317D01*
X1874648D01*
X1876792Y18461D01*
G01X1876881Y22181D02*
X1878455Y20607D01*
Y17772D01*
X1877361Y16678D01*
X1876368D01*
X1874982Y15292D01*
X1862472D01*
X1859210Y12030D01*
X1853023D01*
X1847818Y6825D01*
X1845700D01*
X1844850Y5975D01*
X1835324D01*
X1834711Y5362D01*
X1822138D01*
X1819600Y7900D01*
Y14100D01*
X1817900Y15800D01*
X1813469D01*
X1810000Y19269D01*
Y25507D01*
X1809822Y25685D01*
Y26585D01*
G01X1787969Y47993D02*
X1789327D01*
X1806510Y30810D01*
X1810223D01*
X1812410Y28623D01*
Y28299D01*
X1812425Y28284D01*
Y19660D01*
X1813661Y18424D01*
X1814993D01*
X1814994Y18425D01*
X1818741D01*
X1822700Y14466D01*
Y13200D01*
X1822600Y13100D01*
Y12400D01*
X1822700D01*
X1827700Y7400D01*
X1834000D01*
X1834600Y8000D01*
X1838700D01*
X1840400Y9700D01*
G01X1842000Y17250D02*
X1843019D01*
X1843663Y16606D01*
Y12476D01*
X1843274Y12087D01*
X1840187D01*
X1839500Y11400D01*
X1836800D01*
X1833700Y8300D01*
X1828013D01*
X1823525Y12788D01*
Y14808D01*
X1819083Y19250D01*
X1814550D01*
X1813250Y20550D01*
Y28626D01*
X1813235Y28641D01*
Y28965D01*
X1810500Y31700D01*
X1807149D01*
X1801488Y37361D01*
Y46072D01*
X1797840Y49720D01*
G01X1835600Y13000D02*
Y13730D01*
X1836850Y14980D01*
X1838000D01*
X1838750Y15730D01*
Y17500D01*
G01X1832250D02*
Y14150D01*
X1832842Y13558D01*
Y13500D01*
G01X1832250Y17500D02*
X1835250D01*
G01X1774600Y8800D02*
Y13000D01*
X1775000Y13400D01*
Y19100D01*
X1777600Y21700D01*
X1778700D01*
G01X1774600Y8800D02*
Y7184D01*
X1783627Y-1843D01*
Y-9123D01*
X1789504Y-15000D01*
G01X1793720Y7387D02*
X1799504Y1603D01*
Y-5000D01*
G01X1799438Y44328D02*
X1797771D01*
X1785012Y57087D01*
Y62012D01*
X1786341Y63341D01*
G01X1828340Y149960D02*
X1827780Y149400D01*
X1824959D01*
X1821059Y145500D01*
X1810700D01*
X1809159Y143959D01*
Y140997D01*
X1805306Y137144D01*
Y133894D01*
X1807187Y132013D01*
X1808965D01*
X1811022Y129956D01*
Y126227D01*
X1811531Y125718D01*
Y122626D01*
X1804568Y115663D01*
X1802711D01*
X1794396Y107348D01*
Y103540D01*
X1795778Y102158D01*
Y78041D01*
X1789837Y72100D01*
Y67434D01*
X1786341Y63938D01*
Y63341D01*
G01X1788216Y59197D02*
X1789650Y60631D01*
Y64629D01*
X1791687Y66666D01*
Y71332D01*
X1797628Y77273D01*
Y80464D01*
X1798454Y81290D01*
Y82256D01*
G01X1866606Y109967D02*
X1866395D01*
X1859428Y103000D01*
X1845293D01*
X1842522Y105771D01*
X1824481D01*
X1823170Y104460D01*
Y93309D01*
X1825000Y91479D01*
Y86400D01*
X1827100Y84300D01*
Y81600D01*
G01X1798454Y82256D02*
X1800821Y84623D01*
X1801314D01*
G01X1866376Y67105D02*
X1855893D01*
X1850384Y72614D01*
Y76339D01*
X1846423Y80300D01*
X1832500D01*
X1829000Y83800D01*
Y89400D01*
X1824500Y93900D01*
Y103130D01*
X1824990Y103620D01*
G01X1816418Y127976D02*
X1812600Y124158D01*
Y122386D01*
X1805600Y115386D01*
Y113200D01*
X1804456Y112056D01*
X1803070D01*
X1797787Y106773D01*
Y88223D01*
X1796703Y87139D01*
Y77657D01*
X1790762Y71716D01*
Y67050D01*
X1788178Y64466D01*
Y61927D01*
X1786432Y60181D01*
Y58392D01*
X1794724Y50100D01*
X1797460D01*
X1797840Y49720D01*
G01X1781750Y75500D02*
X1785650D01*
X1786700Y76550D01*
Y77950D01*
G01X1781750Y75500D02*
Y71726D01*
X1779903Y69879D01*
G01X1775711Y70650D02*
X1777434D01*
X1778205Y69879D01*
X1779903D01*
G01X1798377Y126231D02*
X1800268D01*
X1802605Y123894D01*
Y121887D01*
X1801543Y120825D01*
X1800032D01*
X1785250Y106043D01*
Y87283D01*
X1781967Y84000D01*
X1778000D01*
G01X1829580Y38620D02*
X1829500D01*
Y38700D01*
X1831430D01*
X1831559Y38571D01*
X1837694D01*
X1837728Y38537D01*
X1839272D01*
X1839415Y38680D01*
X1840340D01*
X1841040Y37980D01*
X1843236D01*
G01X1826414Y35486D02*
X1827457D01*
X1827686Y35715D01*
X1831653D01*
X1833358Y37420D01*
X1838875D01*
X1839300Y36995D01*
Y34240D01*
X1839880Y33660D01*
X1842916D01*
X1847236Y37980D01*
G01X1785903Y69879D02*
Y72976D01*
X1792378Y79451D01*
Y100492D01*
X1789646Y103224D01*
Y107854D01*
X1800855Y119063D01*
X1802186D01*
X1804305Y121182D01*
Y124599D01*
X1801663Y127241D01*
Y136958D01*
X1801662Y136959D01*
Y138367D01*
X1801663Y138368D01*
Y138553D01*
X1804721Y141611D01*
Y144956D01*
X1807166Y147401D01*
G01X1777628Y62395D02*
X1777623Y62400D01*
X1775250D01*
X1774400Y63250D01*
Y64850D01*
X1775711Y66161D01*
Y67650D01*
G01X1777628Y62395D02*
Y64728D01*
X1778300Y65400D01*
X1779900D01*
X1784379Y69879D01*
X1785903D01*
G01X1782949Y155900D02*
Y161449D01*
X1784023Y162523D01*
G01X1782949Y155900D02*
Y154538D01*
X1783987Y153500D01*
Y138538D01*
X1784000Y138525D01*
Y133900D01*
X1788000Y129900D01*
Y129000D01*
G01X1828340Y149960D02*
X1824735Y153565D01*
X1803335D01*
X1799426Y157474D01*
X1793900D01*
X1792674Y158700D01*
X1788678D01*
X1785837Y155859D01*
Y149640D01*
X1792877Y142600D01*
Y138481D01*
G01X1811400Y140600D02*
Y137600D01*
G01X1815883Y133277D02*
X1812923D01*
X1811400Y134800D01*
Y137600D01*
G01X1856163Y150948D02*
X1842618D01*
X1839720Y148050D01*
X1834627D01*
X1832177Y150500D01*
G01X1828960Y153010D02*
X1829667D01*
X1832177Y150500D01*
G01X1798377Y122731D02*
X1800752D01*
X1800792Y122691D01*
G01X1792127Y125981D02*
Y127727D01*
X1792908Y128508D01*
Y130964D01*
X1793425Y131481D01*
X1795436D01*
G01X1792127Y122981D02*
Y125981D01*
G01X1795377Y122731D02*
X1793819D01*
X1793569Y122981D01*
X1792127D01*
G01D02*
Y118227D01*
X1792000Y118100D01*
G01X1788627Y122981D02*
Y121442D01*
X1787373Y120188D01*
G01D02*
Y115127D01*
X1788000Y114500D01*
G01X1798377Y126231D02*
X1795377D01*
G01X1817767Y101100D02*
Y105033D01*
X1815273Y107527D01*
X1803297D01*
X1802300Y106530D01*
Y104500D01*
G01X1800420Y148240D02*
X1797620D01*
G01X1787000Y175500D02*
Y173625D01*
X1787425Y173200D01*
X1788350D01*
X1789300Y172250D01*
Y171000D01*
G01X1816125Y169492D02*
X1817715Y171082D01*
Y172398D01*
G01X1789300Y167500D02*
X1788800Y168000D01*
X1785500D01*
G01X1806032Y256368D02*
X1809004Y253396D01*
X1818227D01*
X1819325Y252298D01*
X1822198D01*
X1824838Y254938D01*
X1834337D01*
X1836837Y252438D01*
Y249515D01*
X1839534Y246818D01*
Y245040D01*
X1840149Y244425D01*
G01X1854374Y248790D02*
X1853264Y249900D01*
X1840844D01*
X1832956Y257788D01*
X1823513D01*
X1820341Y254616D01*
G01X1847000Y228000D02*
X1844375D01*
X1842300Y230075D01*
X1836525D01*
X1826200Y240400D01*
X1822300D01*
X1821100Y239200D01*
G01D02*
Y237629D01*
X1822877Y235852D01*
G01X1826085Y236034D02*
X1827649D01*
X1829971Y233712D01*
G01D02*
X1834683Y229000D01*
X1841831D01*
X1845831Y225000D01*
X1847000D01*
G01X1834500Y250000D02*
X1834300Y250200D01*
X1831100D01*
X1828900Y252400D01*
X1824900D01*
X1824300Y251800D01*
G01X1847000Y246000D02*
X1845863D01*
X1845337Y245474D01*
Y243718D01*
X1844381Y242762D01*
X1839047D01*
X1837863Y243946D01*
Y245413D01*
X1836713Y246563D01*
X1835246D01*
X1834500Y247309D01*
Y250000D01*
G01X1826287D02*
X1828187Y248100D01*
X1832400D01*
X1835900Y244600D01*
G01X1821600Y227200D02*
X1823000Y225800D01*
X1836000D01*
X1845300Y216500D01*
X1847000D01*
G01X1826662Y232191D02*
Y228000D01*
G01X1847000Y222000D02*
X1844100D01*
X1842200Y223900D01*
Y224800D01*
X1839800Y227200D01*
X1827462D01*
X1826662Y228000D01*
G01X1810350Y525650D02*
X1812021Y527321D01*
Y529899D01*
G01X1807100Y503600D02*
X1808575D01*
X1809000Y504025D01*
Y506175D01*
X1809700Y506875D01*
G01X1815359Y510600D02*
Y509360D01*
X1813936Y507937D01*
X1811776D01*
X1810813Y508900D01*
X1809100D01*
X1807100Y506900D01*
Y503600D01*
G01X1820400Y501100D02*
X1819100D01*
X1817918Y502282D01*
Y503600D01*
G01X1821441Y528960D02*
X1822400Y528001D01*
Y526201D01*
X1821052Y524853D01*
Y523001D01*
G01X1810052Y529899D02*
Y528053D01*
X1806076Y524077D01*
Y523525D01*
G01D02*
X1806600Y523001D01*
X1809052D01*
G01X1801982Y510600D02*
Y512537D01*
X1798883Y515636D01*
G01X1810200Y513300D02*
X1808100D01*
X1807100Y512300D01*
Y510600D01*
G01X1812800D02*
X1807100D01*
G01X1804500Y526200D02*
X1806100D01*
X1808083Y528183D01*
Y529899D01*
G01X1838280Y513800D02*
Y509780D01*
X1836400Y507900D01*
X1828300D01*
X1827600Y507200D01*
X1825000D01*
G01X1808134Y495734D02*
X1810525Y498125D01*
Y505348D01*
X1811689Y506512D01*
X1816662D01*
X1817350Y507200D01*
X1825000D01*
G01X1803900Y491500D02*
X1808134Y495734D01*
G01X1796153Y514200D02*
Y511947D01*
X1801982Y506118D01*
Y503600D01*
G01X1828200Y519000D02*
X1828100Y519100D01*
X1824500D01*
X1822900Y517500D01*
X1817950D01*
G01D02*
X1814300D01*
X1812900Y518900D01*
X1798501D01*
X1794200Y514599D01*
Y512000D01*
X1792400Y510200D01*
X1790400D01*
X1789300Y509100D01*
Y506600D01*
G01X1783300Y519100D02*
X1779300D01*
G01X1786000Y522600D02*
X1783300Y519900D01*
Y519100D01*
G01X1779300Y511600D02*
Y515600D01*
G01D02*
X1781300Y513600D01*
X1784182D01*
G01X1803950Y538954D02*
X1797554D01*
X1796100Y537500D01*
Y528500D01*
X1797800Y526800D01*
X1801251D01*
X1803752Y529301D01*
G01D02*
X1804350Y529899D01*
X1806115D01*
G01X1810052Y542103D02*
Y545103D01*
G01X1816584Y530542D02*
X1816154Y530972D01*
Y532970D01*
G01X1816584Y530542D02*
X1816874Y530252D01*
X1820149D01*
X1821441Y528960D01*
G01X1809600Y582800D02*
X1807521Y584879D01*
Y587899D01*
G01X1819552Y581301D02*
Y584053D01*
X1821895Y586396D01*
Y588200D01*
G01X1811100Y586800D02*
X1811600Y586300D01*
Y582742D01*
X1814894Y579448D01*
X1818766D01*
X1819552Y580234D01*
Y581301D01*
G01X1829300Y572900D02*
X1829000D01*
X1828601Y572501D01*
X1825552D01*
G01D02*
X1822052D01*
G01X1815400Y560541D02*
X1818641D01*
X1819100Y561000D01*
Y563800D01*
X1817300Y565600D01*
X1815400D01*
X1813994Y567006D01*
Y572864D01*
X1810104Y576754D01*
X1794846D01*
X1793100Y578500D01*
G01X1789700Y574700D02*
Y577800D01*
G01D02*
X1792400D01*
X1793100Y578500D01*
G01X1840690Y557190D02*
X1835390D01*
X1834700Y556500D01*
G01X1816280Y550400D02*
Y547712D01*
X1814652Y546084D01*
Y544301D01*
X1813989Y543638D01*
Y542103D01*
G01X1808083D02*
Y545486D01*
X1816097Y553500D01*
X1816280D01*
G01X1837534Y579322D02*
X1837213Y579001D01*
X1833052D01*
G01X1792805Y574675D02*
X1792826Y574654D01*
Y574126D01*
X1789188Y570488D01*
Y568724D01*
G01X1812021Y542103D02*
Y544570D01*
X1812952Y545501D01*
G01X1814138Y548444D02*
X1812952Y547258D01*
Y545501D01*
G01X1809290Y549668D02*
X1809700Y550078D01*
Y552600D01*
X1808300Y554000D01*
X1795200D01*
X1794000Y552800D01*
G01X1809290Y549668D02*
X1806115Y546493D01*
Y542103D01*
G01X1832500Y539500D02*
X1832000D01*
X1831700Y539200D01*
X1830700D01*
X1830088Y538588D01*
X1827965D01*
X1825552Y541001D01*
G01X1818509Y527893D02*
X1816521D01*
X1814515Y529899D01*
X1813989D01*
G01X1829000Y536315D02*
X1827785D01*
X1826599Y537501D01*
X1825552D01*
G01X1788300Y585100D02*
X1789700Y583700D01*
Y580900D01*
G01D02*
X1793451D01*
X1802615Y590064D01*
X1804450D01*
G01X1792170Y583900D02*
X1792000D01*
X1786450Y589450D01*
Y590040D01*
G01X1818500Y576000D02*
X1816300D01*
X1816100Y576200D01*
G01X1808400Y557982D02*
X1811282D01*
X1812554Y559254D01*
Y572126D01*
X1809550Y575130D01*
X1802845D01*
X1800683Y572968D01*
G01X1808400Y557982D02*
X1803518D01*
X1802400Y559100D01*
G01X1800683Y572968D02*
X1798400Y570685D01*
Y562600D01*
G01X1809309Y555713D02*
X1801787D01*
X1798400Y559100D01*
G01X1839126Y583354D02*
X1834694D01*
X1833841Y582501D01*
X1833052D01*
G01X1826600Y549500D02*
X1830000D01*
X1831500Y548000D01*
G01X1831600Y529000D02*
X1828600D01*
G01Y532500D02*
X1834600D01*
X1837000Y534900D01*
G01X1784650Y566000D02*
X1782000D01*
X1781000Y565000D01*
G01X1773900Y562450D02*
X1778450D01*
X1781000Y565000D01*
G01X1779500Y579500D02*
X1778650Y578650D01*
X1776200D01*
G01X1782300Y555900D02*
X1781900Y555500D01*
X1774000D01*
G01X1776800Y567650D02*
X1780150D01*
X1780500Y568000D01*
G01X1783400Y570900D02*
X1780500Y568000D01*
G01Y570718D02*
Y574750D01*
X1779950Y575300D01*
G01X1776800Y571695D02*
Y573600D01*
X1778500Y575300D01*
X1779950D01*
G01X1776400Y583900D02*
X1778000D01*
X1779400Y582500D01*
G01X1800378Y593527D02*
Y593475D01*
X1801821Y592032D01*
X1804450D01*
G01Y597938D02*
Y600351D01*
X1805252Y601153D01*
Y602852D01*
X1805500Y603100D01*
G01D02*
X1803000Y605600D01*
Y608075D01*
X1803425Y608500D01*
X1813700D01*
X1814483Y607717D01*
Y603683D01*
X1813505Y602705D01*
Y600103D01*
G01X1816654Y594001D02*
X1819245D01*
X1819443Y593803D01*
X1819654D01*
G01X1782700Y608400D02*
Y610900D01*
G01X1800352Y596101D02*
X1802452Y594001D01*
X1804450D01*
G01X1821895Y588200D02*
Y588755D01*
X1820586Y590064D01*
X1816654D01*
G01X1822273Y595046D02*
X1821349Y595970D01*
X1816654D01*
G01X1791349Y589122D02*
X1795000Y592773D01*
Y595001D01*
X1797800Y597801D01*
X1801351D01*
X1803182Y595970D01*
X1804450D01*
G01X1816654Y592032D02*
X1826503D01*
X1827211Y592740D01*
Y597431D01*
G01X1791323Y594030D02*
X1790167Y595186D01*
Y600866D01*
X1800801Y611500D01*
X1817193D01*
X1827211Y601482D01*
Y597431D01*
G01X1786450Y590040D02*
X1788088Y591678D01*
X1791581D01*
X1793115Y593212D01*
Y594590D01*
X1791600Y596105D01*
Y600283D01*
X1801242Y609925D01*
X1815876D01*
X1819250Y606551D01*
Y600534D01*
X1816654Y597938D01*
G01X1785700Y608400D02*
Y610702D01*
X1787004Y612006D01*
X1788290D01*
G01X1782700Y604900D02*
X1785700D01*
G01D02*
Y602300D01*
X1787500Y600500D01*
G01X1781800Y588500D02*
X1779000D01*
G01D02*
X1778900Y588400D01*
X1775900D01*
G01X1784200Y593924D02*
Y596400D01*
X1783200Y597400D01*
G01X1781600Y592600D02*
X1781300D01*
X1780924Y592224D01*
X1778675D01*
G01X1886465Y-15068D02*
Y-11802D01*
X1895945Y-2322D01*
G01X1889575Y-18562D02*
X1889569Y-18568D01*
X1886465D01*
G01X1889575Y-18562D02*
X1895213D01*
X1897472Y-20821D01*
X1901755D01*
X1903160Y-19416D01*
G01X1848322Y12723D02*
Y12322D01*
X1846500Y10500D01*
G01X1876792Y18461D02*
X1876273Y18980D01*
X1873336D01*
G01X1876881Y22181D02*
X1876582Y22480D01*
X1873336D01*
G01X1844835Y20168D02*
X1843836D01*
X1842000Y18332D01*
Y17250D01*
G01Y13750D02*
X1839440D01*
X1838850Y13160D01*
G01X1835600Y13000D02*
X1838690D01*
X1838850Y13160D01*
G01X1864706Y34766D02*
X1867619Y37679D01*
Y39779D01*
G01X1871460Y73390D02*
X1866670D01*
X1866039Y74021D01*
Y75138D01*
G01Y78537D02*
Y75138D01*
G01X1891494Y70584D02*
X1894885Y67193D01*
X1898161D01*
G01X1895945Y45630D02*
X1892600Y48975D01*
Y66350D01*
X1891494Y67456D01*
Y70584D01*
G01X1895000Y61600D02*
Y59245D01*
X1900945Y53300D01*
Y49626D01*
G01X1904666Y67073D02*
Y65365D01*
X1902701Y63400D01*
X1896800D01*
X1895000Y61600D01*
G01X1873956Y60299D02*
Y55350D01*
G01X1860786Y41200D02*
Y42494D01*
X1856350Y46930D01*
X1844610D01*
X1843236Y45556D01*
Y44980D01*
G01X1858198Y41108D02*
Y42247D01*
X1855465Y44980D01*
X1847236D01*
G01X1838500Y40400D02*
X1839580Y41480D01*
X1843236D01*
G01X1847236D02*
X1847880D01*
X1852390Y36970D01*
X1854109D01*
X1856333Y34746D01*
Y34518D01*
G01X1871988Y47250D02*
X1870450D01*
X1866100Y51600D01*
G01X1878997Y37546D02*
X1877454D01*
X1875912Y39088D01*
X1871812D01*
G01X1878800Y40200D02*
X1882700Y44100D01*
Y61700D01*
X1875839Y68561D01*
X1867832D01*
X1866376Y67105D01*
G01X1851341Y106358D02*
X1857358D01*
X1860100Y109100D01*
Y111500D01*
G01X1861015Y130815D02*
X1860100Y129900D01*
Y111500D01*
G01X1881165Y105561D02*
Y105587D01*
X1881290Y105712D01*
Y109080D01*
G01X1863500Y151000D02*
Y147999D01*
X1861932Y146431D01*
G01D02*
X1859663Y148700D01*
Y150948D01*
G01X1895060Y136099D02*
X1895372D01*
X1897500Y133971D01*
Y131500D01*
G01X1836100Y179700D02*
X1837275D01*
X1839000Y181425D01*
Y183750D01*
G01X1840900Y179700D02*
X1842000Y180800D01*
Y183750D01*
G01X1845700Y179700D02*
X1845000Y180400D01*
Y183750D01*
G01X1896710Y194380D02*
Y194140D01*
X1898250Y192600D01*
Y191000D01*
G01X1854477Y212365D02*
X1857205Y209637D01*
X1862963D01*
X1863700Y208900D01*
X1866263D01*
X1867000Y209637D01*
X1870363D01*
X1872100Y207900D01*
G01X1844110Y206600D02*
X1850401D01*
X1856901Y200100D01*
X1858500D01*
G01X1868000Y199100D02*
X1865098D01*
X1864464Y198466D01*
G01X1836932Y170486D02*
X1839623D01*
X1840783Y169326D01*
G01X1841900Y174200D02*
X1846340D01*
X1849013Y176873D01*
Y196587D01*
X1847000Y198600D01*
G01X1884400Y224100D02*
X1882625Y225875D01*
Y228125D01*
X1884800Y230300D01*
X1888376D01*
X1889463Y231387D01*
G01X1885719Y232386D02*
X1886480Y233147D01*
X1893031D01*
X1893222Y233338D01*
X1899810D01*
X1900235Y232913D01*
Y231622D01*
G01X1885719Y232386D02*
X1881800Y228467D01*
Y224200D01*
X1881900Y224100D01*
G01X1885000Y227500D02*
X1885887Y228387D01*
X1889463D01*
G01X1894968Y220827D02*
Y222080D01*
X1893927Y223121D01*
X1890795D01*
X1889913Y222239D01*
Y220437D01*
G01X1892963Y228387D02*
Y231387D01*
G01X1896735Y231622D02*
X1893198D01*
X1892963Y231387D01*
G01X1897527Y220827D02*
Y223023D01*
X1896735Y223815D01*
Y225622D01*
G01Y228622D02*
Y225622D01*
G01Y231622D02*
Y228622D01*
G01X1891950Y225100D02*
Y226250D01*
X1892963Y227263D01*
Y228387D01*
G01X1847000Y234000D02*
X1845600D01*
X1843500Y231900D01*
X1840052D01*
X1836348Y235604D01*
X1835936D01*
G01X1847000Y231000D02*
X1838600D01*
X1836900Y232700D01*
G01X1847000Y240000D02*
X1845564D01*
X1844800Y240764D01*
X1841764D01*
X1840300Y239300D01*
G01X1847000Y237000D02*
X1845600D01*
X1843600Y239000D01*
G01X1835900Y244600D02*
X1838663Y241837D01*
X1845837D01*
X1847000Y243000D01*
G01X1878500Y454750D02*
Y450600D01*
X1878100Y450200D01*
G01X1856422Y456400D02*
Y456426D01*
X1856000Y456848D01*
Y460000D01*
G01X1848511Y445558D02*
X1853949Y450996D01*
Y457174D01*
X1853000Y458123D01*
Y460000D01*
G01X1858633Y452803D02*
Y454767D01*
X1861312Y457446D01*
G01X1866050Y451100D02*
X1865100Y452050D01*
Y453523D01*
X1864700Y453923D01*
Y476300D01*
X1866173Y477773D01*
X1875351D01*
X1876374Y476750D01*
X1878526D01*
X1880776Y479000D01*
X1899500D01*
X1903324Y482824D01*
X1908424D01*
X1909080Y483480D01*
X1914799D01*
X1916790Y481489D01*
Y473260D01*
X1919360Y470690D01*
X1932580D01*
X1934530Y472640D01*
X1937640D01*
X1939280Y471000D01*
X1943500D01*
G01X1877407Y479046D02*
X1865845D01*
X1863800Y477001D01*
Y456400D01*
X1861174Y453774D01*
Y451897D01*
X1861902Y451169D01*
Y448086D01*
X1858916Y445100D01*
X1858500D01*
G01X1860500Y469800D02*
Y468600D01*
X1859200Y467300D01*
Y464800D01*
X1857900Y463500D01*
X1856000D01*
G01X1853000D02*
Y468906D01*
X1855206Y471112D01*
G01X1867500Y447900D02*
X1861100Y441500D01*
X1858500D01*
G01X1868015Y452987D02*
X1866900Y454102D01*
Y458400D01*
G01X1883016Y473995D02*
X1881703D01*
X1881158Y473450D01*
X1875650D01*
X1874785Y472585D01*
Y463285D01*
X1874750Y463250D01*
G01X1866900Y458400D02*
Y460800D01*
X1869350Y463250D01*
X1874750D01*
G01X1853900Y516600D02*
X1859360D01*
X1859530Y516430D01*
G01X1847000Y516600D02*
X1842600D01*
X1842400Y516800D01*
G01X1943100Y488420D02*
X1942740Y488780D01*
X1937180D01*
X1934770Y491190D01*
X1915623D01*
X1908082Y483649D01*
X1902349D01*
X1899726Y481026D01*
X1875100D01*
X1874074Y480000D01*
X1865800D01*
X1863800Y482000D01*
X1855510D01*
X1851150Y477640D01*
G01X1868167Y467855D02*
X1867500Y468522D01*
Y472200D01*
G01X1900890Y477200D02*
X1880992D01*
X1878992Y475200D01*
X1875908D01*
X1875408Y475700D01*
X1867500D01*
G01X1884100Y493000D02*
X1888600Y488500D01*
X1895000D01*
X1897900Y485600D01*
X1907491D01*
X1911100Y489209D01*
Y503050D01*
X1912800Y504750D01*
G01X1857450Y473654D02*
X1859046D01*
X1860500Y472200D01*
Y469800D01*
G01X1948880Y519250D02*
Y509880D01*
X1945480Y506480D01*
Y502810D01*
X1944150Y501480D01*
X1941310D01*
X1939010Y499180D01*
Y494450D01*
X1936680Y492120D01*
X1915320D01*
X1907800Y484600D01*
X1901999D01*
X1899999Y482600D01*
X1879574D01*
X1878825Y481851D01*
X1874758D01*
X1873732Y480825D01*
X1866142D01*
X1864142Y482825D01*
X1850175D01*
X1847000Y486000D01*
Y487500D01*
G01X1858050Y505510D02*
Y504550D01*
X1856350Y502850D01*
Y502750D01*
X1856190Y502590D01*
Y498881D01*
X1857908Y497163D01*
X1873298D01*
X1875973Y499838D01*
G01X1858090Y508600D02*
Y506390D01*
X1858050Y506350D01*
Y505510D01*
G01X1865799Y504018D02*
X1864062D01*
X1862547Y505533D01*
Y511117D01*
X1865755Y514325D01*
X1867014D01*
X1869914Y517225D01*
G01X1866688Y517128D02*
X1867757Y518197D01*
Y519254D01*
X1863995Y523016D01*
Y525936D01*
X1861327Y528604D01*
X1857575D01*
X1856166Y530013D01*
Y530769D01*
X1856167Y530770D01*
Y532417D01*
X1856193Y532443D01*
Y533821D01*
X1855219Y534795D01*
X1855182D01*
X1855130Y534847D01*
X1845354D01*
X1845341Y534860D01*
G01X1866688Y517128D02*
X1867069Y516747D01*
Y516145D01*
X1866174Y515250D01*
X1865371D01*
X1861622Y511501D01*
Y505149D01*
X1863955Y502816D01*
Y502030D01*
X1865031Y500954D01*
X1865847D01*
G01X1874410Y509560D02*
X1878390D01*
X1880700Y507250D01*
X1891900D01*
X1893400Y508750D01*
Y512650D01*
X1889365Y516685D01*
Y527335D01*
X1891810Y529780D01*
X1904104D01*
X1908469Y525415D01*
G01X1847000Y525600D02*
X1845768D01*
X1844474Y524306D01*
X1841204D01*
X1836924Y528586D01*
X1836909D01*
G01X1847000Y525600D02*
X1853900D01*
G01X1852500Y530700D02*
Y529400D01*
X1853900Y528000D01*
Y525600D01*
G01X1869290Y509560D02*
Y504327D01*
X1869299Y504318D01*
Y504018D01*
G01X1878272Y519465D02*
Y516793D01*
X1876594Y515115D01*
X1871045D01*
X1869290Y513360D01*
Y509560D01*
G01X1871850D02*
Y503457D01*
X1869347Y500954D01*
G01X1881293Y519486D02*
Y516993D01*
X1880242Y515942D01*
G01X1871850Y509560D02*
Y513579D01*
X1872360Y514089D01*
X1878389D01*
X1880242Y515942D01*
G01X1839200Y589619D02*
X1840016Y588803D01*
X1847069D01*
X1851250Y584622D01*
G01X1864804Y555268D02*
X1859900D01*
X1859003Y554371D01*
X1856419D01*
X1856391Y554343D01*
X1856143D01*
X1854508Y552708D01*
G01X1851250Y568874D02*
X1838843D01*
G01X1864804Y545028D02*
X1859028D01*
X1858528Y544528D01*
G01X1864804Y547588D02*
X1859628D01*
X1857108Y550108D01*
G01Y552708D02*
X1858771Y551045D01*
X1860455D01*
X1861352Y550148D01*
X1864804D01*
G01X1887004D02*
X1890452D01*
X1891300Y549300D01*
Y547667D01*
X1893000Y545967D01*
Y545600D01*
X1892900Y545500D01*
Y543500D01*
X1893000Y543400D01*
Y543200D01*
X1897900Y538300D01*
X1897933D01*
X1897958Y538275D01*
X1931541D01*
X1931566Y538300D01*
X1931600D01*
X1936400Y543100D01*
Y544300D01*
X1937200Y545100D01*
G01X1937300Y541600D02*
X1933100Y537400D01*
X1897600D01*
X1892100Y542900D01*
Y543100D01*
X1892000Y543200D01*
Y545700D01*
X1890400Y547300D01*
Y547400D01*
X1890212Y547588D01*
X1887004D01*
G01X1939700Y540900D02*
X1935300Y536500D01*
X1897300D01*
X1891200Y542600D01*
Y542800D01*
X1891100Y542900D01*
Y544400D01*
X1890472Y545028D01*
X1887004D01*
G01Y542468D02*
X1890300D01*
Y542300D01*
X1897000Y535600D01*
X1939100D01*
X1940800Y537300D01*
G01X1887004Y560388D02*
X1889112D01*
X1894800Y554700D01*
Y548900D01*
X1896400Y547300D01*
Y544900D01*
X1899300Y542000D01*
X1901671D01*
G01X1887004Y557828D02*
X1890172D01*
X1893850Y554150D01*
Y548618D01*
X1895550Y546918D01*
Y544518D01*
X1899068Y541000D01*
X1908245D01*
X1908295Y541050D01*
G01X1915085Y540100D02*
X1898585D01*
X1894725Y543960D01*
Y544075D01*
X1894700Y544100D01*
Y544900D01*
X1894725Y544925D01*
Y546576D01*
X1892950Y548351D01*
Y552554D01*
X1890236Y555268D01*
X1887004D01*
G01Y552708D02*
X1890286D01*
X1892125Y550869D01*
Y548009D01*
X1893900Y546234D01*
Y545300D01*
X1893800Y545200D01*
Y543800D01*
X1893900Y543700D01*
Y543500D01*
X1898300Y539100D01*
X1931199D01*
X1935400Y543301D01*
Y547300D01*
X1937800Y549700D01*
G01X1885350Y578837D02*
Y581050D01*
X1882825Y583575D01*
X1874075D01*
X1871500Y581000D01*
Y579500D01*
G01D02*
X1866899D01*
X1863933Y576534D01*
X1856573D01*
G01X1896800Y551900D02*
Y553100D01*
X1901337Y557637D01*
Y558537D01*
X1903100Y560300D01*
X1905300D01*
X1906000Y561000D01*
Y564600D01*
G01X1896800Y551900D02*
Y551700D01*
X1898700Y549800D01*
X1900850D01*
X1901400Y549250D01*
X1904250D01*
G01X1899550Y582865D02*
X1897578D01*
X1897300Y582587D01*
X1893850D01*
G01X1899550Y586365D02*
X1895523D01*
G01X1857812Y557245D02*
X1860332D01*
X1860915Y557828D01*
X1864804D01*
G01X1869800Y557100D02*
X1876100Y550800D01*
Y540800D01*
X1875208Y539908D01*
X1864804D01*
G01X1847070Y537610D02*
X1848970Y539510D01*
Y542220D01*
X1849250Y542500D01*
G01X1852250D02*
X1849250D01*
G01X1855750D02*
X1855782Y542468D01*
X1864804D01*
G01X1855750Y545500D02*
Y548000D01*
G01Y545500D02*
Y542500D01*
G01X1865300Y584950D02*
X1867300D01*
X1868463Y586113D01*
Y587613D01*
X1869529Y588679D01*
X1872115D01*
G01X1882100Y586619D02*
X1881600Y586119D01*
X1879115D01*
G01Y588679D02*
X1881675D01*
X1882100Y588254D01*
Y586619D01*
G01D02*
X1882461Y586258D01*
X1892550D01*
X1897392Y591100D01*
X1899700D01*
G01X1848800Y551400D02*
X1851600D01*
G01X1871704Y572718D02*
Y569424D01*
X1869934Y567654D01*
Y565817D01*
X1869935Y565816D01*
Y563612D01*
G01X1868704Y572718D02*
Y566040D01*
X1868442Y565778D01*
G01X1864804Y552708D02*
X1859708D01*
G01X1852500Y530700D02*
Y531102D01*
X1854530Y533132D01*
G01X1872722Y535778D02*
X1872146Y535202D01*
Y533140D01*
G01D02*
Y531747D01*
X1871850Y531451D01*
Y527560D01*
G01X1872115Y588679D02*
X1875421D01*
X1875600Y588500D01*
G01X1909643Y-19572D02*
X1907368D01*
X1904564Y-16768D01*
Y-15203D01*
X1900945Y-11584D01*
Y-6318D01*
G01X1920500Y71500D02*
X1918090D01*
X1916660Y70070D01*
G01X1923379Y78770D02*
Y74125D01*
X1922954Y73700D01*
X1920999D01*
X1920500Y73201D01*
Y71500D01*
G01X1901643Y70589D02*
Y67211D01*
X1901661Y67193D01*
G01X1920300Y68300D02*
X1920107Y68107D01*
X1915183D01*
X1913942Y69348D01*
Y75982D01*
X1911471Y78453D01*
X1907956D01*
X1901643Y72140D01*
Y70589D01*
G01X1917600Y66000D02*
X1913720D01*
X1909113Y70607D01*
X1908236D01*
G01D02*
Y67143D01*
X1908166Y67073D01*
G01X1933379Y78770D02*
Y90242D01*
X1937316Y94179D01*
X1942528D01*
X1946499Y98150D01*
X1946770D01*
G01X1928379Y78770D02*
Y87258D01*
X1936725Y95604D01*
X1941084D01*
X1943660Y98180D01*
G01X1929937Y143484D02*
X1933284D01*
X1936700Y146900D01*
X1937100D01*
G01D02*
X1937900D01*
X1940900Y149900D01*
G01X1950934Y143730D02*
X1951129Y143535D01*
X1956376D01*
G01X1936187Y144013D02*
X1933690Y141516D01*
X1929937D01*
G01X1923600Y143100D02*
X1925507D01*
X1927091Y141516D01*
X1929937D01*
G01X1951700Y141000D02*
X1952267Y141567D01*
X1956376D01*
G01X1952821Y149724D02*
X1949161D01*
X1948458Y149021D01*
G01X1940700Y136300D02*
Y136289D01*
X1941289Y135700D01*
X1958643D01*
X1959619Y136676D01*
G01X1948458Y149021D02*
Y144849D01*
X1948949Y144358D01*
Y139711D01*
X1951140Y137520D01*
X1958775D01*
X1959619Y136676D01*
G01X1919484Y149500D02*
X1917100Y147116D01*
Y145600D01*
X1915700Y144200D01*
G01X1925135Y111900D02*
X1927292D01*
X1930000Y114608D01*
G01X1928379Y105370D02*
Y107266D01*
X1925135Y110510D01*
Y111900D01*
G01X1927000Y152200D02*
X1927300Y151900D01*
X1929800D01*
G01X1918379Y105370D02*
Y101421D01*
X1922210Y97590D01*
X1923639D01*
X1925189Y96040D01*
X1933914D01*
G01X1921620Y111900D02*
X1917953D01*
G01D02*
Y110548D01*
X1918379Y110122D01*
Y105370D01*
G01X1934256Y99459D02*
X1925904D01*
X1923379Y101984D01*
Y105370D01*
G01X1919702Y125920D02*
X1916700Y122918D01*
Y122700D01*
G01X1926952Y156049D02*
X1924901Y158100D01*
X1921900D01*
G01X1944609Y149184D02*
X1946300Y147493D01*
Y144300D01*
X1945484Y143484D01*
X1941937D01*
G01Y145452D02*
X1942900Y146415D01*
Y150000D01*
X1944600Y151700D01*
G01X1956321Y149724D02*
Y150821D01*
X1957800Y152300D01*
X1960400D01*
X1962800Y149900D01*
Y149300D01*
G01X1941937Y141516D02*
X1945916D01*
X1947000Y142600D01*
G01X1897500Y128000D02*
Y124457D01*
X1897507Y124450D01*
G01X1916400Y127900D02*
X1916800Y127500D01*
X1918701D01*
X1919702Y128501D01*
G01X1916400Y127900D02*
X1916700Y128200D01*
Y134200D01*
X1917532Y135032D01*
Y135085D01*
X1918200Y135753D01*
Y137600D01*
G01D02*
X1918500Y137900D01*
X1925137D01*
X1926785Y139548D01*
X1929937D01*
G01X1963119Y136676D02*
Y138834D01*
X1962354Y139599D01*
X1956376D01*
G01X1926892Y121203D02*
X1929903D01*
X1931600Y122900D01*
Y128400D01*
X1937800Y134600D01*
X1966194D01*
X1966619Y135025D01*
Y136676D01*
G01X1951481Y156109D02*
Y154175D01*
X1949389Y152083D01*
G01X1909350Y196300D02*
Y197402D01*
X1912359Y200411D01*
X1916764D01*
X1917568Y201215D01*
G01X1916700Y196700D02*
X1917024Y196376D01*
Y193600D01*
G01X1921100Y199269D02*
Y199300D01*
X1921524Y198876D01*
Y193624D01*
X1921500Y193600D01*
G01X1925400Y196300D02*
Y197999D01*
X1922167Y201232D01*
X1920132D01*
X1918239Y199339D01*
X1915889D01*
X1912850Y196300D01*
G01X1935600Y176300D02*
X1935300Y176000D01*
Y172600D01*
G01X1900500Y209200D02*
Y211000D01*
X1900086Y211414D01*
Y213827D01*
G01X1900500Y209200D02*
Y204770D01*
X1900230Y204500D01*
G01X1921900Y158100D02*
X1922650Y158850D01*
Y163100D01*
G01X1936750Y157600D02*
X1940500D01*
G01X1933900Y167600D02*
X1932400Y169100D01*
X1931347D01*
X1930300Y170147D01*
G01X1938400Y178200D02*
X1941487Y181287D01*
Y183204D01*
G01Y188854D02*
Y190204D01*
G01D02*
Y197758D01*
X1944173Y200444D01*
G01X1954070Y177088D02*
X1953454D01*
X1951318Y179224D01*
Y181882D01*
G01X1938928Y183204D02*
Y181138D01*
X1938010Y180220D01*
X1935080D01*
X1934070Y181230D01*
Y182706D01*
X1933054Y183722D01*
X1930449D01*
G01X1930341Y188701D02*
X1931981D01*
X1932000Y188720D01*
X1933670D01*
X1933689Y188701D01*
X1933999D01*
X1935210Y187490D01*
X1937420D01*
X1937680Y187750D01*
X1938468D01*
X1938928Y188210D01*
Y190204D01*
G01X1947686Y190522D02*
Y193522D01*
G01Y190522D02*
X1946531D01*
X1946023Y191030D01*
Y191988D01*
X1944611Y193400D01*
G01X1947646Y178328D02*
Y175344D01*
X1947662Y175328D01*
G01X1947646Y178328D02*
X1949620D01*
X1952908Y175040D01*
X1955081D01*
G01X1943482Y163012D02*
X1947805D01*
X1948157Y163364D01*
X1948921D01*
G01X1943482Y163012D02*
X1942894Y163600D01*
X1938400D01*
X1937800Y163000D01*
G01X1943482Y166512D02*
Y167706D01*
X1943776Y168000D01*
Y169512D01*
G01X1944550Y176450D02*
X1944206D01*
X1941788Y174032D01*
Y171825D01*
X1942307Y171306D01*
Y170537D01*
X1943332Y169512D01*
X1943776D01*
G01X1943482Y166512D02*
X1946651D01*
X1950556Y170417D01*
X1952560D01*
X1954143Y172000D01*
G01D02*
X1955400D01*
X1962551Y179151D01*
Y180204D01*
G01X1950981Y168064D02*
X1953930D01*
X1964700Y178834D01*
Y181500D01*
X1964028Y182172D01*
X1962551D01*
G01X1900235Y225622D02*
X1902981Y228368D01*
X1903032D01*
G01X1902907Y231294D02*
X1900235Y228622D01*
G01X1934800Y457700D02*
X1935850Y458750D01*
X1938600D01*
Y458767D01*
G01D02*
Y463615D01*
X1937430Y464785D01*
G01D02*
Y469860D01*
G01X1919510Y475100D02*
X1920950Y476540D01*
X1929510D01*
X1930650Y475400D01*
G01X1919510Y479200D02*
X1921220Y477490D01*
X1929740D01*
X1930650Y478400D01*
G01X1904100Y493000D02*
X1903200D01*
X1898101Y487901D01*
Y487025D01*
X1898601Y486525D01*
X1907107D01*
X1910175Y489593D01*
Y504375D01*
X1909800Y504750D01*
G01X1951800Y477900D02*
X1951600Y477700D01*
X1940100D01*
X1939000Y476600D01*
G01X1953440Y488450D02*
Y479540D01*
X1951800Y477900D01*
G01X1960700Y531600D02*
X1961500Y530800D01*
Y524256D01*
X1957300Y520056D01*
Y517600D01*
X1959100Y515800D01*
Y511500D01*
X1960919Y509681D01*
X1962541D01*
X1964270Y511410D01*
G01X1948880Y526250D02*
Y528110D01*
X1952620Y531850D01*
X1953450D01*
X1954300Y532700D01*
X1959600D01*
X1960700Y531600D01*
G01X1953998Y526250D02*
X1956185D01*
X1956606Y526671D01*
G01X1912800Y508250D02*
Y510700D01*
G01X1934150Y475400D02*
X1934950Y476200D01*
X1935691D01*
X1937916Y473975D01*
X1941484D01*
X1942284Y474775D01*
X1944225D01*
X1945000Y474000D01*
G01X1934150Y478400D02*
X1935425Y477125D01*
X1936075D01*
X1938300Y474900D01*
X1941100D01*
X1941900Y475700D01*
X1946800D01*
X1948200Y474300D01*
G01X1909800Y508250D02*
Y510700D01*
G01X1943500Y471000D02*
X1948400D01*
X1949301Y471901D01*
X1962301D01*
X1974247Y483847D01*
Y524069D01*
X1972800Y525516D01*
Y536800D01*
G01X1928620Y482710D02*
X1929860Y483950D01*
Y486480D01*
G01X1928620Y482710D02*
Y481553D01*
X1927138Y480071D01*
G01X1942722Y505100D02*
Y506350D01*
X1943941Y507569D01*
X1945023D01*
X1947400Y509946D01*
Y528457D01*
X1947856Y528913D01*
X1948111D01*
X1952198Y533000D01*
X1952900D01*
X1954100Y534200D01*
Y538649D01*
X1955501Y540050D01*
X1956650D01*
X1959100Y542500D01*
G01X1946350Y491950D02*
X1943130D01*
X1943100Y491920D01*
G01X1945281Y498100D02*
Y493019D01*
X1946350Y491950D01*
G01X1949940D02*
X1953440D01*
G01X1947840Y498100D02*
Y494050D01*
X1949940Y491950D01*
G01X1953440D02*
Y495050D01*
G01X1953998Y519250D02*
Y516702D01*
X1954800Y515900D01*
X1956300D01*
G01X1959300Y525500D02*
X1956600Y522800D01*
X1955098D01*
X1953998Y521700D01*
Y519250D01*
G01X1934720Y523900D02*
X1932540D01*
X1930402Y521762D01*
Y516640D01*
G01X1934720Y523900D02*
X1935220D01*
X1937283Y521837D01*
X1939737D01*
X1940959Y523059D01*
Y524500D01*
G01X1930402Y516640D02*
X1928262Y514500D01*
X1908300D01*
G01X1938400Y524500D02*
X1937410D01*
X1935350Y526560D01*
X1931800D01*
X1927240Y522000D01*
X1914240D01*
X1910825Y525415D01*
X1908469D01*
G01X1947500Y532600D02*
X1945682Y530782D01*
Y528782D01*
X1945200Y528300D01*
X1938901D01*
X1938400Y527799D01*
Y524500D01*
G01X1945170Y510870D02*
Y510101D01*
X1943781Y508712D01*
X1942328D01*
G01X1945170Y510870D02*
Y513830D01*
X1943518Y515482D01*
Y517500D01*
G01X1952756Y574212D02*
X1948844Y570300D01*
X1939348D01*
X1937648Y572000D01*
X1931285D01*
G01D02*
X1931250D01*
Y570350D01*
X1932200Y569400D01*
X1934400D01*
G01X1944882Y574212D02*
X1943094Y576000D01*
X1931785D01*
X1931285Y575500D01*
G01D02*
Y574125D01*
X1931710Y573700D01*
X1934200D01*
G01X1931285Y579500D02*
X1932585Y580800D01*
X1939600D01*
X1942200Y578200D01*
X1948870D01*
X1952756Y582086D01*
G01X1934200Y577700D02*
X1932470D01*
X1931285Y578885D01*
Y579500D01*
G01X1944882Y582086D02*
X1941968Y585000D01*
X1931675D01*
X1931250Y584575D01*
Y583000D01*
X1931285D01*
G01X1935400D02*
X1931285D01*
G01X1949800Y545850D02*
X1951250D01*
X1951800Y546400D01*
Y554200D01*
X1952756Y555156D01*
Y558464D01*
G01X1901671Y542000D02*
X1930300D01*
X1932600Y544300D01*
Y551800D01*
X1934600Y553800D01*
X1947100D01*
X1949800Y551100D01*
Y545850D01*
G01X1946800Y545900D02*
X1945900Y546800D01*
Y549900D01*
G01X1908295Y541050D02*
X1930649D01*
X1933600Y544001D01*
Y551601D01*
X1934699Y552700D01*
X1945600D01*
X1947600Y550700D01*
Y546700D01*
X1946800Y545900D01*
G01X1935400Y550800D02*
X1934500Y549900D01*
Y543700D01*
X1930900Y540100D01*
X1915085D01*
G01X1923500Y579500D02*
X1927785D01*
G01X1946800Y542400D02*
X1945940D01*
X1945413Y542927D01*
Y543787D01*
X1943600Y545600D01*
X1940500D01*
X1939800Y546300D01*
G01X1949800Y542350D02*
Y540400D01*
X1948100Y538700D01*
G01X1923400Y583000D02*
X1927785D01*
G01X1923600Y575500D02*
X1927785D01*
G01X1925800Y567500D02*
X1925500Y567200D01*
X1924800D01*
X1923300Y568700D01*
X1923000D01*
G01X1927785Y572000D02*
Y569485D01*
X1925800Y567500D01*
G01X1958940Y538890D02*
X1960550Y540500D01*
X1963000D01*
G01X1956100Y537500D02*
X1957550D01*
X1958940Y538890D01*
G01X1925808Y562498D02*
X1924437Y561127D01*
Y558237D01*
G01X1921000Y554400D02*
Y553100D01*
X1920500Y552600D01*
X1916363D01*
X1915963Y553000D01*
X1912750D01*
G01X1924437Y558237D02*
X1925574Y557100D01*
X1927600D01*
X1928500Y556200D01*
Y553500D01*
G01X1924437Y558237D02*
X1923537D01*
X1921000Y555700D01*
Y554400D01*
G01X1918000Y582000D02*
Y584220D01*
X1911520Y590700D01*
X1906000D01*
G01Y582000D02*
X1906400D01*
X1915100Y573300D01*
X1918000D01*
G01X1904800Y577700D02*
Y580800D01*
X1906000Y582000D01*
G01Y573300D02*
X1909300D01*
X1918000Y564600D01*
G01X1919500Y558900D02*
X1918000Y560400D01*
Y564600D01*
G01X1904790Y586240D02*
X1901415Y582865D01*
X1899550D01*
G01X1926240Y591260D02*
X1923230Y588250D01*
X1920670D01*
X1918880Y586460D01*
G01X1943750Y541100D02*
Y543332D01*
X1942982Y544100D01*
X1940200D01*
X1939800Y543700D01*
G01X1922500Y546700D02*
Y548900D01*
X1921500Y549900D01*
G01X1925941Y546500D02*
X1922700D01*
X1922500Y546700D01*
G01X1898850Y545250D02*
X1900900Y543200D01*
X1916000D01*
X1921500Y548700D01*
Y549900D01*
G01X1930625Y566185D02*
X1933526D01*
X1934600Y565111D01*
Y561900D01*
G01X1930600Y561000D02*
Y559259D01*
X1931059Y558800D01*
Y553500D01*
G01X1928500Y546500D02*
Y548900D01*
X1928900Y549300D01*
X1930700D01*
X1931059Y548941D01*
Y546500D01*
G01X1959100Y542500D02*
Y544600D01*
X1957174Y546526D01*
Y547717D01*
X1956191Y548700D01*
G01X1964281Y525057D02*
Y531065D01*
X1960346Y535000D01*
X1958500D01*
G01X1969100Y556263D02*
X1967363Y558000D01*
X1960772D01*
X1955163Y552391D01*
Y551211D01*
X1954350Y550398D01*
Y545350D01*
G01D02*
Y542050D01*
X1949600Y537300D01*
Y534700D01*
X1947500Y532600D01*
G01X1924800Y586400D02*
X1925900Y587500D01*
X1929790D01*
X1932390Y590100D01*
G01X1934350Y609250D02*
X1929250D01*
X1928500Y608500D01*
Y606000D01*
G01X1921250Y596900D02*
Y595350D01*
X1918000Y592100D01*
Y590700D01*
G01X1913180Y601923D02*
X1916438Y598665D01*
X1920242D01*
X1921250Y597657D01*
Y596900D01*
G01X1906900Y603200D02*
X1906000Y602300D01*
Y590700D01*
G01X1910150Y597900D02*
X1910900Y598650D01*
X1915050D01*
X1916800Y596900D01*
X1917750D01*
G01X1910150Y597900D02*
X1909200Y596950D01*
Y595350D01*
X1911750Y592800D01*
G01X1931250Y611550D02*
Y612599D01*
X1929349Y614500D01*
X1927000D01*
G01X1952756Y597834D02*
X1952754D01*
X1948720Y593800D01*
X1942640D01*
X1941403Y592563D01*
X1936157D01*
X1933960Y594760D01*
X1929740D01*
G01D02*
Y591260D01*
G01X1921700Y613500D02*
X1925100D01*
X1927050Y611550D01*
X1927750D01*
G01X1925941Y606000D02*
Y609741D01*
X1927750Y611550D01*
G01X1931059Y599000D02*
X1933548D01*
X1933848Y599300D01*
X1938800D01*
X1941200Y601700D01*
X1954700D01*
X1956300Y603300D01*
Y609900D01*
X1959200Y612800D01*
X1963300D01*
G01X1902800Y599200D02*
Y596394D01*
X1902040Y595634D01*
Y591680D01*
X1901460Y591100D01*
X1899700D01*
G01X1952756Y589960D02*
X1956200Y593404D01*
Y601200D01*
X1958300Y603300D01*
Y605300D01*
X1961000Y608000D01*
X1964100D01*
G01X1973004Y143120D02*
X1972305D01*
X1971890Y143535D01*
X1968376D01*
G01X1964382Y147318D02*
Y146606D01*
X1965485Y145503D01*
X1968376D01*
G01X1959821Y149724D02*
Y149379D01*
X1964700Y144500D01*
Y142774D01*
X1965907Y141567D01*
X1968376D01*
G01X1966311Y156309D02*
Y153389D01*
X1966700Y153000D01*
Y152400D01*
G01X1963092Y167936D02*
Y167104D01*
X1963751Y166445D01*
Y163564D01*
G01X1962551Y180204D02*
X1960252D01*
G01Y182172D02*
X1962551D01*
G01X1964481Y506010D02*
Y508750D01*
X1964270Y508961D01*
Y511410D01*
G01X1968375Y509375D02*
X1967040Y508040D01*
Y506010D01*
G01X1964281Y525057D02*
Y524381D01*
X1961600Y521700D01*
Y516100D01*
X1961922Y515778D01*
Y513010D01*
G01X1959120Y547050D02*
Y549835D01*
X1960078Y550793D01*
G01X1963000Y545500D02*
X1961850D01*
X1960300Y547050D01*
X1959120D01*
G01X1961715Y555639D02*
X1963501D01*
X1964640Y554500D01*
X1966100D01*
G01X1967500Y566700D02*
X1971300D01*
X1972800Y565200D01*
G01X1967500Y566700D02*
Y563059D01*
X1967441Y563000D01*
G01X1966941Y583300D02*
Y580459D01*
X1967500Y579900D01*
Y566700D01*
G01X1965700Y578200D02*
X1962800D01*
X1962500Y578500D01*
G01X1969100Y554600D02*
Y556263D01*
G01D02*
X1970000Y557163D01*
Y563000D01*
G01X1969500Y583300D02*
Y578400D01*
X1969800Y578100D01*
G01X1970000Y594700D02*
X1969300D01*
X1966800Y592200D01*
Y588800D01*
X1965000Y587000D01*
X1962100D01*
X1959200Y584100D01*
Y574929D01*
G01D02*
Y573200D01*
X1962400Y570000D01*
X1964882D01*
G01X1963200Y594600D02*
Y593173D01*
X1961771Y591744D01*
G01X1971000Y603100D02*
Y605300D01*
X1968300Y608000D01*
X1964100D01*
G01X1964382Y590300D02*
Y592282D01*
X1965300Y593200D01*
Y599000D01*
X1964300Y600000D01*
Y601900D01*
G01D02*
Y602600D01*
X1964800Y603100D01*
X1967500D01*
G01X1970000Y598200D02*
X1972000D01*
X1973000Y597200D01*
G54D167*
X1706065Y141740D03*
X1707042Y147319D03*
G54D185*
X1780700Y89500D03*
Y94500D03*
X1802300D03*
Y89500D03*
X1780700Y99500D03*
X1802300D03*
Y104500D03*
X1780700D03*
G54D83*
X503389Y136125D03*
G54D38*
X17300Y450210D03*
X1839390Y59416D03*
G54D56*
X83500Y229800D03*
Y234800D03*
Y239800D03*
Y224800D03*
G54D194*
X1887327Y511202D03*
X1929453Y532541D03*
G54D47*
X94683Y-5822D03*
Y31978D03*
Y13078D03*
Y69778D03*
Y50878D03*
Y88678D03*
Y514079D03*
Y532955D03*
Y570755D03*
Y589679D03*
Y551879D03*
Y608555D03*
X637793Y-5822D03*
Y31978D03*
Y13078D03*
Y69778D03*
Y50878D03*
Y88678D03*
Y514079D03*
Y532955D03*
Y570755D03*
Y589679D03*
Y551879D03*
Y608555D03*
X744293Y-5822D03*
Y31978D03*
Y13078D03*
Y69778D03*
Y88678D03*
Y50878D03*
Y514079D03*
Y570755D03*
Y532955D03*
Y589679D03*
Y551879D03*
Y608555D03*
X1287403Y-5822D03*
Y31978D03*
Y13078D03*
Y69778D03*
Y88678D03*
Y50878D03*
Y514079D03*
Y570755D03*
Y532955D03*
Y589679D03*
Y551879D03*
Y608555D03*
G54D65*
X56872Y310550D03*
Y318050D03*
X48372Y314300D03*
X690704Y274026D03*
X682204Y277776D03*
Y270276D03*
X1497600Y164750D03*
Y172250D03*
X1489100Y168500D03*
X1518798Y166578D03*
Y174078D03*
X1510298Y170328D03*
X1628500Y31900D03*
Y24400D03*
X1637000Y28150D03*
X1648400Y67721D03*
Y60221D03*
X1648900Y53121D03*
Y45621D03*
X1652250Y275750D03*
X1643750Y279500D03*
X1652250Y283250D03*
X1646250Y311000D03*
X1656900Y63971D03*
X1657400Y49371D03*
X1654750Y307250D03*
Y314750D03*
X1743650Y74700D03*
X1735150Y78450D03*
X1743650Y82200D03*
X1774900Y599750D03*
X1766400Y603500D03*
Y596000D03*
X1893850Y575087D03*
Y582587D03*
X1885350Y578837D03*
X1904250Y556750D03*
X1912750Y553000D03*
X1904250Y549250D03*
G54D149*
X1554960Y145900D03*
Y153300D03*
X1557520Y145900D03*
Y153300D03*
X1552400Y145900D03*
Y153300D03*
X1847000Y516600D03*
Y525600D03*
X1853900Y516600D03*
Y525600D03*
G54D74*
X116927Y22133D03*
Y4023D03*
X120273Y22133D03*
X126966D03*
X133659D03*
X143699D03*
X150392D03*
X157084D03*
X163777D03*
X123620Y4023D03*
X130313D03*
X137006D03*
X147045D03*
X153738D03*
X160431D03*
X167124D03*
X137006Y22133D03*
X140352D03*
X143699Y4023D03*
X140352D03*
X120273D03*
X167124Y22133D03*
X150392Y4023D03*
X147045Y22133D03*
X126966Y4023D03*
X123620Y22133D03*
X157084Y4023D03*
X153738Y22133D03*
X133659Y4023D03*
X163777D03*
X160431Y22133D03*
X130313D03*
X116927Y59933D03*
Y41823D03*
X120273Y59933D03*
X126966D03*
X133659D03*
X143699D03*
X150392D03*
X157084D03*
X163777D03*
X123620Y41823D03*
X130313D03*
X137006D03*
X147045D03*
X153738D03*
X160431D03*
X167124D03*
X137006Y59933D03*
X140352D03*
X143699Y41823D03*
X140352D03*
X120273D03*
X167124Y59933D03*
X150392Y41823D03*
X147045Y59933D03*
X126966Y41823D03*
X123620Y59933D03*
X157084Y41823D03*
X153738Y59933D03*
X133659Y41823D03*
X163777D03*
X160431Y59933D03*
X130313D03*
X116927Y97733D03*
Y79623D03*
X120273Y97733D03*
X126966D03*
X133659D03*
X143699D03*
X150392D03*
X157084D03*
X163777D03*
X123620Y79623D03*
X130313D03*
X137006D03*
X147045D03*
X153738D03*
X160431D03*
X167124D03*
X137006Y97733D03*
X140352D03*
X143699Y79623D03*
X140352D03*
X120273D03*
X167124Y97733D03*
X150392Y79623D03*
X147045Y97733D03*
X126966Y79623D03*
X123620Y97733D03*
X157084Y79623D03*
X153738Y97733D03*
X133659Y79623D03*
X163777D03*
X160431Y97733D03*
X130313D03*
X167124Y505024D03*
X163777D03*
X160431D03*
X157084D03*
X153738D03*
X150392D03*
X147045D03*
X143699D03*
X140352D03*
X137006D03*
X133659D03*
X130313D03*
X126966D03*
X123620D03*
X120273D03*
X116927D03*
X167124Y523134D03*
X163777D03*
X160431D03*
X157084D03*
X153738D03*
X150392D03*
X147045D03*
X143699D03*
X140352D03*
X137006D03*
X133659D03*
X130313D03*
X126966D03*
X123620D03*
X120273D03*
X116927D03*
X167124Y580624D03*
X163777D03*
X160431D03*
X157084D03*
X153738D03*
X150392D03*
X147045D03*
X143699D03*
X140352D03*
X137006D03*
X133659D03*
X130313D03*
X126966D03*
X123620D03*
X120273D03*
X116927D03*
X167124Y542824D03*
X163777D03*
X160431D03*
X157084D03*
X153738D03*
X150392D03*
X147045D03*
X143699D03*
X140352D03*
X137006D03*
X133659D03*
X130313D03*
X126966D03*
X123620D03*
X120273D03*
X116927D03*
X167124Y560934D03*
X163777D03*
X160431D03*
X157084D03*
X153738D03*
X150392D03*
X147045D03*
X143699D03*
X140352D03*
X137006D03*
X133659D03*
X130313D03*
X126966D03*
X123620D03*
X120273D03*
X116927D03*
X167124Y598734D03*
X163777D03*
X160431D03*
X157084D03*
X153738D03*
X150392D03*
X147045D03*
X143699D03*
X140352D03*
X137006D03*
X133659D03*
X130313D03*
X126966D03*
X123620D03*
X120273D03*
X116927D03*
X170470Y22133D03*
X180510D03*
X187203D03*
X193896D03*
X200588D03*
X207281D03*
X217321D03*
X224014D03*
X230707D03*
X173817Y4023D03*
X183856D03*
X190549D03*
X197242D03*
X203935D03*
X210628D03*
X220667D03*
X227360D03*
X217321D03*
X213974D03*
X180510D03*
X177163D03*
X210628Y22133D03*
X213974D03*
X173817D03*
X177163D03*
X170470Y4023D03*
X224014D03*
X220667Y22133D03*
X200588Y4023D03*
X197242Y22133D03*
X230707Y4023D03*
X227360Y22133D03*
X207281Y4023D03*
X203935Y22133D03*
X187203Y4023D03*
X183856Y22133D03*
X193896Y4023D03*
X190549Y22133D03*
X170470Y59933D03*
X180510D03*
X187203D03*
X193896D03*
X200588D03*
X207281D03*
X217321D03*
X224014D03*
X230707D03*
X173817Y41823D03*
X183856D03*
X190549D03*
X197242D03*
X203935D03*
X210628D03*
X220667D03*
X227360D03*
X217321D03*
X213974D03*
X180510D03*
X177163D03*
X210628Y59933D03*
X213974D03*
X173817D03*
X177163D03*
X170470Y41823D03*
X224014D03*
X220667Y59933D03*
X200588Y41823D03*
X197242Y59933D03*
X230707Y41823D03*
X227360Y59933D03*
X207281Y41823D03*
X203935Y59933D03*
X187203Y41823D03*
X183856Y59933D03*
X193896Y41823D03*
X190549Y59933D03*
X170470Y97733D03*
X180510D03*
X187203D03*
X193896D03*
X200588D03*
X207281D03*
X217321D03*
X224014D03*
X230707D03*
X173817Y79623D03*
X183856D03*
X190549D03*
X197242D03*
X203935D03*
X210628D03*
X220667D03*
X227360D03*
X217321D03*
X213974D03*
X180510D03*
X177163D03*
X210628Y97733D03*
X213974D03*
X173817D03*
X177163D03*
X170470Y79623D03*
X224014D03*
X220667Y97733D03*
X200588Y79623D03*
X197242Y97733D03*
X230707Y79623D03*
X227360Y97733D03*
X207281Y79623D03*
X203935Y97733D03*
X187203Y79623D03*
X183856Y97733D03*
X193896Y79623D03*
X190549Y97733D03*
X230707Y505024D03*
X227360D03*
X224014D03*
X220667D03*
X217321D03*
X213974D03*
X210628D03*
X207281D03*
X203935D03*
X200588D03*
X197242D03*
X193896D03*
X190549D03*
X187203D03*
X183856D03*
X180510D03*
X177163D03*
X173817D03*
X170470D03*
X230707Y523134D03*
X227360D03*
X224014D03*
X220667D03*
X217321D03*
X213974D03*
X210628D03*
X207281D03*
X203935D03*
X200588D03*
X197242D03*
X193896D03*
X190549D03*
X187203D03*
X183856D03*
X180510D03*
X177163D03*
X173817D03*
X170470D03*
X230707Y580624D03*
X227360D03*
X224014D03*
X220667D03*
X217321D03*
X213974D03*
X210628D03*
X207281D03*
X203935D03*
X200588D03*
X197242D03*
X193896D03*
X190549D03*
X187203D03*
X183856D03*
X180510D03*
X177163D03*
X173817D03*
X170470D03*
X230707Y542824D03*
X227360D03*
X224014D03*
X220667D03*
X217321D03*
X213974D03*
X210628D03*
X207281D03*
X203935D03*
X200588D03*
X197242D03*
X193896D03*
X190549D03*
X187203D03*
X183856D03*
X180510D03*
X177163D03*
X173817D03*
X170470D03*
X230707Y560934D03*
X227360D03*
X224014D03*
X220667D03*
X217321D03*
X213974D03*
X210628D03*
X207281D03*
X203935D03*
X200588D03*
X197242D03*
X193896D03*
X190549D03*
X187203D03*
X183856D03*
X180510D03*
X177163D03*
X173817D03*
X170470D03*
X230707Y598734D03*
X227360D03*
X224014D03*
X220667D03*
X217321D03*
X213974D03*
X210628D03*
X207281D03*
X203935D03*
X200588D03*
X197242D03*
X193896D03*
X190549D03*
X187203D03*
X183856D03*
X180510D03*
X177163D03*
X173817D03*
X170470D03*
X237399Y22133D03*
X244092D03*
X254132D03*
X260825D03*
X267518D03*
X274210D03*
X280903D03*
X290943D03*
X234053Y4023D03*
X240746D03*
X247439D03*
X257478D03*
X264171D03*
X270864D03*
X277557D03*
X284250D03*
X290943D03*
X287596D03*
X254132D03*
X250785D03*
X284250Y22133D03*
X287596D03*
X247439D03*
X250785D03*
X260825Y4023D03*
X257478Y22133D03*
X237399Y4023D03*
X234053Y22133D03*
X267518Y4023D03*
X264171Y22133D03*
X244092Y4023D03*
X240746Y22133D03*
X274210Y4023D03*
X270864Y22133D03*
X280903Y4023D03*
X277557Y22133D03*
X237399Y59933D03*
X244092D03*
X254132D03*
X260825D03*
X267518D03*
X274210D03*
X280903D03*
X290943D03*
X234053Y41823D03*
X240746D03*
X247439D03*
X257478D03*
X264171D03*
X270864D03*
X277557D03*
X284250D03*
X290943D03*
X287596D03*
X254132D03*
X250785D03*
X284250Y59933D03*
X287596D03*
X247439D03*
X250785D03*
X260825Y41823D03*
X257478Y59933D03*
X237399Y41823D03*
X234053Y59933D03*
X267518Y41823D03*
X264171Y59933D03*
X244092Y41823D03*
X240746Y59933D03*
X274210Y41823D03*
X270864Y59933D03*
X280903Y41823D03*
X277557Y59933D03*
X237399Y97733D03*
X244092D03*
X254132D03*
X260825D03*
X267518D03*
X274210D03*
X280903D03*
X290943D03*
X234053Y79623D03*
X240746D03*
X247439D03*
X257478D03*
X264171D03*
X270864D03*
X277557D03*
X284250D03*
X290943D03*
X287596D03*
X254132D03*
X250785D03*
X284250Y97733D03*
X287596D03*
X247439D03*
X250785D03*
X260825Y79623D03*
X257478Y97733D03*
X237399Y79623D03*
X234053Y97733D03*
X267518Y79623D03*
X264171Y97733D03*
X244092Y79623D03*
X240746Y97733D03*
X274210Y79623D03*
X270864Y97733D03*
X280903Y79623D03*
X277557Y97733D03*
X290943Y505024D03*
X287596D03*
X284250D03*
X280903D03*
X277557D03*
X274210D03*
X270864D03*
X267518D03*
X264171D03*
X260825D03*
X257478D03*
X254132D03*
X250785D03*
X247439D03*
X244092D03*
X240746D03*
X237399D03*
X234053D03*
X290943Y523134D03*
X287596D03*
X284250D03*
X280903D03*
X277557D03*
X274210D03*
X270864D03*
X267518D03*
X264171D03*
X260825D03*
X257478D03*
X254132D03*
X250785D03*
X247439D03*
X244092D03*
X240746D03*
X237399D03*
X234053D03*
X290943Y580624D03*
X287596D03*
X284250D03*
X280903D03*
X277557D03*
X274210D03*
X270864D03*
X267518D03*
X264171D03*
X260825D03*
X257478D03*
X254132D03*
X250785D03*
X247439D03*
X244092D03*
X240746D03*
X237399D03*
X234053D03*
X290943Y542824D03*
X287596D03*
X284250D03*
X280903D03*
X277557D03*
X274210D03*
X270864D03*
X267518D03*
X264171D03*
X260825D03*
X257478D03*
X254132D03*
X250785D03*
X247439D03*
X244092D03*
X240746D03*
X237399D03*
X234053D03*
X290943Y560934D03*
X287596D03*
X284250D03*
X280903D03*
X277557D03*
X274210D03*
X270864D03*
X267518D03*
X264171D03*
X260825D03*
X257478D03*
X254132D03*
X250785D03*
X247439D03*
X244092D03*
X240746D03*
X237399D03*
X234053D03*
X290943Y598734D03*
X287596D03*
X284250D03*
X280903D03*
X277557D03*
X274210D03*
X270864D03*
X267518D03*
X264171D03*
X260825D03*
X257478D03*
X254132D03*
X250785D03*
X247439D03*
X244092D03*
X240746D03*
X237399D03*
X234053D03*
X341140Y4023D03*
X351179D03*
X311021Y22133D03*
X317714D03*
X327754D03*
X337793D03*
X347833D03*
X314368Y4023D03*
X321061D03*
X331100D03*
X297636Y22133D03*
X304329D03*
X294289Y4023D03*
X300982D03*
X307675D03*
X317714D03*
X307675Y22133D03*
X311021Y4023D03*
X314368Y22133D03*
X297636Y4023D03*
X294289Y22133D03*
X304329Y4023D03*
X300982Y22133D03*
X324407Y4023D03*
Y22133D03*
X327754Y4023D03*
X321061Y22133D03*
X334447D03*
X341140D03*
X337793Y4023D03*
X344486Y22133D03*
Y4023D03*
X347833D03*
X351179Y22133D03*
X354525Y4023D03*
X331100Y22133D03*
X334447Y4023D03*
X354525Y22133D03*
X341140Y41823D03*
X351179D03*
X311021Y59933D03*
X317714D03*
X327754D03*
X337793D03*
X347833D03*
X314368Y41823D03*
X321061D03*
X331100D03*
X297636Y59933D03*
X304329D03*
X294289Y41823D03*
X300982D03*
X307675D03*
X317714D03*
X307675Y59933D03*
X311021Y41823D03*
X314368Y59933D03*
X297636Y41823D03*
X294289Y59933D03*
X304329Y41823D03*
X300982Y59933D03*
X324407Y41823D03*
Y59933D03*
X327754Y41823D03*
X321061Y59933D03*
X334447D03*
X341140D03*
X337793Y41823D03*
X344486Y59933D03*
Y41823D03*
X347833D03*
X351179Y59933D03*
X354525Y41823D03*
X331100Y59933D03*
X334447Y41823D03*
X354525Y59933D03*
X341140Y79623D03*
X351179D03*
X311021Y97733D03*
X317714D03*
X327754D03*
X337793D03*
X347833D03*
X314368Y79623D03*
X321061D03*
X331100D03*
X297636Y97733D03*
X304329D03*
X294289Y79623D03*
X300982D03*
X307675D03*
X317714D03*
X307675Y97733D03*
X311021Y79623D03*
X314368Y97733D03*
X297636Y79623D03*
X294289Y97733D03*
X304329Y79623D03*
X300982Y97733D03*
X324407Y79623D03*
Y97733D03*
X327754Y79623D03*
X321061Y97733D03*
X334447D03*
X341140D03*
X337793Y79623D03*
X344486Y97733D03*
Y79623D03*
X347833D03*
X351179Y97733D03*
X354525Y79623D03*
X331100Y97733D03*
X334447Y79623D03*
X354525Y97733D03*
Y505024D03*
X351179D03*
X347833D03*
X344486D03*
X341140D03*
X337793D03*
X334447D03*
X331100D03*
X327754D03*
X324407D03*
X321061D03*
X317714D03*
X314368D03*
X311021D03*
X307675D03*
X304329D03*
X300982D03*
X297636D03*
X294289D03*
X354525Y523134D03*
X351179D03*
X347833D03*
X344486D03*
X341140D03*
X337793D03*
X334447D03*
X331100D03*
X327754D03*
X324407D03*
X321061D03*
X317714D03*
X314368D03*
X311021D03*
X307675D03*
X304329D03*
X300982D03*
X297636D03*
X294289D03*
X354525Y580624D03*
X351179D03*
X347833D03*
X344486D03*
X341140D03*
X337793D03*
X334447D03*
X331100D03*
X327754D03*
X324407D03*
X321061D03*
X317714D03*
X314368D03*
X311021D03*
X307675D03*
X304329D03*
X300982D03*
X297636D03*
X294289D03*
X354525Y542824D03*
X351179D03*
X347833D03*
X344486D03*
X341140D03*
X337793D03*
X334447D03*
X331100D03*
X327754D03*
X324407D03*
X321061D03*
X317714D03*
X314368D03*
X311021D03*
X307675D03*
X304329D03*
X300982D03*
X297636D03*
X294289D03*
X354525Y560934D03*
X351179D03*
X347833D03*
X344486D03*
X341140D03*
X337793D03*
X334447D03*
X331100D03*
X327754D03*
X324407D03*
X321061D03*
X317714D03*
X314368D03*
X311021D03*
X307675D03*
X304329D03*
X300982D03*
X297636D03*
X294289D03*
X354525Y598734D03*
X351179D03*
X347833D03*
X344486D03*
X341140D03*
X337793D03*
X334447D03*
X331100D03*
X327754D03*
X324407D03*
X321061D03*
X317714D03*
X314368D03*
X311021D03*
X307675D03*
X304329D03*
X300982D03*
X297636D03*
X294289D03*
X371258Y22133D03*
Y4023D03*
X357872D03*
X367911D03*
X398029D03*
X408069D03*
X357872Y22133D03*
X367911D03*
X401376D03*
X411415D03*
X414762D03*
X411415Y4023D03*
X394683D03*
Y22133D03*
X361218Y4023D03*
X364565D03*
X361218Y22133D03*
X364565D03*
X401376Y4023D03*
X404722Y22133D03*
X408069D03*
X414762Y4023D03*
X404722D03*
X398029Y22133D03*
X371258Y59933D03*
Y41823D03*
X357872D03*
X367911D03*
X398029D03*
X408069D03*
X357872Y59933D03*
X367911D03*
X401376D03*
X411415D03*
X414762D03*
X411415Y41823D03*
X394683D03*
Y59933D03*
X361218Y41823D03*
X364565D03*
X361218Y59933D03*
X364565D03*
X401376Y41823D03*
X404722Y59933D03*
X408069D03*
X414762Y41823D03*
X404722D03*
X398029Y59933D03*
X371258Y97733D03*
Y79623D03*
X357872D03*
X367911D03*
X398029D03*
X408069D03*
X357872Y97733D03*
X367911D03*
X401376D03*
X411415D03*
X414762D03*
X411415Y79623D03*
X394683D03*
Y97733D03*
X361218Y79623D03*
X364565D03*
X361218Y97733D03*
X364565D03*
X401376Y79623D03*
X404722Y97733D03*
X408069D03*
X414762Y79623D03*
X404722D03*
X398029Y97733D03*
X414762Y505024D03*
X411415D03*
X408069D03*
X404722D03*
X401376D03*
X398029D03*
X394683D03*
X371258D03*
X367911D03*
X364565D03*
X361218D03*
X357872D03*
X414762Y523134D03*
X411415D03*
X408069D03*
X404722D03*
X401376D03*
X398029D03*
X394683D03*
X371258D03*
X367911D03*
X364565D03*
X361218D03*
X357872D03*
X414762Y580624D03*
X411415D03*
X408069D03*
X404722D03*
X401376D03*
X398029D03*
X394683D03*
X371258D03*
X367911D03*
X364565D03*
X361218D03*
X357872D03*
X414762Y542824D03*
X411415D03*
X408069D03*
X404722D03*
X401376D03*
X398029D03*
X394683D03*
X371258D03*
X367911D03*
X364565D03*
X361218D03*
X357872D03*
X414762Y560934D03*
X411415D03*
X408069D03*
X404722D03*
X401376D03*
X398029D03*
X394683D03*
X371258D03*
X367911D03*
X364565D03*
X361218D03*
X357872D03*
X414762Y598734D03*
X411415D03*
X408069D03*
X404722D03*
X401376D03*
X398029D03*
X394683D03*
X371258D03*
X367911D03*
X364565D03*
X361218D03*
X357872D03*
X418108Y4023D03*
X424801D03*
X431494D03*
X418108Y22133D03*
X428147D03*
X434840D03*
X441533D03*
Y4023D03*
X448226Y22133D03*
X454919D03*
X461612D03*
X471651D03*
X478344D03*
X451573Y4023D03*
X458266D03*
X464958D03*
X474998D03*
X471651D03*
X468305D03*
X464958Y22133D03*
X468305D03*
X421455Y4023D03*
X448226D03*
X444880D03*
Y22133D03*
X431494D03*
X438187D03*
X424801D03*
X478344Y4023D03*
X474998Y22133D03*
X454919Y4023D03*
X451573Y22133D03*
X461612Y4023D03*
X458266Y22133D03*
X438187Y4023D03*
X434840D03*
X421455Y22133D03*
X428147Y4023D03*
X418108Y41823D03*
X424801D03*
X431494D03*
X418108Y59933D03*
X428147D03*
X434840D03*
X441533D03*
Y41823D03*
X448226Y59933D03*
X454919D03*
X461612D03*
X471651D03*
X478344D03*
X451573Y41823D03*
X458266D03*
X464958D03*
X474998D03*
X471651D03*
X468305D03*
X464958Y59933D03*
X468305D03*
X421455Y41823D03*
X448226D03*
X444880D03*
Y59933D03*
X431494D03*
X438187D03*
X424801D03*
X478344Y41823D03*
X474998Y59933D03*
X454919Y41823D03*
X451573Y59933D03*
X461612Y41823D03*
X458266Y59933D03*
X438187Y41823D03*
X434840D03*
X421455Y59933D03*
X428147Y41823D03*
X418108Y79623D03*
X424801D03*
X431494D03*
X418108Y97733D03*
X428147D03*
X434840D03*
X441533D03*
Y79623D03*
X448226Y97733D03*
X454919D03*
X461612D03*
X471651D03*
X478344D03*
X451573Y79623D03*
X458266D03*
X464958D03*
X474998D03*
X471651D03*
X468305D03*
X464958Y97733D03*
X468305D03*
X421455Y79623D03*
X448226D03*
X444880D03*
Y97733D03*
X431494D03*
X438187D03*
X424801D03*
X478344Y79623D03*
X474998Y97733D03*
X454919Y79623D03*
X451573Y97733D03*
X461612Y79623D03*
X458266Y97733D03*
X438187Y79623D03*
X434840D03*
X421455Y97733D03*
X428147Y79623D03*
X478344Y505024D03*
X474998D03*
X471651D03*
X468305D03*
X464958D03*
X461612D03*
X458266D03*
X454919D03*
X451573D03*
X448226D03*
X444880D03*
X441533D03*
X438187D03*
X434840D03*
X431494D03*
X428147D03*
X424801D03*
X421455D03*
X418108D03*
X478344Y523134D03*
X474998D03*
X471651D03*
X468305D03*
X464958D03*
X461612D03*
X458266D03*
X454919D03*
X451573D03*
X448226D03*
X444880D03*
X441533D03*
X438187D03*
X434840D03*
X431494D03*
X428147D03*
X424801D03*
X421455D03*
X418108D03*
X478344Y580624D03*
X474998D03*
X471651D03*
X468305D03*
X464958D03*
X461612D03*
X458266D03*
X454919D03*
X451573D03*
X448226D03*
X444880D03*
X441533D03*
X438187D03*
X434840D03*
X431494D03*
X428147D03*
X424801D03*
X421455D03*
X418108D03*
X478344Y542824D03*
X474998D03*
X471651D03*
X468305D03*
X464958D03*
X461612D03*
X458266D03*
X454919D03*
X451573D03*
X448226D03*
X444880D03*
X441533D03*
X438187D03*
X434840D03*
X431494D03*
X428147D03*
X424801D03*
X421455D03*
X418108D03*
X478344Y560934D03*
X474998D03*
X471651D03*
X468305D03*
X464958D03*
X461612D03*
X458266D03*
X454919D03*
X451573D03*
X448226D03*
X444880D03*
X441533D03*
X438187D03*
X434840D03*
X431494D03*
X428147D03*
X424801D03*
X421455D03*
X418108D03*
X478344Y598734D03*
X474998D03*
X471651D03*
X468305D03*
X464958D03*
X461612D03*
X458266D03*
X454919D03*
X451573D03*
X448226D03*
X444880D03*
X441533D03*
X438187D03*
X434840D03*
X431494D03*
X428147D03*
X424801D03*
X421455D03*
X418108D03*
X531888Y4023D03*
X538581D03*
X485037Y22133D03*
X491730D03*
X498423D03*
X508462D03*
X515155D03*
X521848D03*
X528541D03*
X535234D03*
X481691Y4023D03*
X488384D03*
X495077D03*
X501770D03*
X511809D03*
X518502D03*
X525195D03*
X508462D03*
X505116D03*
X538581Y22133D03*
X501770D03*
X505116D03*
X528541Y4023D03*
X525195Y22133D03*
X535234Y4023D03*
X531888Y22133D03*
X515155Y4023D03*
X511809Y22133D03*
X491730Y4023D03*
X488384Y22133D03*
X521848Y4023D03*
X518502Y22133D03*
X498423Y4023D03*
X495077Y22133D03*
X485037Y4023D03*
X481691Y22133D03*
X531888Y41823D03*
X538581D03*
X485037Y59933D03*
X491730D03*
X498423D03*
X508462D03*
X515155D03*
X521848D03*
X528541D03*
X535234D03*
X481691Y41823D03*
X488384D03*
X495077D03*
X501770D03*
X511809D03*
X518502D03*
X525195D03*
X508462D03*
X505116D03*
X538581Y59933D03*
X501770D03*
X505116D03*
X528541Y41823D03*
X525195Y59933D03*
X535234Y41823D03*
X531888Y59933D03*
X515155Y41823D03*
X511809Y59933D03*
X491730Y41823D03*
X488384Y59933D03*
X521848Y41823D03*
X518502Y59933D03*
X498423Y41823D03*
X495077Y59933D03*
X485037Y41823D03*
X481691Y59933D03*
X531888Y79623D03*
X538581D03*
X485037Y97733D03*
X491730D03*
X498423D03*
X508462D03*
X515155D03*
X521848D03*
X528541D03*
X535234D03*
X481691Y79623D03*
X488384D03*
X495077D03*
X501770D03*
X511809D03*
X518502D03*
X525195D03*
X508462D03*
X505116D03*
X538581Y97733D03*
X501770D03*
X505116D03*
X528541Y79623D03*
X525195Y97733D03*
X535234Y79623D03*
X531888Y97733D03*
X515155Y79623D03*
X511809Y97733D03*
X491730Y79623D03*
X488384Y97733D03*
X521848Y79623D03*
X518502Y97733D03*
X498423Y79623D03*
X495077Y97733D03*
X485037Y79623D03*
X481691Y97733D03*
X538581Y505024D03*
X535234D03*
X531888D03*
X528541D03*
X525195D03*
X521848D03*
X518502D03*
X515155D03*
X511809D03*
X508462D03*
X505116D03*
X501770D03*
X498423D03*
X495077D03*
X491730D03*
X488384D03*
X485037D03*
X481691D03*
X538581Y523134D03*
X535234D03*
X531888D03*
X528541D03*
X525195D03*
X521848D03*
X518502D03*
X515155D03*
X511809D03*
X508462D03*
X505116D03*
X501770D03*
X498423D03*
X495077D03*
X491730D03*
X488384D03*
X485037D03*
X481691D03*
X538581Y580624D03*
X535234D03*
X531888D03*
X528541D03*
X525195D03*
X521848D03*
X518502D03*
X515155D03*
X511809D03*
X508462D03*
X505116D03*
X501770D03*
X498423D03*
X495077D03*
X491730D03*
X488384D03*
X485037D03*
X481691D03*
X538581Y542824D03*
X535234D03*
X531888D03*
X528541D03*
X525195D03*
X521848D03*
X518502D03*
X515155D03*
X511809D03*
X508462D03*
X505116D03*
X501770D03*
X498423D03*
X495077D03*
X491730D03*
X488384D03*
X485037D03*
X481691D03*
X538581Y560934D03*
X535234D03*
X531888D03*
X528541D03*
X525195D03*
X521848D03*
X518502D03*
X515155D03*
X511809D03*
X508462D03*
X505116D03*
X501770D03*
X498423D03*
X495077D03*
X491730D03*
X488384D03*
X485037D03*
X481691D03*
X538581Y598734D03*
X535234D03*
X531888D03*
X528541D03*
X525195D03*
X521848D03*
X518502D03*
X515155D03*
X511809D03*
X508462D03*
X505116D03*
X501770D03*
X498423D03*
X495077D03*
X491730D03*
X488384D03*
X485037D03*
X481691D03*
X548620Y4023D03*
X555313D03*
X562006D03*
X545273Y22133D03*
X551966D03*
X558659D03*
X565352D03*
X572045D03*
X568699Y4023D03*
X582084Y22133D03*
X588777D03*
X595470D03*
X575392Y4023D03*
X585431D03*
X592124D03*
X598817D03*
X582084D03*
X578738D03*
X545273D03*
X541927D03*
X575392Y22133D03*
X578738D03*
X541927D03*
X602163Y4023D03*
Y22133D03*
X598817D03*
X588777Y4023D03*
X585431Y22133D03*
X565352Y4023D03*
X562006Y22133D03*
X595470Y4023D03*
X592124Y22133D03*
X572045Y4023D03*
X568699Y22133D03*
X551966Y4023D03*
X548620Y22133D03*
X558659Y4023D03*
X555313Y22133D03*
X548620Y41823D03*
X555313D03*
X562006D03*
X545273Y59933D03*
X551966D03*
X558659D03*
X565352D03*
X572045D03*
X568699Y41823D03*
X582084Y59933D03*
X588777D03*
X595470D03*
X575392Y41823D03*
X585431D03*
X592124D03*
X598817D03*
X582084D03*
X578738D03*
X545273D03*
X541927D03*
X575392Y59933D03*
X578738D03*
X541927D03*
X602163Y41823D03*
Y59933D03*
X598817D03*
X588777Y41823D03*
X585431Y59933D03*
X565352Y41823D03*
X562006Y59933D03*
X595470Y41823D03*
X592124Y59933D03*
X572045Y41823D03*
X568699Y59933D03*
X551966Y41823D03*
X548620Y59933D03*
X558659Y41823D03*
X555313Y59933D03*
X548620Y79623D03*
X555313D03*
X562006D03*
X545273Y97733D03*
X551966D03*
X558659D03*
X565352D03*
X572045D03*
X568699Y79623D03*
X582084Y97733D03*
X588777D03*
X595470D03*
X575392Y79623D03*
X585431D03*
X592124D03*
X598817D03*
X582084D03*
X578738D03*
X545273D03*
X541927D03*
X575392Y97733D03*
X578738D03*
X541927D03*
X602163Y79623D03*
Y97733D03*
X598817D03*
X588777Y79623D03*
X585431Y97733D03*
X565352Y79623D03*
X562006Y97733D03*
X595470Y79623D03*
X592124Y97733D03*
X572045Y79623D03*
X568699Y97733D03*
X551966Y79623D03*
X548620Y97733D03*
X558659Y79623D03*
X555313Y97733D03*
X602163Y505024D03*
X598817D03*
X595470D03*
X592124D03*
X588777D03*
X585431D03*
X582084D03*
X578738D03*
X575392D03*
X572045D03*
X568699D03*
X565352D03*
X562006D03*
X558659D03*
X555313D03*
X551966D03*
X548620D03*
X545273D03*
X541927D03*
X602163Y523134D03*
X598817D03*
X595470D03*
X592124D03*
X588777D03*
X585431D03*
X582084D03*
X578738D03*
X575392D03*
X572045D03*
X568699D03*
X565352D03*
X562006D03*
X558659D03*
X555313D03*
X551966D03*
X548620D03*
X545273D03*
X541927D03*
X602163Y580624D03*
X598817D03*
X595470D03*
X592124D03*
X588777D03*
X585431D03*
X582084D03*
X578738D03*
X575392D03*
X572045D03*
X568699D03*
X565352D03*
X562006D03*
X558659D03*
X555313D03*
X551966D03*
X548620D03*
X545273D03*
X541927D03*
X602163Y542824D03*
X598817D03*
X595470D03*
X592124D03*
X588777D03*
X585431D03*
X582084D03*
X578738D03*
X575392D03*
X572045D03*
X568699D03*
X565352D03*
X562006D03*
X558659D03*
X555313D03*
X551966D03*
X548620D03*
X545273D03*
X541927D03*
X602163Y560934D03*
X598817D03*
X595470D03*
X592124D03*
X588777D03*
X585431D03*
X582084D03*
X578738D03*
X575392D03*
X572045D03*
X568699D03*
X565352D03*
X562006D03*
X558659D03*
X555313D03*
X551966D03*
X548620D03*
X545273D03*
X541927D03*
X602163Y598734D03*
X598817D03*
X595470D03*
X592124D03*
X588777D03*
X585431D03*
X582084D03*
X578738D03*
X575392D03*
X572045D03*
X568699D03*
X565352D03*
X562006D03*
X558659D03*
X555313D03*
X551966D03*
X548620D03*
X545273D03*
X541927D03*
X608856Y22133D03*
X612203D03*
X615549Y4023D03*
X608856D03*
X612203D03*
X605510D03*
Y22133D03*
X615549D03*
X608856Y59933D03*
X612203D03*
X615549Y41823D03*
X608856D03*
X612203D03*
X605510D03*
Y59933D03*
X615549D03*
X608856Y97733D03*
X612203D03*
X615549Y79623D03*
X608856D03*
X612203D03*
X605510D03*
Y97733D03*
X615549D03*
Y505024D03*
X612203D03*
X608856D03*
X605510D03*
X615549Y523134D03*
X612203D03*
X608856D03*
X605510D03*
X615549Y580624D03*
X612203D03*
X608856D03*
X605510D03*
X615549Y542824D03*
X612203D03*
X608856D03*
X605510D03*
X615549Y560934D03*
X612203D03*
X608856D03*
X605510D03*
X615549Y598734D03*
X612203D03*
X608856D03*
X605510D03*
X786616Y4023D03*
X783269D03*
X779923D03*
X776576D03*
X773230D03*
X769883D03*
X766537D03*
X786616Y22133D03*
X783269D03*
X779923D03*
X776576D03*
X773230D03*
X769883D03*
X766537D03*
X786616Y79623D03*
X783269D03*
X779923D03*
X776576D03*
X773230D03*
X769883D03*
X766537D03*
X786616Y97733D03*
X783269D03*
X779923D03*
X776576D03*
X773230D03*
X769883D03*
X766537D03*
X786616Y41823D03*
X783269D03*
X779923D03*
X776576D03*
X773230D03*
X769883D03*
X766537D03*
X786616Y59933D03*
X783269D03*
X779923D03*
X776576D03*
X773230D03*
X769883D03*
X766537D03*
X786616Y505024D03*
X783269D03*
X779923D03*
X776576D03*
X773230D03*
X769883D03*
X766537D03*
X786616Y523134D03*
X783269D03*
X779923D03*
X776576D03*
X773230D03*
X769883D03*
X766537D03*
X786616Y580624D03*
X783269D03*
X779923D03*
X776576D03*
X773230D03*
X769883D03*
X766537D03*
X786616Y542824D03*
X783269D03*
X779923D03*
X776576D03*
X773230D03*
X769883D03*
X766537D03*
X786616Y560934D03*
X783269D03*
X779923D03*
X776576D03*
X773230D03*
X769883D03*
X766537D03*
X786616Y598734D03*
X783269D03*
X779923D03*
X776576D03*
X773230D03*
X769883D03*
X766537D03*
X846852Y4023D03*
X843506D03*
X840159D03*
X836813D03*
X833466D03*
X830120D03*
X826773D03*
X823427D03*
X820080D03*
X816734D03*
X813387D03*
X810041D03*
X806694D03*
X803348D03*
X800002D03*
X796655D03*
X793309D03*
X789962D03*
X846852Y22133D03*
X843506D03*
X840159D03*
X836813D03*
X833466D03*
X830120D03*
X826773D03*
X823427D03*
X820080D03*
X816734D03*
X813387D03*
X810041D03*
X806694D03*
X803348D03*
X800002D03*
X796655D03*
X793309D03*
X789962D03*
X846852Y79623D03*
X843506D03*
X840159D03*
X836813D03*
X833466D03*
X830120D03*
X826773D03*
X823427D03*
X820080D03*
X816734D03*
X813387D03*
X810041D03*
X806694D03*
X803348D03*
X800002D03*
X796655D03*
X793309D03*
X789962D03*
X846852Y97733D03*
X843506D03*
X840159D03*
X836813D03*
X833466D03*
X830120D03*
X826773D03*
X823427D03*
X820080D03*
X816734D03*
X813387D03*
X810041D03*
X806694D03*
X803348D03*
X800002D03*
X796655D03*
X793309D03*
X789962D03*
X846852Y41823D03*
X843506D03*
X840159D03*
X836813D03*
X833466D03*
X830120D03*
X826773D03*
X823427D03*
X820080D03*
X816734D03*
X813387D03*
X810041D03*
X806694D03*
X803348D03*
X800002D03*
X796655D03*
X793309D03*
X789962D03*
X846852Y59933D03*
X843506D03*
X840159D03*
X836813D03*
X833466D03*
X830120D03*
X826773D03*
X823427D03*
X820080D03*
X816734D03*
X813387D03*
X810041D03*
X806694D03*
X803348D03*
X800002D03*
X796655D03*
X793309D03*
X789962D03*
X846852Y505024D03*
X843506D03*
X840159D03*
X836813D03*
X833466D03*
X830120D03*
X826773D03*
X823427D03*
X820080D03*
X816734D03*
X813387D03*
X810041D03*
X806694D03*
X803348D03*
X800002D03*
X796655D03*
X793309D03*
X789962D03*
X846852Y523134D03*
X843506D03*
X840159D03*
X836813D03*
X833466D03*
X830120D03*
X826773D03*
X823427D03*
X820080D03*
X816734D03*
X813387D03*
X810041D03*
X806694D03*
X803348D03*
X800002D03*
X796655D03*
X793309D03*
X789962D03*
X846852Y580624D03*
X843506D03*
X840159D03*
X836813D03*
X833466D03*
X830120D03*
X826773D03*
X823427D03*
X820080D03*
X816734D03*
X813387D03*
X810041D03*
X806694D03*
X803348D03*
X800002D03*
X796655D03*
X793309D03*
X789962D03*
X846852Y542824D03*
X843506D03*
X840159D03*
X836813D03*
X833466D03*
X830120D03*
X826773D03*
X823427D03*
X820080D03*
X816734D03*
X813387D03*
X810041D03*
X806694D03*
X803348D03*
X800002D03*
X796655D03*
X793309D03*
X789962D03*
X846852Y560934D03*
X843506D03*
X840159D03*
X836813D03*
X833466D03*
X830120D03*
X826773D03*
X823427D03*
X820080D03*
X816734D03*
X813387D03*
X810041D03*
X806694D03*
X803348D03*
X800002D03*
X796655D03*
X793309D03*
X789962D03*
X846852Y598734D03*
X843506D03*
X840159D03*
X836813D03*
X833466D03*
X830120D03*
X826773D03*
X823427D03*
X820080D03*
X816734D03*
X813387D03*
X810041D03*
X806694D03*
X803348D03*
X800002D03*
X796655D03*
X793309D03*
X789962D03*
X910435Y4023D03*
X907088D03*
X903742D03*
X900395D03*
X897049D03*
X893702D03*
X890356D03*
X887009D03*
X883663D03*
X880317D03*
X876970D03*
X873624D03*
X870277D03*
X866931D03*
X863584D03*
X860238D03*
X856891D03*
X853545D03*
X850198D03*
X910435Y22133D03*
X907088D03*
X903742D03*
X900395D03*
X897049D03*
X893702D03*
X890356D03*
X887009D03*
X883663D03*
X880317D03*
X876970D03*
X873624D03*
X870277D03*
X866931D03*
X863584D03*
X860238D03*
X856891D03*
X853545D03*
X850198D03*
X910435Y79623D03*
X907088D03*
X903742D03*
X900395D03*
X897049D03*
X893702D03*
X890356D03*
X887009D03*
X883663D03*
X880317D03*
X876970D03*
X873624D03*
X870277D03*
X866931D03*
X863584D03*
X860238D03*
X856891D03*
X853545D03*
X850198D03*
X910435Y97733D03*
X907088D03*
X903742D03*
X900395D03*
X897049D03*
X893702D03*
X890356D03*
X887009D03*
X883663D03*
X880317D03*
X876970D03*
X873624D03*
X870277D03*
X866931D03*
X863584D03*
X860238D03*
X856891D03*
X853545D03*
X850198D03*
X910435Y41823D03*
X907088D03*
X903742D03*
X900395D03*
X897049D03*
X893702D03*
X890356D03*
X887009D03*
X883663D03*
X880317D03*
X876970D03*
X873624D03*
X870277D03*
X866931D03*
X863584D03*
X860238D03*
X856891D03*
X853545D03*
X850198D03*
X910435Y59933D03*
X907088D03*
X903742D03*
X900395D03*
X897049D03*
X893702D03*
X890356D03*
X887009D03*
X883663D03*
X880317D03*
X876970D03*
X873624D03*
X870277D03*
X866931D03*
X863584D03*
X860238D03*
X856891D03*
X853545D03*
X850198D03*
X910435Y505024D03*
X907088D03*
X903742D03*
X900395D03*
X897049D03*
X893702D03*
X890356D03*
X887009D03*
X883663D03*
X880317D03*
X876970D03*
X873624D03*
X870277D03*
X866931D03*
X863584D03*
X860238D03*
X856891D03*
X853545D03*
X850198D03*
X910435Y523134D03*
X907088D03*
X903742D03*
X900395D03*
X897049D03*
X893702D03*
X890356D03*
X887009D03*
X883663D03*
X880317D03*
X876970D03*
X873624D03*
X870277D03*
X866931D03*
X863584D03*
X860238D03*
X856891D03*
X853545D03*
X850198D03*
X910435Y580624D03*
X907088D03*
X903742D03*
X900395D03*
X897049D03*
X893702D03*
X890356D03*
X887009D03*
X883663D03*
X880317D03*
X876970D03*
X873624D03*
X870277D03*
X866931D03*
X863584D03*
X860238D03*
X856891D03*
X853545D03*
X850198D03*
X910435Y542824D03*
X907088D03*
X903742D03*
X900395D03*
X897049D03*
X893702D03*
X890356D03*
X887009D03*
X883663D03*
X880317D03*
X876970D03*
X873624D03*
X870277D03*
X866931D03*
X863584D03*
X860238D03*
X856891D03*
X853545D03*
X850198D03*
X910435Y560934D03*
X907088D03*
X903742D03*
X900395D03*
X897049D03*
X893702D03*
X890356D03*
X887009D03*
X883663D03*
X880317D03*
X876970D03*
X873624D03*
X870277D03*
X866931D03*
X863584D03*
X860238D03*
X856891D03*
X853545D03*
X850198D03*
X910435Y598734D03*
X907088D03*
X903742D03*
X900395D03*
X897049D03*
X893702D03*
X890356D03*
X887009D03*
X883663D03*
X880317D03*
X876970D03*
X873624D03*
X870277D03*
X866931D03*
X863584D03*
X860238D03*
X856891D03*
X853545D03*
X850198D03*
X970671Y4023D03*
X967324D03*
X963978D03*
X960631D03*
X957285D03*
X953939D03*
X950592D03*
X947246D03*
X943899D03*
X940553D03*
X937206D03*
X933860D03*
X930513D03*
X927167D03*
X923820D03*
X920474D03*
X917128D03*
X913781D03*
X970671Y22133D03*
X967324D03*
X963978D03*
X960631D03*
X957285D03*
X953939D03*
X950592D03*
X947246D03*
X943899D03*
X940553D03*
X937206D03*
X933860D03*
X930513D03*
X927167D03*
X923820D03*
X920474D03*
X917128D03*
X913781D03*
X970671Y79623D03*
X967324D03*
X963978D03*
X960631D03*
X957285D03*
X953939D03*
X950592D03*
X947246D03*
X943899D03*
X940553D03*
X937206D03*
X933860D03*
X930513D03*
X927167D03*
X923820D03*
X920474D03*
X917128D03*
X913781D03*
X970671Y97733D03*
X967324D03*
X963978D03*
X960631D03*
X957285D03*
X953939D03*
X950592D03*
X947246D03*
X943899D03*
X940553D03*
X937206D03*
X933860D03*
X930513D03*
X927167D03*
X923820D03*
X920474D03*
X917128D03*
X913781D03*
X970671Y41823D03*
X967324D03*
X963978D03*
X960631D03*
X957285D03*
X953939D03*
X950592D03*
X947246D03*
X943899D03*
X940553D03*
X937206D03*
X933860D03*
X930513D03*
X927167D03*
X923820D03*
X920474D03*
X917128D03*
X913781D03*
X970671Y59933D03*
X967324D03*
X963978D03*
X960631D03*
X957285D03*
X953939D03*
X950592D03*
X947246D03*
X943899D03*
X940553D03*
X937206D03*
X933860D03*
X930513D03*
X927167D03*
X923820D03*
X920474D03*
X917128D03*
X913781D03*
X970671Y505024D03*
X967324D03*
X963978D03*
X960631D03*
X957285D03*
X953939D03*
X950592D03*
X947246D03*
X943899D03*
X940553D03*
X937206D03*
X933860D03*
X930513D03*
X927167D03*
X923820D03*
X920474D03*
X917128D03*
X913781D03*
X970671Y523134D03*
X967324D03*
X963978D03*
X960631D03*
X957285D03*
X953939D03*
X950592D03*
X947246D03*
X943899D03*
X940553D03*
X937206D03*
X933860D03*
X930513D03*
X927167D03*
X923820D03*
X920474D03*
X917128D03*
X913781D03*
X970671Y580624D03*
X967324D03*
X963978D03*
X960631D03*
X957285D03*
X953939D03*
X950592D03*
X947246D03*
X943899D03*
X940553D03*
X937206D03*
X933860D03*
X930513D03*
X927167D03*
X923820D03*
X920474D03*
X917128D03*
X913781D03*
X970671Y542824D03*
X967324D03*
X963978D03*
X960631D03*
X957285D03*
X953939D03*
X950592D03*
X947246D03*
X943899D03*
X940553D03*
X937206D03*
X933860D03*
X930513D03*
X927167D03*
X923820D03*
X920474D03*
X917128D03*
X913781D03*
X970671Y560934D03*
X967324D03*
X963978D03*
X960631D03*
X957285D03*
X953939D03*
X950592D03*
X947246D03*
X943899D03*
X940553D03*
X937206D03*
X933860D03*
X930513D03*
X927167D03*
X923820D03*
X920474D03*
X917128D03*
X913781D03*
X970671Y598734D03*
X967324D03*
X963978D03*
X960631D03*
X957285D03*
X953939D03*
X950592D03*
X947246D03*
X943899D03*
X940553D03*
X937206D03*
X933860D03*
X930513D03*
X927167D03*
X923820D03*
X920474D03*
X917128D03*
X913781D03*
X1020868Y4023D03*
X1017521D03*
X1014175D03*
X1010828D03*
X1007482D03*
X1004135D03*
X1000789D03*
X997443D03*
X994096D03*
X990750D03*
X987403D03*
X984057D03*
X980710D03*
X977364D03*
X974017D03*
X1020868Y22133D03*
X1017521D03*
X1014175D03*
X1010828D03*
X1007482D03*
X1004135D03*
X1000789D03*
X997443D03*
X994096D03*
X990750D03*
X987403D03*
X984057D03*
X980710D03*
X977364D03*
X974017D03*
X1020868Y79623D03*
X1017521D03*
X1014175D03*
X1010828D03*
X1007482D03*
X1004135D03*
X1000789D03*
X997443D03*
X994096D03*
X990750D03*
X987403D03*
X984057D03*
X980710D03*
X977364D03*
X974017D03*
X1020868Y97733D03*
X1017521D03*
X1014175D03*
X1010828D03*
X1007482D03*
X1004135D03*
X1000789D03*
X997443D03*
X994096D03*
X990750D03*
X987403D03*
X984057D03*
X980710D03*
X977364D03*
X974017D03*
X1020868Y41823D03*
X1017521D03*
X1014175D03*
X1010828D03*
X1007482D03*
X1004135D03*
X1000789D03*
X997443D03*
X994096D03*
X990750D03*
X987403D03*
X984057D03*
X980710D03*
X977364D03*
X974017D03*
X1020868Y59933D03*
X1017521D03*
X1014175D03*
X1010828D03*
X1007482D03*
X1004135D03*
X1000789D03*
X997443D03*
X994096D03*
X990750D03*
X987403D03*
X984057D03*
X980710D03*
X977364D03*
X974017D03*
X1020868Y505024D03*
X1017521D03*
X1014175D03*
X1010828D03*
X1007482D03*
X1004135D03*
X1000789D03*
X997443D03*
X994096D03*
X990750D03*
X987403D03*
X984057D03*
X980710D03*
X977364D03*
X974017D03*
X1020868Y523134D03*
X1017521D03*
X1014175D03*
X1010828D03*
X1007482D03*
X1004135D03*
X1000789D03*
X997443D03*
X994096D03*
X990750D03*
X987403D03*
X984057D03*
X980710D03*
X977364D03*
X974017D03*
X1020868Y580624D03*
X1017521D03*
X1014175D03*
X1010828D03*
X1007482D03*
X1004135D03*
X1000789D03*
X997443D03*
X994096D03*
X990750D03*
X987403D03*
X984057D03*
X980710D03*
X977364D03*
X974017D03*
X1020868Y542824D03*
X1017521D03*
X1014175D03*
X1010828D03*
X1007482D03*
X1004135D03*
X1000789D03*
X997443D03*
X994096D03*
X990750D03*
X987403D03*
X984057D03*
X980710D03*
X977364D03*
X974017D03*
X1020868Y560934D03*
X1017521D03*
X1014175D03*
X1010828D03*
X1007482D03*
X1004135D03*
X1000789D03*
X997443D03*
X994096D03*
X990750D03*
X987403D03*
X984057D03*
X980710D03*
X977364D03*
X974017D03*
X1020868Y598734D03*
X1017521D03*
X1014175D03*
X1010828D03*
X1007482D03*
X1004135D03*
X1000789D03*
X997443D03*
X994096D03*
X990750D03*
X987403D03*
X984057D03*
X980710D03*
X977364D03*
X974017D03*
X1094490Y4023D03*
X1091143D03*
X1087797D03*
X1084450D03*
X1081104D03*
X1077757D03*
X1074411D03*
X1071065D03*
X1067718D03*
X1064372D03*
X1061025D03*
X1057679D03*
X1054332D03*
X1050986D03*
X1047639D03*
X1044293D03*
X1094490Y22133D03*
X1091143D03*
X1087797D03*
X1084450D03*
X1081104D03*
X1077757D03*
X1074411D03*
X1071065D03*
X1067718D03*
X1064372D03*
X1061025D03*
X1057679D03*
X1054332D03*
X1050986D03*
X1047639D03*
X1044293D03*
X1094490Y79623D03*
X1091143D03*
X1087797D03*
X1084450D03*
X1081104D03*
X1077757D03*
X1074411D03*
X1071065D03*
X1067718D03*
X1064372D03*
X1061025D03*
X1057679D03*
X1054332D03*
X1050986D03*
X1047639D03*
X1044293D03*
X1094490Y97733D03*
X1091143D03*
X1087797D03*
X1084450D03*
X1081104D03*
X1077757D03*
X1074411D03*
X1071065D03*
X1067718D03*
X1064372D03*
X1061025D03*
X1057679D03*
X1054332D03*
X1050986D03*
X1047639D03*
X1044293D03*
X1094490Y41823D03*
X1091143D03*
X1087797D03*
X1084450D03*
X1081104D03*
X1077757D03*
X1074411D03*
X1071065D03*
X1067718D03*
X1064372D03*
X1061025D03*
X1057679D03*
X1054332D03*
X1050986D03*
X1047639D03*
X1044293D03*
X1094490Y59933D03*
X1091143D03*
X1087797D03*
X1084450D03*
X1081104D03*
X1077757D03*
X1074411D03*
X1071065D03*
X1067718D03*
X1064372D03*
X1061025D03*
X1057679D03*
X1054332D03*
X1050986D03*
X1047639D03*
X1044293D03*
X1094490Y505024D03*
X1091143D03*
X1087797D03*
X1084450D03*
X1081104D03*
X1077757D03*
X1074411D03*
X1071065D03*
X1067718D03*
X1064372D03*
X1061025D03*
X1057679D03*
X1054332D03*
X1050986D03*
X1047639D03*
X1044293D03*
X1094490Y523134D03*
X1091143D03*
X1087797D03*
X1084450D03*
X1081104D03*
X1077757D03*
X1074411D03*
X1071065D03*
X1067718D03*
X1064372D03*
X1061025D03*
X1057679D03*
X1054332D03*
X1050986D03*
X1047639D03*
X1044293D03*
X1094490Y580624D03*
X1091143D03*
X1087797D03*
X1084450D03*
X1081104D03*
X1077757D03*
X1074411D03*
X1071065D03*
X1067718D03*
X1064372D03*
X1061025D03*
X1057679D03*
X1054332D03*
X1050986D03*
X1047639D03*
X1044293D03*
X1094490Y542824D03*
X1091143D03*
X1087797D03*
X1084450D03*
X1081104D03*
X1077757D03*
X1074411D03*
X1071065D03*
X1067718D03*
X1064372D03*
X1061025D03*
X1057679D03*
X1054332D03*
X1050986D03*
X1047639D03*
X1044293D03*
X1094490Y560934D03*
X1091143D03*
X1087797D03*
X1084450D03*
X1081104D03*
X1077757D03*
X1074411D03*
X1071065D03*
X1067718D03*
X1064372D03*
X1061025D03*
X1057679D03*
X1054332D03*
X1050986D03*
X1047639D03*
X1044293D03*
X1094490Y598734D03*
X1091143D03*
X1087797D03*
X1084450D03*
X1081104D03*
X1077757D03*
X1074411D03*
X1071065D03*
X1067718D03*
X1064372D03*
X1061025D03*
X1057679D03*
X1054332D03*
X1050986D03*
X1047639D03*
X1044293D03*
X1154726Y4023D03*
X1151380D03*
X1148033D03*
X1144687D03*
X1141340D03*
X1137994D03*
X1134647D03*
X1131301D03*
X1127954D03*
X1124608D03*
X1121261D03*
X1117915D03*
X1114568D03*
X1111222D03*
X1107876D03*
X1104529D03*
X1101183D03*
X1097836D03*
X1154726Y22133D03*
X1151380D03*
X1148033D03*
X1144687D03*
X1141340D03*
X1137994D03*
X1134647D03*
X1131301D03*
X1127954D03*
X1124608D03*
X1121261D03*
X1117915D03*
X1114568D03*
X1111222D03*
X1107876D03*
X1104529D03*
X1101183D03*
X1097836D03*
X1154726Y79623D03*
X1151380D03*
X1148033D03*
X1144687D03*
X1141340D03*
X1137994D03*
X1134647D03*
X1131301D03*
X1127954D03*
X1124608D03*
X1121261D03*
X1117915D03*
X1114568D03*
X1111222D03*
X1107876D03*
X1104529D03*
X1101183D03*
X1097836D03*
X1154726Y97733D03*
X1151380D03*
X1148033D03*
X1144687D03*
X1141340D03*
X1137994D03*
X1134647D03*
X1131301D03*
X1127954D03*
X1124608D03*
X1121261D03*
X1117915D03*
X1114568D03*
X1111222D03*
X1107876D03*
X1104529D03*
X1101183D03*
X1097836D03*
X1154726Y41823D03*
X1151380D03*
X1148033D03*
X1144687D03*
X1141340D03*
X1137994D03*
X1134647D03*
X1131301D03*
X1127954D03*
X1124608D03*
X1121261D03*
X1117915D03*
X1114568D03*
X1111222D03*
X1107876D03*
X1104529D03*
X1101183D03*
X1097836D03*
X1154726Y59933D03*
X1151380D03*
X1148033D03*
X1144687D03*
X1141340D03*
X1137994D03*
X1134647D03*
X1131301D03*
X1127954D03*
X1124608D03*
X1121261D03*
X1117915D03*
X1114568D03*
X1111222D03*
X1107876D03*
X1104529D03*
X1101183D03*
X1097836D03*
X1154726Y505024D03*
X1151380D03*
X1148033D03*
X1144687D03*
X1141340D03*
X1137994D03*
X1134647D03*
X1131301D03*
X1127954D03*
X1124608D03*
X1121261D03*
X1117915D03*
X1114568D03*
X1111222D03*
X1107876D03*
X1104529D03*
X1101183D03*
X1097836D03*
X1154726Y523134D03*
X1151380D03*
X1148033D03*
X1144687D03*
X1141340D03*
X1137994D03*
X1134647D03*
X1131301D03*
X1127954D03*
X1124608D03*
X1121261D03*
X1117915D03*
X1114568D03*
X1111222D03*
X1107876D03*
X1104529D03*
X1101183D03*
X1097836D03*
X1154726Y580624D03*
X1151380D03*
X1148033D03*
X1144687D03*
X1141340D03*
X1137994D03*
X1134647D03*
X1131301D03*
X1127954D03*
X1124608D03*
X1121261D03*
X1117915D03*
X1114568D03*
X1111222D03*
X1107876D03*
X1104529D03*
X1101183D03*
X1097836D03*
X1154726Y542824D03*
X1151380D03*
X1148033D03*
X1144687D03*
X1141340D03*
X1137994D03*
X1134647D03*
X1131301D03*
X1127954D03*
X1124608D03*
X1121261D03*
X1117915D03*
X1114568D03*
X1111222D03*
X1107876D03*
X1104529D03*
X1101183D03*
X1097836D03*
X1154726Y560934D03*
X1151380D03*
X1148033D03*
X1144687D03*
X1141340D03*
X1137994D03*
X1134647D03*
X1131301D03*
X1127954D03*
X1124608D03*
X1121261D03*
X1117915D03*
X1114568D03*
X1111222D03*
X1107876D03*
X1104529D03*
X1101183D03*
X1097836D03*
X1154726Y598734D03*
X1151380D03*
X1148033D03*
X1144687D03*
X1141340D03*
X1137994D03*
X1134647D03*
X1131301D03*
X1127954D03*
X1124608D03*
X1121261D03*
X1117915D03*
X1114568D03*
X1111222D03*
X1107876D03*
X1104529D03*
X1101183D03*
X1097836D03*
X1218309Y4023D03*
X1214962D03*
X1211616D03*
X1208269D03*
X1204923D03*
X1201576D03*
X1198230D03*
X1194883D03*
X1191537D03*
X1188191D03*
X1184844D03*
X1181498D03*
X1178151D03*
X1174805D03*
X1171458D03*
X1168112D03*
X1164765D03*
X1161419D03*
X1158072D03*
X1218309Y22133D03*
X1214962D03*
X1211616D03*
X1208269D03*
X1204923D03*
X1201576D03*
X1198230D03*
X1194883D03*
X1191537D03*
X1188191D03*
X1184844D03*
X1181498D03*
X1178151D03*
X1174805D03*
X1171458D03*
X1168112D03*
X1164765D03*
X1161419D03*
X1158072D03*
X1218309Y79623D03*
X1214962D03*
X1211616D03*
X1208269D03*
X1204923D03*
X1201576D03*
X1198230D03*
X1194883D03*
X1191537D03*
X1188191D03*
X1184844D03*
X1181498D03*
X1178151D03*
X1174805D03*
X1171458D03*
X1168112D03*
X1164765D03*
X1161419D03*
X1158072D03*
X1218309Y97733D03*
X1214962D03*
X1211616D03*
X1208269D03*
X1204923D03*
X1201576D03*
X1198230D03*
X1194883D03*
X1191537D03*
X1188191D03*
X1184844D03*
X1181498D03*
X1178151D03*
X1174805D03*
X1171458D03*
X1168112D03*
X1164765D03*
X1161419D03*
X1158072D03*
X1218309Y41823D03*
X1214962D03*
X1211616D03*
X1208269D03*
X1204923D03*
X1201576D03*
X1198230D03*
X1194883D03*
X1191537D03*
X1188191D03*
X1184844D03*
X1181498D03*
X1178151D03*
X1174805D03*
X1171458D03*
X1168112D03*
X1164765D03*
X1161419D03*
X1158072D03*
X1218309Y59933D03*
X1214962D03*
X1211616D03*
X1208269D03*
X1204923D03*
X1201576D03*
X1198230D03*
X1194883D03*
X1191537D03*
X1188191D03*
X1184844D03*
X1181498D03*
X1178151D03*
X1174805D03*
X1171458D03*
X1168112D03*
X1164765D03*
X1161419D03*
X1158072D03*
X1218309Y505024D03*
X1214962D03*
X1211616D03*
X1208269D03*
X1204923D03*
X1201576D03*
X1198230D03*
X1194883D03*
X1191537D03*
X1188191D03*
X1184844D03*
X1181498D03*
X1178151D03*
X1174805D03*
X1171458D03*
X1168112D03*
X1164765D03*
X1161419D03*
X1158072D03*
X1218309Y523134D03*
X1214962D03*
X1211616D03*
X1208269D03*
X1204923D03*
X1201576D03*
X1198230D03*
X1194883D03*
X1191537D03*
X1188191D03*
X1184844D03*
X1181498D03*
X1178151D03*
X1174805D03*
X1171458D03*
X1168112D03*
X1164765D03*
X1161419D03*
X1158072D03*
X1218309Y580624D03*
X1214962D03*
X1211616D03*
X1208269D03*
X1204923D03*
X1201576D03*
X1198230D03*
X1194883D03*
X1191537D03*
X1188191D03*
X1184844D03*
X1181498D03*
X1178151D03*
X1174805D03*
X1171458D03*
X1168112D03*
X1164765D03*
X1161419D03*
X1158072D03*
X1218309Y542824D03*
X1214962D03*
X1211616D03*
X1208269D03*
X1204923D03*
X1201576D03*
X1198230D03*
X1194883D03*
X1191537D03*
X1188191D03*
X1184844D03*
X1181498D03*
X1178151D03*
X1174805D03*
X1171458D03*
X1168112D03*
X1164765D03*
X1161419D03*
X1158072D03*
X1218309Y560934D03*
X1214962D03*
X1211616D03*
X1208269D03*
X1204923D03*
X1201576D03*
X1198230D03*
X1194883D03*
X1191537D03*
X1188191D03*
X1184844D03*
X1181498D03*
X1178151D03*
X1174805D03*
X1171458D03*
X1168112D03*
X1164765D03*
X1161419D03*
X1158072D03*
X1218309Y598734D03*
X1214962D03*
X1211616D03*
X1208269D03*
X1204923D03*
X1201576D03*
X1198230D03*
X1194883D03*
X1191537D03*
X1188191D03*
X1184844D03*
X1181498D03*
X1178151D03*
X1174805D03*
X1171458D03*
X1168112D03*
X1164765D03*
X1161419D03*
X1158072D03*
X1265159Y4023D03*
X1261813D03*
X1258466D03*
X1255120D03*
X1251773D03*
X1248427D03*
X1245080D03*
X1241734D03*
X1238387D03*
X1235041D03*
X1231694D03*
X1228348D03*
X1225002D03*
X1221655D03*
X1265159Y22133D03*
X1261813D03*
X1258466D03*
X1255120D03*
X1251773D03*
X1248427D03*
X1245080D03*
X1241734D03*
X1238387D03*
X1235041D03*
X1231694D03*
X1228348D03*
X1225002D03*
X1221655D03*
X1265159Y79623D03*
X1261813D03*
X1258466D03*
X1255120D03*
X1251773D03*
X1248427D03*
X1245080D03*
X1241734D03*
X1238387D03*
X1235041D03*
X1231694D03*
X1228348D03*
X1225002D03*
X1221655D03*
X1265159Y97733D03*
X1261813D03*
X1258466D03*
X1255120D03*
X1251773D03*
X1248427D03*
X1245080D03*
X1241734D03*
X1238387D03*
X1235041D03*
X1231694D03*
X1228348D03*
X1225002D03*
X1221655D03*
X1265159Y41823D03*
X1261813D03*
X1258466D03*
X1255120D03*
X1251773D03*
X1248427D03*
X1245080D03*
X1241734D03*
X1238387D03*
X1235041D03*
X1231694D03*
X1228348D03*
X1225002D03*
X1221655D03*
X1265159Y59933D03*
X1261813D03*
X1258466D03*
X1255120D03*
X1251773D03*
X1248427D03*
X1245080D03*
X1241734D03*
X1238387D03*
X1235041D03*
X1231694D03*
X1228348D03*
X1225002D03*
X1221655D03*
X1265159Y505024D03*
X1261813D03*
X1258466D03*
X1255120D03*
X1251773D03*
X1248427D03*
X1245080D03*
X1241734D03*
X1238387D03*
X1235041D03*
X1231694D03*
X1228348D03*
X1225002D03*
X1221655D03*
X1265159Y523134D03*
X1261813D03*
X1258466D03*
X1255120D03*
X1251773D03*
X1248427D03*
X1245080D03*
X1241734D03*
X1238387D03*
X1235041D03*
X1231694D03*
X1228348D03*
X1225002D03*
X1221655D03*
X1265159Y580624D03*
X1261813D03*
X1258466D03*
X1255120D03*
X1251773D03*
X1248427D03*
X1245080D03*
X1241734D03*
X1238387D03*
X1235041D03*
X1231694D03*
X1228348D03*
X1225002D03*
X1221655D03*
X1265159Y542824D03*
X1261813D03*
X1258466D03*
X1255120D03*
X1251773D03*
X1248427D03*
X1245080D03*
X1241734D03*
X1238387D03*
X1235041D03*
X1231694D03*
X1228348D03*
X1225002D03*
X1221655D03*
X1265159Y560934D03*
X1261813D03*
X1258466D03*
X1255120D03*
X1251773D03*
X1248427D03*
X1245080D03*
X1241734D03*
X1238387D03*
X1235041D03*
X1231694D03*
X1228348D03*
X1225002D03*
X1221655D03*
X1265159Y598734D03*
X1261813D03*
X1258466D03*
X1255120D03*
X1251773D03*
X1248427D03*
X1245080D03*
X1241734D03*
X1238387D03*
X1235041D03*
X1231694D03*
X1228348D03*
X1225002D03*
X1221655D03*
G54D92*
X586109Y367405D03*
G54D29*
X20340Y24559D03*
X16720Y53240D03*
X6840Y564000D03*
X8530Y529080D03*
X130564Y209283D03*
X130774Y241333D03*
X130250Y273300D03*
X130574Y305323D03*
Y337533D03*
X130834Y369363D03*
X780152Y209163D03*
X780182Y241283D03*
Y273533D03*
X780892Y305563D03*
X780722Y337353D03*
X780112Y369433D03*
G54D176*
X1741189Y165669D03*
X1745689D03*
X1750189D03*
X1736689D03*
X1732189D03*
X1727689D03*
X1723189D03*
X1718689D03*
X1723189Y173125D03*
X1718689D03*
X1727689D03*
X1732189D03*
X1736689D03*
X1741189D03*
X1745689D03*
X1750189D03*
X1721808Y601405D03*
X1781800Y588450D03*
G54D158*
X1629849Y156438D03*
X1685800Y165650D03*
X1785703Y69879D03*
X1839250Y98250D03*
G54D168*
X1697694Y151292D03*
X1690970Y103101D03*
X1676372Y138275D03*
X1692944Y144363D03*
X1691596Y162922D03*
G54D75*
X210427Y649705D03*
X398011Y649585D03*
X585478Y649314D03*
X901122Y649294D03*
X1214648Y649283D03*
X1528146Y649313D03*
G54D84*
X594741Y135085D03*
G54D93*
X584181Y360208D03*
G54D186*
X1830800Y513800D03*
Y503300D03*
X1834540Y513800D03*
X1838280D03*
Y503300D03*
G54D48*
X72600Y-10500D03*
Y17500D03*
X73350Y518400D03*
Y490400D03*
X153666Y140388D03*
Y168388D03*
X705900Y347800D03*
Y375800D03*
X1317000Y70500D03*
Y42500D03*
X1296100Y136950D03*
Y108950D03*
X1316000Y209000D03*
Y181000D03*
X1407000Y105000D03*
Y133000D03*
X1422000Y63500D03*
Y91500D03*
X1440500Y63500D03*
Y91500D03*
X1451600Y583300D03*
Y555300D03*
X1475500Y581500D03*
Y553500D03*
X1496000Y581500D03*
Y553500D03*
X1519000Y581500D03*
Y553500D03*
X1559330Y577970D03*
Y549970D03*
X1540110Y577870D03*
Y549870D03*
G54D177*
X1741189Y162269D03*
X1745689D03*
X1750189D03*
X1736689D03*
X1732189D03*
X1727689D03*
X1723189D03*
X1718689D03*
X1723189Y169725D03*
X1718689D03*
X1727689D03*
X1732189D03*
X1736689D03*
X1741189D03*
X1745689D03*
X1750189D03*
X1721808Y598005D03*
X1781800Y585050D03*
G54D159*
X1629618Y122418D03*
X1772903Y112612D03*
G54D66*
X80539Y320948D03*
X65800Y364500D03*
X110758Y122310D03*
X1609800Y82000D03*
X1741100Y61300D03*
X1773350Y567650D03*
Y571695D03*
X1883066Y473995D03*
G54D195*
X1894689Y518328D03*
G54D39*
X8846Y454070D03*
X1830936Y63276D03*
G54D57*
X68000Y232300D03*
G54D85*
X543984Y131273D03*
G54D169*
X1703100Y135246D03*
X1690860Y124143D03*
G54D196*
X1866730Y509560D03*
Y527560D03*
X1871850Y509560D03*
Y527560D03*
X1869290Y509560D03*
Y527560D03*
X1874410Y509560D03*
Y527560D03*
G54D178*
X1761339Y536791D03*
X1757402D03*
X1753465D03*
X1749528D03*
X1745591D03*
X1741654D03*
X1761339D03*
X1757402D03*
X1753465D03*
X1749528D03*
X1745591D03*
X1741654D03*
G54D187*
X1807521Y587899D03*
X1813505D03*
G54D67*
X83939Y320948D03*
X69200Y364500D03*
X114158Y122310D03*
X1613200Y82000D03*
X1744500Y61300D03*
X1776750Y567650D03*
Y571695D03*
X1886466Y473995D03*
G54D49*
X107249Y105000D03*
X102328D03*
X97406D03*
X92485D03*
X87564D03*
X82643D03*
X77721D03*
G54D94*
X600568Y359708D03*
G54D76*
G01X337642Y13200D02*
X334292D01*
G01X312442Y32100D02*
X308092D01*
G01X334292Y570900D02*
X337642D01*
G01X321334D02*
X324642D01*
G01X307992D02*
X312442D01*
G01X307992Y533100D02*
X312442D01*
G01X399200Y51000D02*
Y52666D01*
X401376Y54842D01*
G01X411650Y51000D02*
Y54623D01*
X411416Y54857D01*
G01X408184Y570900D02*
X404700D01*
G01X401950Y533100D02*
X408184D01*
G01X373400Y593800D02*
X373550Y593650D01*
X376204D01*
G01D02*
Y590786D01*
X377340Y589650D01*
G01X421368Y570900D02*
X417150D01*
G01X433508D02*
X430150D01*
G01Y533100D02*
X434199D01*
X434395Y532904D01*
G01X421368Y533100D02*
X417150D01*
G01X442508Y570900D02*
X446526D01*
X448226Y569200D01*
G01X618430Y488550D02*
Y491550D01*
G01X680500Y496500D02*
X680433Y496433D01*
X675518D01*
X674300Y495215D01*
Y489500D01*
G01X974250Y13200D02*
X970800D01*
G01X970942Y32100D02*
X974250D01*
G01X962050D02*
X957700D01*
G01X961950Y13200D02*
X957600D01*
G01X970942Y69900D02*
X974250D01*
G01X970942Y570900D02*
X974250D01*
G01X957600D02*
X962050D01*
G01X974250Y552000D02*
X970731D01*
G01X970942Y533100D02*
X974250D01*
G01X957600D02*
X962050D01*
G01X961950Y589800D02*
X960300D01*
X959100Y591000D01*
X957500D01*
G01X1003108Y32100D02*
X1005600D01*
X1006964Y30736D01*
X1008200D01*
G01X983900Y32100D02*
X987250D01*
G01Y13200D02*
X983900D01*
G01X1003108Y51000D02*
X1004449Y49659D01*
X1007370D01*
G01X1003108Y69900D02*
X1004673Y68335D01*
X1007380D01*
G01X1003108Y589800D02*
X1004542Y588366D01*
X1006406D01*
G01X1003108Y533100D02*
X1004671Y531537D01*
X1007207D01*
G01X983900Y570900D02*
X987250D01*
G01Y552000D02*
X983900D01*
G01Y533100D02*
X987250D01*
G01X1003108Y570900D02*
X1004598Y569410D01*
X1007332D01*
G01X1017000Y532800D02*
Y529576D01*
X1017519Y529057D01*
G01X1017000Y532800D02*
X1021622D01*
X1021800Y532978D01*
G01X1083116Y570900D02*
X1079758D01*
G01X1070976D02*
X1066758D01*
G01X1079758Y552000D02*
X1083116D01*
G01X1079758Y533100D02*
X1083807D01*
X1084003Y532904D01*
G01X1070976Y533100D02*
X1066758D01*
G01Y552000D02*
X1070976D01*
G01X1057792Y570900D02*
X1054308D01*
G01X1051558Y533100D02*
X1057792D01*
G01X1054308Y552000D02*
X1057792D01*
G01X1098300Y553100D02*
X1095800D01*
X1094700Y552000D01*
X1092116D01*
G01Y570900D02*
X1096134D01*
X1097834Y569200D01*
G01X1097969Y533618D02*
X1094134D01*
X1093616Y533100D01*
G01X1079758Y589800D02*
X1083108D01*
G01X1066758D02*
X1070242D01*
G01X1054308D02*
X1057792D01*
G01X1098160Y533809D02*
X1097969Y533618D01*
G01X1448600Y24550D02*
X1451600D01*
G01D02*
X1455100D01*
G01X1464500Y24250D02*
X1468000D01*
G01X1471500D02*
X1468000D01*
G01X1616893Y140782D02*
X1616599Y140488D01*
Y137538D01*
G01X1616750Y131500D02*
Y134248D01*
X1616891Y134389D01*
G01D02*
X1616599Y134681D01*
Y137538D01*
G01X1638938Y153286D02*
Y154277D01*
X1641099Y156438D01*
G01X1644930Y157200D02*
X1641861D01*
X1641099Y156438D01*
G01X1620250Y131500D02*
Y128299D01*
X1620040Y128089D01*
G01X1620250Y131500D02*
Y134178D01*
X1620040Y134388D01*
G01D02*
X1620099Y134447D01*
Y137538D01*
G01X1630049Y156438D02*
Y153846D01*
X1629489Y153286D01*
G01X1620040Y146987D02*
X1620200Y146827D01*
Y143900D01*
G01X1620040Y140687D02*
X1620200Y140847D01*
Y143900D01*
G01X1626339Y124940D02*
X1624547Y123148D01*
G01D02*
Y123111D01*
X1619388Y117952D01*
Y116340D01*
X324407Y9114D03*
X317714D03*
X307675Y17057D03*
Y28014D03*
X321061D03*
X324407D03*
X314368D03*
X331100D03*
Y17057D03*
X334446Y9114D03*
X354525Y28022D03*
X351179D03*
X344486D03*
X341140D03*
X334446Y28014D03*
X334447Y17057D03*
X311021Y9114D03*
X314368Y17057D03*
X324407D03*
X327754Y9114D03*
X321061Y17057D03*
X341140D03*
X337793Y9114D03*
X344486Y17057D03*
Y9122D03*
X347833D03*
X351179Y17057D03*
X354525Y9122D03*
X354526Y17057D03*
X317714Y46914D03*
Y35957D03*
X307928Y67802D03*
X307675Y54857D03*
X321061Y65814D03*
X324407D03*
X314368D03*
X331100D03*
X321061Y54857D03*
X327754Y35957D03*
Y46914D03*
X324407Y54857D03*
Y35957D03*
Y46914D03*
X314368Y54857D03*
X311021Y46914D03*
X331100Y54857D03*
X317714Y73757D03*
X327754D03*
X324407D03*
X354525Y65822D03*
X351179D03*
X344486D03*
X341140D03*
X334446Y46914D03*
X354526Y54857D03*
X354525Y46922D03*
X354526Y35957D03*
X351179Y54857D03*
X347833Y46922D03*
X344486D03*
Y35957D03*
Y54857D03*
X337793Y46914D03*
Y35957D03*
X341140Y54857D03*
X334447D03*
X347833Y73757D03*
X344486D03*
X337793D03*
X334447D03*
X354526D03*
X320784Y203219D03*
X330948Y201258D03*
X308198Y528863D03*
X317714Y536957D03*
Y547914D03*
Y585714D03*
X307675Y555857D03*
X307984Y566743D03*
X317714Y574757D03*
X324407Y585714D03*
X344486Y585722D03*
X327754Y536957D03*
X321061Y529014D03*
X334447Y555857D03*
X341140D03*
X337793Y547914D03*
X344486Y555857D03*
Y547922D03*
X347833D03*
X351179Y555857D03*
X354525Y547922D03*
X354526Y555857D03*
X331100D03*
X334446Y547914D03*
X311021D03*
X314368Y555857D03*
X324407Y547914D03*
Y555857D03*
X327754Y547914D03*
X321061Y555857D03*
X334446Y529014D03*
X341140Y529022D03*
X337793Y536957D03*
X347833D03*
X351179Y529022D03*
X354526Y536957D03*
X331100Y529014D03*
X311021Y536957D03*
X324407D03*
X311021Y574757D03*
X324407D03*
Y566814D03*
X327754Y574757D03*
X337793Y585714D03*
X347833Y585722D03*
X354525D03*
X334446Y585714D03*
X311021D03*
X327754D03*
X334446Y566814D03*
X341140Y566822D03*
X337793Y574757D03*
X344486D03*
X347833D03*
X351179Y566822D03*
X354526Y574757D03*
X354525Y566822D03*
X331100Y566814D03*
X334447Y574757D03*
X307675Y593657D03*
X334447D03*
X341140D03*
X344486D03*
X351179D03*
X354526D03*
X331100D03*
X314368D03*
X324407D03*
X321061D03*
X361218Y28014D03*
X401376Y9121D03*
X404722D03*
X411416Y9122D03*
X404723Y28022D03*
X401377D03*
X411416D03*
X404723Y17057D03*
X408069Y17042D03*
X414763Y9122D03*
X398029Y17042D03*
X414762Y17058D03*
X364265Y46914D03*
X361518D03*
X411416Y46922D03*
X411415Y36058D03*
X404723Y65822D03*
X414763D03*
X404723Y54857D03*
X401377Y46922D03*
Y35957D03*
X414763Y54857D03*
X398029Y54842D03*
X404723Y46922D03*
X414763Y35957D03*
Y46922D03*
X408069Y54842D03*
X394684Y35957D03*
X401377Y65822D03*
X411416D03*
Y73757D03*
X401377D03*
X404723D03*
X414763D03*
X401377Y529022D03*
X411416D03*
Y536957D03*
X411415Y547921D03*
X411416Y574757D03*
Y585722D03*
X401377Y566822D03*
X411416D03*
X414763Y585722D03*
X404723Y529022D03*
X408069Y555842D03*
X414763Y547922D03*
X404723D03*
X398029Y555842D03*
X414763Y555857D03*
X401376Y547922D03*
X404723Y555857D03*
Y536957D03*
X401377Y574757D03*
X404723Y566822D03*
Y585722D03*
X401377D03*
X394684Y574757D03*
X414763D03*
X404723D03*
X408069Y593642D03*
X398029D03*
X404723Y593657D03*
X438187Y9120D03*
X428147D03*
X434840D03*
X421455Y9121D03*
X444880Y28022D03*
X421456D03*
Y17057D03*
X428149Y28022D03*
X434842Y28268D03*
X438187Y17059D03*
X424801Y17042D03*
X444880Y9122D03*
Y17059D03*
X431494Y17042D03*
X421455Y46921D03*
X444880Y65822D03*
X421456D03*
X438189D03*
Y46922D03*
Y35957D03*
X431494Y54842D03*
X444880Y54859D03*
Y46922D03*
X428149Y35957D03*
Y46922D03*
X421456Y54857D03*
X434842Y46922D03*
Y35957D03*
X424801Y54842D03*
X438187Y54859D03*
X421456Y35957D03*
X434842Y65822D03*
X428149D03*
X421456Y73757D03*
X438189D03*
X428149D03*
X458640Y200596D03*
X421456Y585722D03*
X428149Y529022D03*
X434842D03*
X421456Y547922D03*
X428149Y566822D03*
X434842D03*
X438189Y536957D03*
X438187Y555859D03*
X424801Y555842D03*
X434842Y547922D03*
X421456Y555857D03*
X428149Y547922D03*
X444880D03*
Y555859D03*
X431494Y555842D03*
X438189Y547922D03*
X428149Y536957D03*
X444880Y585722D03*
X438189D03*
Y566822D03*
X434842Y574757D03*
X421456Y566822D03*
X428149Y574757D03*
X444882D03*
X438189D03*
X434842Y585722D03*
X428149D03*
X444880Y593659D03*
X431494Y593642D03*
X424801D03*
X421456Y593657D03*
X957283Y28014D03*
Y17057D03*
X970669Y28014D03*
X963976D03*
X967322Y9114D03*
X960629D03*
X963976Y17057D03*
X970669D03*
X957536Y67802D03*
X957283Y54857D03*
X970669D03*
X960629Y35957D03*
X963976Y54857D03*
X960629Y46914D03*
X967322Y35957D03*
Y73757D03*
X963976Y65814D03*
X970669D03*
X967322Y46914D03*
X970392Y203219D03*
X967322Y536957D03*
X957806Y528863D03*
X960629Y547914D03*
X967322Y574757D03*
X957283Y555857D03*
X957592Y566743D03*
X970669Y555857D03*
Y566814D03*
X963976Y555857D03*
X967322Y585714D03*
Y547914D03*
X960629Y585714D03*
X957283Y593657D03*
X963976D03*
X970669D03*
X974015Y28014D03*
X994094Y28022D03*
X990748D03*
X1004133D03*
X1000787D03*
X984055Y17057D03*
X990748D03*
X987401Y9114D03*
X994094Y17057D03*
Y9122D03*
X997441D03*
X1000787Y17057D03*
X1004133Y9122D03*
X1004134Y17057D03*
X980708D03*
X984054Y9114D03*
X974015D03*
Y17057D03*
X977362Y9114D03*
X984054Y28014D03*
X980708D03*
X977362Y35957D03*
Y46914D03*
X974015Y54857D03*
X997441Y46922D03*
Y35957D03*
X994094Y46922D03*
Y35957D03*
Y54857D03*
X987401Y46914D03*
Y35957D03*
X990748Y54857D03*
X1004134D03*
Y35957D03*
X1004133Y46922D03*
X1000787Y54857D03*
X984054Y65814D03*
X990748Y65822D03*
X994094D03*
X1000787D03*
X1004133D03*
X980708Y65814D03*
X974015D03*
X987401Y73757D03*
X994094D03*
X997441D03*
X1004134D03*
X984055D03*
X974015D03*
X977362D03*
X974015Y35957D03*
Y46914D03*
X984055Y54857D03*
X980708D03*
X984054Y46914D03*
X984055Y35957D03*
X980556Y201258D03*
X977362Y536957D03*
X974015D03*
X984055D03*
X980708Y529014D03*
X977362Y547914D03*
X974015D03*
X984054D03*
X997441Y547922D03*
X994094D03*
X987401Y547914D03*
X997441Y585722D03*
X977362Y574757D03*
X974015Y555857D03*
Y566814D03*
Y574757D03*
X984055D03*
X980708Y555857D03*
Y566814D03*
X994094Y574757D03*
Y555857D03*
Y566822D03*
X990748Y555857D03*
Y566822D03*
X984055Y555857D03*
X984054Y566814D03*
X977362Y585714D03*
X1004133Y547922D03*
X1004134Y555857D03*
X1004133Y566822D03*
X1004134Y574757D03*
X1000787Y555857D03*
Y566822D03*
X1004133Y585722D03*
X974015Y529014D03*
X990748Y529022D03*
X987401Y536957D03*
X994094D03*
X997441D03*
X1000787Y529022D03*
X1004134Y536957D03*
X987401Y585714D03*
X994094Y585722D03*
X984054Y585714D03*
X974015D03*
X980708Y593657D03*
X984055D03*
X990748D03*
X994094D03*
X1000787D03*
X1004134D03*
X974015D03*
X1054331Y28022D03*
X1050985D03*
X1071064Y9122D03*
X1064371Y28022D03*
X1094488D03*
X1087797D03*
X1061024D03*
X1077757D03*
X1084450Y28098D03*
X1071064Y17057D03*
X1061024Y9122D03*
X1094488D03*
Y17059D03*
X1081102Y17042D03*
X1064371Y17057D03*
X1087797Y9122D03*
X1050985D03*
X1054331Y17057D03*
X1071064Y28022D03*
X1087795Y17059D03*
X1074409Y17042D03*
X1084450Y9122D03*
X1057677Y17042D03*
X1064371Y9122D03*
X1077757D03*
X1054331D03*
X1047637Y17042D03*
X1054331Y54857D03*
X1047637Y54842D03*
X1057677D03*
X1044292Y35957D03*
X1050985Y65822D03*
X1071064Y46922D03*
X1094490Y35957D03*
X1064371Y54857D03*
X1081102Y54842D03*
X1094488Y54859D03*
Y46922D03*
X1064371Y35957D03*
Y46922D03*
X1074409Y54842D03*
X1087795Y54859D03*
X1071064Y35957D03*
X1061024Y65822D03*
X1084450D03*
X1077757D03*
X1071064Y73757D03*
X1061024D03*
X1071064Y65822D03*
X1064371D03*
X1054331D03*
X1064371Y73757D03*
X1054331D03*
X1050985D03*
X1087797Y65822D03*
X1094488D03*
X1087797Y73757D03*
X1084450D03*
X1077757D03*
X1061024Y46922D03*
Y35957D03*
X1084450D03*
Y46922D03*
X1071064Y54857D03*
X1077757Y35957D03*
Y46922D03*
X1054331Y35957D03*
Y46922D03*
X1087797Y35957D03*
Y46922D03*
X1050985Y35957D03*
Y46922D03*
Y536957D03*
X1054331D03*
X1050984Y547922D03*
X1054331D03*
X1050985Y529022D03*
Y566822D03*
X1054331Y555857D03*
Y566822D03*
X1050985Y574757D03*
X1047637Y555842D03*
X1054331Y574757D03*
X1057677Y555842D03*
X1044292Y574757D03*
X1050985Y585722D03*
X1054331D03*
X1064371Y547922D03*
X1084450D03*
X1061024Y529022D03*
X1084450D03*
X1077757D03*
X1067716Y547907D03*
X1061024Y536957D03*
Y547922D03*
X1071064D03*
X1087797Y536957D03*
X1077757D03*
X1071064Y529022D03*
X1084450Y536957D03*
X1087797Y547922D03*
X1094488D03*
X1064371Y574757D03*
X1071064Y555857D03*
Y566822D03*
X1084450Y574757D03*
X1074409Y555842D03*
X1087795Y555859D03*
X1087797Y585722D03*
X1064371D03*
X1084450D03*
X1071064Y574757D03*
X1061024Y566822D03*
X1084450D03*
X1077757D03*
X1061024Y574757D03*
Y585722D03*
X1071064D03*
X1087797Y574757D03*
X1064371Y566822D03*
X1094488D03*
X1064371Y555857D03*
X1081102Y555842D03*
X1094488Y555859D03*
X1064371Y536957D03*
X1077757Y547922D03*
Y585722D03*
Y574757D03*
X1094488Y585722D03*
X1071064Y593657D03*
X1087795Y593659D03*
X1057677Y593642D03*
X1047637D03*
X1094488Y593659D03*
X1081102Y593642D03*
X1064371Y593657D03*
X1054331D03*
X1108248Y200596D03*
X1111631Y198327D03*
X1445454Y267304D03*
X1458102Y270402D03*
X1458052Y273603D03*
Y276753D03*
X1445454D03*
X1442304Y279902D03*
X1461400Y264700D03*
X1458052Y279902D03*
X1451753Y270454D03*
X1461202Y276753D03*
X1448603Y279902D03*
X1464351Y276753D03*
X1461202Y279902D03*
Y273603D03*
X1451753D03*
Y267304D03*
X1448603Y270454D03*
Y267304D03*
X1442303Y267303D03*
X1454902Y276753D03*
X1451753Y279902D03*
X1442303Y270454D03*
X1461300Y270400D03*
X1445454Y279902D03*
X1448603Y276753D03*
X1442304Y273603D03*
X1454902D03*
X1451753Y276753D03*
X1454902Y279902D03*
X1445454Y270454D03*
X1448603Y273603D03*
X1454902Y270454D03*
X1464424Y273676D03*
X1445454Y273603D03*
X1464351Y279902D03*
X1454902Y311397D03*
X1463610Y321329D03*
X1451753Y301948D03*
X1445454D03*
X1464351Y311397D03*
X1461202D03*
X1458052Y308247D03*
X1464351Y301948D03*
X1451753Y298798D03*
X1458052Y311397D03*
X1454902Y295649D03*
X1445454Y311397D03*
X1442304D03*
X1454902Y298798D03*
X1464351Y305098D03*
X1458052Y295649D03*
X1448603Y301948D03*
X1442304Y308247D03*
X1448603Y298798D03*
X1445454D03*
X1458052Y314546D03*
X1462776Y318200D03*
X1451753Y314546D03*
X1448603Y308247D03*
X1454902Y305098D03*
X1448603Y311397D03*
X1458051Y301949D03*
X1464351Y295649D03*
X1442304Y305098D03*
X1445454Y308247D03*
X1448603Y314546D03*
X1454928Y317723D03*
X1461202Y305098D03*
X1440910Y316693D03*
X1458052Y298798D03*
X1451753Y317696D03*
X1458052Y305098D03*
X1448603Y317696D03*
X1458400Y318500D03*
X1445454Y305098D03*
X1448603D03*
X1454902Y308247D03*
X1451753Y305098D03*
X1442303Y298799D03*
X1464351Y298798D03*
X1461202D03*
Y295649D03*
X1445528Y317772D03*
X1454902Y301948D03*
X1461202D03*
Y314546D03*
X1464350Y308247D03*
X1445427Y295624D03*
X1448577D03*
X1451751Y295649D03*
X1454902Y314546D03*
X1448603Y283053D03*
X1461202Y283052D03*
X1445454Y289351D03*
X1451753D03*
X1454902Y283052D03*
X1442304Y289350D03*
X1458052Y286202D03*
X1454902Y289351D03*
Y286202D03*
X1454751Y292651D03*
X1442304Y292499D03*
X1448603Y289351D03*
X1458052D03*
X1464351Y283052D03*
X1461202Y286202D03*
X1464351D03*
X1461202Y289351D03*
X1451754Y283053D03*
X1448603Y286202D03*
X1451753D03*
X1464351Y289351D03*
X1458051Y283051D03*
X1451753Y311397D03*
X1445427Y292526D03*
X1470649Y279902D03*
Y270454D03*
Y276753D03*
X1469829Y266909D03*
X1470649Y273603D03*
X1480098Y270454D03*
X1483247Y273603D03*
Y270454D03*
X1489546Y279902D03*
X1473798Y276753D03*
X1476948Y273603D03*
X1480098Y267304D03*
X1476948Y270454D03*
X1473798D03*
X1480098Y273603D03*
X1486397Y270454D03*
X1483247Y267304D03*
X1476948Y279902D03*
X1473798D03*
X1480098Y276753D03*
X1483247Y279902D03*
X1476948Y276753D03*
X1486574Y267127D03*
X1496030Y267665D03*
X1473798Y273603D03*
X1489546Y270454D03*
X1486397Y273603D03*
X1483247Y276753D03*
X1470649Y305098D03*
Y311397D03*
Y301948D03*
Y308247D03*
Y314546D03*
Y295649D03*
Y298798D03*
Y283052D03*
Y286202D03*
Y289351D03*
X1480098Y305098D03*
X1476949Y301949D03*
X1486397Y311397D03*
X1489546Y314546D03*
X1473798Y305098D03*
X1480098Y301948D03*
Y298798D03*
X1495651Y311350D03*
X1493400Y300800D03*
X1486397Y298798D03*
X1480098Y295649D03*
X1476948Y298798D03*
X1489546Y286202D03*
X1486397Y305098D03*
X1473798Y295649D03*
X1483247Y305098D03*
X1480098Y308247D03*
X1473798Y298798D03*
X1492696Y314546D03*
X1473798Y308247D03*
X1476948Y305098D03*
X1497509Y303120D03*
X1489546Y308247D03*
X1476948Y311397D03*
X1489546Y317696D03*
X1486397Y295649D03*
Y308247D03*
X1483247Y298798D03*
X1473798Y301948D03*
X1476948Y295649D03*
X1486396Y317696D03*
X1495699Y314546D03*
X1476948Y308247D03*
X1473798Y314546D03*
X1483247D03*
X1489546Y301948D03*
Y311397D03*
X1486397Y314546D03*
X1483247Y311397D03*
X1492700Y311376D03*
X1495300Y297300D03*
X1478524Y318900D03*
X1480098Y311397D03*
X1483247Y301948D03*
X1473798Y311397D03*
X1493500Y304400D03*
X1486397Y301948D03*
X1483247Y308247D03*
X1476948Y286202D03*
X1483247D03*
Y289351D03*
Y283052D03*
X1473798D03*
X1486397Y286202D03*
X1480098D03*
X1476948Y289351D03*
X1480098Y283052D03*
X1473798Y289351D03*
Y286202D03*
X1486397Y283052D03*
X1476949Y283051D03*
X1480098Y314546D03*
X1588176Y157600D03*
X1604000Y93925D03*
X1606470Y93759D03*
X1632574Y106107D03*
X1594565Y148720D03*
X1635750Y128240D03*
X1648393Y153280D03*
X1642150Y118660D03*
X1651536Y134388D03*
X1642087Y143837D03*
X1648386Y156435D03*
X1651532Y137534D03*
X1590569Y152464D03*
X1595390Y151778D03*
X1638938Y109192D03*
X1638250Y125750D03*
X1651536Y121790D03*
X1638938Y118641D03*
X1645378Y128378D03*
X1638902Y112305D03*
X1648430Y150163D03*
X1638937Y131239D03*
Y143837D03*
Y137538D03*
X1638938Y153286D03*
X1648387Y115491D03*
X1651536D03*
X1645237D03*
X1641770Y112340D03*
X1645237Y112341D03*
X1651536D03*
Y128089D03*
X1642087Y124940D03*
X1645237D03*
X1637363Y149484D03*
X1651536Y140687D03*
Y143837D03*
Y131239D03*
Y124939D03*
X1645237Y118640D03*
X1642087Y153286D03*
X1642084Y115494D03*
X1648387Y112341D03*
Y109191D03*
X1651536D03*
X1645237D03*
X1600182Y148562D03*
X1607401Y146947D03*
X1604292Y150137D03*
X1600148Y142262D03*
X1610645Y143783D03*
X1613741Y118640D03*
X1629489Y153286D03*
X1620040Y134388D03*
Y128089D03*
X1616891D03*
X1607441Y112341D03*
X1610591Y118640D03*
X1600490Y110766D03*
X1607441Y115491D03*
X1598190Y110711D03*
X1610591Y112341D03*
X1613741Y153286D03*
X1616848Y115449D03*
X1616890Y112341D03*
X1632638Y115491D03*
Y112341D03*
X1632615Y109215D03*
X1629489Y115491D03*
X1610591Y121790D03*
X1613741D03*
X1620100Y153300D03*
X1613741Y146987D03*
X1616891Y150137D03*
X1616900Y153200D03*
X1629489Y150136D03*
X1616891Y146987D03*
X1616893Y140782D03*
X1635788Y137538D03*
Y143837D03*
Y131239D03*
X1616891Y134389D03*
X1629489Y137538D03*
Y143837D03*
Y131239D03*
X1620040Y106042D03*
X1623189Y118640D03*
X1629489D03*
X1610793Y109190D03*
X1607441Y118640D03*
X1616891Y124939D03*
X1596220Y109470D03*
X1613741Y115491D03*
X1602717Y102240D03*
X1610591Y115491D03*
Y128089D03*
X1604292Y134388D03*
X1607441Y137538D03*
X1607239Y131358D03*
X1604292Y137538D03*
X1607441Y121790D03*
X1626339Y124940D03*
X1626313Y153312D03*
X1632638Y153286D03*
X1620100Y150200D03*
X1620040Y146987D03*
Y140687D03*
X1632639Y124940D03*
Y118640D03*
X1635788D03*
X1626364Y121765D03*
X1626339Y150136D03*
X1635788Y153286D03*
X1623190Y146987D03*
Y140687D03*
Y134388D03*
Y128089D03*
Y124940D03*
X1607441Y124939D03*
X1623200Y153100D03*
X1626300Y112300D03*
X1626339Y109191D03*
Y118651D03*
X1613741Y128089D03*
X1626339Y115491D03*
X1613741Y156436D03*
Y150137D03*
X1607441Y106042D03*
X1610591Y146987D03*
X1607441Y143837D03*
X1608000Y99400D03*
X1613741Y134389D03*
X1613690Y124990D03*
X1613741Y140688D03*
X1610591Y134389D03*
X1600900Y131900D03*
X1607441Y153286D03*
X1613741Y137538D03*
X1610591Y150137D03*
Y124939D03*
Y137538D03*
Y140688D03*
X1607441Y134389D03*
X1616900Y143880D03*
X1616890Y118641D03*
X1613741Y109191D03*
Y106042D03*
X1607441Y156436D03*
X1610591Y153286D03*
X1604169Y156407D03*
X1610591Y156436D03*
X1600148Y151711D03*
X1651536Y146988D03*
Y156435D03*
X1629489Y112341D03*
X1629487Y109280D03*
X1629400Y106131D03*
X1648320Y172690D03*
X1635788Y162735D03*
X1591950Y158250D03*
X1595042Y172184D03*
X1600490Y158010D03*
X1596427Y157975D03*
X1645237Y165884D03*
X1648387Y159585D03*
X1651536D03*
X1645151Y162649D03*
X1642101Y162749D03*
X1651536Y165884D03*
X1642088Y165885D03*
X1638938Y165884D03*
X1651536Y162735D03*
X1642087Y159585D03*
X1645237D03*
X1648326Y162674D03*
X1648386Y165885D03*
X1635788Y159585D03*
X1629489D03*
X1616890Y162735D03*
X1613741Y159585D03*
X1613650Y173750D03*
X1609222Y173389D03*
X1620041Y165885D03*
X1620006Y168956D03*
X1615900Y172800D03*
X1608731Y180819D03*
X1635788Y165885D03*
X1597642Y172184D03*
X1616891Y165885D03*
X1613741D03*
X1610591Y159585D03*
X1622217Y177809D03*
X1610591Y162735D03*
X1611500Y172900D03*
X1629489Y165884D03*
X1621942Y173237D03*
X1624966Y172936D03*
X1629489Y162735D03*
X1600490Y167459D03*
X1623276Y165798D03*
X1626339Y162735D03*
X1607441D03*
X1613741D03*
X1607442Y159585D03*
X1620040Y162735D03*
X1627998Y172854D03*
X1601142Y172185D03*
X1616890Y159585D03*
X1626339Y165884D03*
X1623189Y159585D03*
X1623250Y162611D03*
X1626339Y159585D03*
X1620040D03*
X1610591Y165885D03*
X1643662Y172609D03*
X1638938Y162735D03*
Y159585D03*
X1616286Y176515D03*
X1674685Y134217D03*
X1693625Y133220D03*
X1680402Y128652D03*
X1678127Y117293D03*
X1673883Y124308D03*
X1660985Y156435D03*
X1667348Y156500D03*
X1660985Y118640D03*
X1667284Y115491D03*
X1654686Y109191D03*
X1654673Y118628D03*
X1654685Y112341D03*
X1653111Y102240D03*
X1654685Y146987D03*
X1654686Y156436D03*
X1654678Y137530D03*
X1657835Y134389D03*
X1671000Y103000D03*
X1670434Y115491D03*
X1657835Y112341D03*
X1660985Y115491D03*
X1657835Y118640D03*
X1664135Y115491D03*
Y118640D03*
X1709000Y127200D03*
X1691207Y139891D03*
X1681586Y141438D03*
X1660986Y137538D03*
X1667238Y112387D03*
X1667284Y137537D03*
X1657835Y124940D03*
Y150136D03*
X1667284Y121790D03*
Y128089D03*
Y150136D03*
X1658154Y99400D03*
X1657835Y115491D03*
Y109191D03*
X1660985D03*
Y112341D03*
X1664134Y140688D03*
Y156436D03*
X1664135Y112341D03*
X1695236Y135788D03*
Y138938D03*
X1676886Y120038D03*
Y123188D03*
X1660985Y146987D03*
X1657836Y137538D03*
X1654686Y153288D03*
Y134389D03*
X1693586Y142438D03*
X1654686Y150138D03*
X1660985Y131239D03*
X1657835Y121790D03*
X1660985D03*
X1667284Y131239D03*
X1654685D03*
X1664135Y128089D03*
X1657836Y140688D03*
X1660985Y124939D03*
X1654685Y140687D03*
X1664135Y153286D03*
X1664136Y137538D03*
X1657836Y153288D03*
X1657835Y143837D03*
X1664135Y121790D03*
X1660985Y128089D03*
Y150137D03*
X1664186Y147038D03*
X1657835Y146987D03*
X1654685Y143837D03*
X1660985D03*
X1677386Y132788D03*
Y129638D03*
X1660985Y140688D03*
X1654686Y124940D03*
X1657835Y162735D03*
X1660985D03*
X1654685D03*
X1654638Y159685D03*
X1668213Y172608D03*
X1657835Y165884D03*
X1660985Y165885D03*
X1657835Y159585D03*
X1665063Y172608D03*
X1660985Y159585D03*
X1688207Y168972D03*
X1689785Y161180D03*
X1729444Y123782D03*
X1726294Y101785D03*
X1735912Y123750D03*
X1742212Y117451D03*
X1717014Y148950D03*
X1714114D03*
X1717014Y97550D03*
Y104850D03*
Y108000D03*
Y111150D03*
Y133200D03*
Y139500D03*
X1743500Y96400D03*
X1739064Y108000D03*
X1742214Y101700D03*
X1735914D03*
X1745364Y117450D03*
Y114300D03*
Y98550D03*
X1745363Y108004D03*
X1746189Y153250D03*
X1755089Y150750D03*
X1752189Y136750D03*
X1746189Y134777D03*
Y131624D03*
X1752389Y132250D03*
X1754189Y124250D03*
X1757689Y123850D03*
X1752889Y146250D03*
X1745364Y145800D03*
Y142650D03*
X1731903Y133712D03*
X1745500Y104500D03*
X1726464Y117450D03*
X1720164Y97550D03*
Y111150D03*
X1723314D03*
X1720164Y117451D03*
X1723314Y117450D03*
X1720164Y120600D03*
Y123750D03*
X1723314D03*
X1720164Y133200D03*
Y126800D03*
X1751800Y141700D03*
X1745768Y111743D03*
X1742214Y98550D03*
Y126900D03*
X1745364Y123750D03*
X1742214D03*
X1745364Y120600D03*
X1742214Y114300D03*
Y111150D03*
X1739064Y114300D03*
X1720164Y139500D03*
X1723314Y101700D03*
X1731789Y139450D03*
X1717014Y142650D03*
X1723314Y133200D03*
Y108000D03*
X1726464Y111150D03*
X1723314Y139500D03*
X1739064D03*
X1726464Y133200D03*
X1735914Y108000D03*
X1739064Y123750D03*
X1726464Y120600D03*
X1742214D03*
X1739064Y130050D03*
Y142650D03*
X1726464Y123750D03*
X1720164Y104850D03*
X1742214Y142650D03*
X1726464Y145800D03*
X1723314Y104850D03*
X1720164Y108000D03*
X1734989Y142750D03*
X1723314Y98550D03*
X1735914Y117450D03*
X1728789Y136250D03*
X1723264Y145850D03*
X1739064Y145800D03*
X1723314Y130050D03*
X1735914Y104850D03*
X1735989Y149050D03*
X1742214Y130050D03*
X1726539Y139450D03*
X1720164Y145800D03*
X1739064Y117450D03*
X1723314Y126900D03*
X1735989Y133250D03*
X1739064Y120600D03*
X1723314Y120601D03*
X1739064Y126900D03*
X1735914Y139500D03*
X1739064Y136350D03*
X1723314Y142650D03*
X1742214Y145800D03*
G54D58*
X67500Y276800D03*
X84522Y389977D03*
X90811Y444806D03*
X100287Y426488D03*
X97916Y436463D03*
X82464Y407622D03*
X81387Y434036D03*
X103799Y431342D03*
X91900Y429101D03*
X599199Y240594D03*
X1077942Y112727D03*
X1371834Y263088D03*
X1366331Y258929D03*
X1378550Y344550D03*
X1450413Y246661D03*
X1476265Y437109D03*
X1565671Y534929D03*
X1576454Y547056D03*
X1624547Y123148D03*
X1624064Y174709D03*
G54D188*
X1804450Y597938D03*
Y594001D03*
Y595970D03*
Y592032D03*
Y590064D03*
G54D77*
X317942Y32100D03*
X312442D03*
X330142D03*
X324642D03*
X343142D03*
X337642D03*
X348000D03*
X353500D03*
X317942Y69900D03*
X312442D03*
X330142D03*
X324642D03*
X343142D03*
X337642D03*
X348000D03*
X353500D03*
X307492Y109500D03*
X312992D03*
X323292Y107100D03*
X317792D03*
X307692Y495600D03*
X313192D03*
X323670Y494675D03*
X318170D03*
X317942Y533100D03*
X312442D03*
X330142D03*
X324642D03*
X343142D03*
X337642D03*
X348000D03*
X353500D03*
X317942Y570900D03*
X312442D03*
X330142D03*
X324642D03*
X343142D03*
X337642D03*
X348000D03*
X353500D03*
X362392Y31800D03*
X367892D03*
X390900Y-15300D03*
X396400D03*
X399200Y32100D03*
X404700D03*
X411650D03*
X417150D03*
X361592Y69400D03*
X367092D03*
X399200Y69900D03*
X404700D03*
X411650D03*
X417150D03*
X383580Y497770D03*
X378080D03*
X360962Y532800D03*
X366462D03*
X401950Y533100D03*
X396450D03*
X360982Y570460D03*
X366482D03*
X411650Y533100D03*
X417150D03*
X399200Y570900D03*
X404700D03*
X411650D03*
X417150D03*
X424650Y32100D03*
X430150D03*
X437008D03*
X442508D03*
X424650Y69900D03*
X430150D03*
X437008D03*
X442508D03*
X445550Y113710D03*
X440050D03*
X452120Y490771D03*
X446620D03*
X424650Y533100D03*
X430150D03*
X438508D03*
X444008D03*
X424650Y570900D03*
X430150D03*
X437008D03*
X442508D03*
X967550Y32100D03*
X962050D03*
X967550Y69900D03*
X962050D03*
X972900Y107100D03*
X967400D03*
X957100Y109500D03*
X962600D03*
X957300Y494315D03*
X962800D03*
X967778D03*
X967550Y533100D03*
X962050D03*
X967550Y570900D03*
X962050D03*
X1012000Y31800D03*
X1017500D03*
X979750Y32100D03*
X974250D03*
X992750D03*
X987250D03*
X997608D03*
X1003108D03*
X1012000Y69400D03*
X1017500D03*
X979750Y69900D03*
X974250D03*
X992750D03*
X987250D03*
X997608D03*
X1003108D03*
X1020800Y104233D03*
X1026300D03*
X1017800Y496600D03*
X1023300D03*
X973278Y494315D03*
X1011500Y532800D03*
X1017000D03*
X1011050Y570400D03*
X1016550D03*
X979750Y533100D03*
X974250D03*
X992750D03*
X987250D03*
X997608D03*
X1003108D03*
X979750Y570900D03*
X974250D03*
X992750D03*
X987250D03*
X997608D03*
X1003108D03*
X1048808Y32100D03*
X1054308D03*
X1061258D03*
X1066758D03*
X1074258D03*
X1079758D03*
X1086616D03*
X1092116D03*
X1048808Y69900D03*
X1054308D03*
X1061258D03*
X1066758D03*
X1074258D03*
X1079758D03*
X1086616D03*
X1092116D03*
X1094900Y111400D03*
X1089400D03*
X1095788Y494860D03*
X1090288D03*
X1051558Y533100D03*
X1046058D03*
X1061258D03*
X1066758D03*
X1074258D03*
X1079758D03*
X1048808Y570900D03*
X1054308D03*
X1061258D03*
X1066758D03*
X1074258D03*
X1079758D03*
X1086616D03*
X1092116D03*
X1088116Y533100D03*
X1093616D03*
X1319119Y155667D03*
X1313619D03*
X1319119Y150629D03*
X1313619D03*
G54D86*
X601995Y156616D03*
G54D59*
X61200Y274300D03*
X1339862Y256652D03*
X1397910Y248590D03*
X1389637Y258137D03*
X1346683Y251175D03*
X1353668Y255112D03*
X1368828Y247672D03*
X1382472Y256172D03*
X1346640Y260796D03*
X1362848Y252308D03*
X1387012Y250288D03*
X1528368Y508532D03*
X1583861Y67690D03*
X1597307Y114193D03*
X1750253Y135786D03*
X1716228Y154772D03*
X1931994Y212699D03*
X1928449Y226251D03*
G54D179*
X1756417Y563840D03*
X1810052Y536001D03*
X1810552Y594001D03*
G54D197*
X1872938Y483295D03*
Y485263D03*
Y489200D03*
Y491169D03*
X1875237Y483295D03*
Y485263D03*
Y489200D03*
Y491169D03*
X1960252Y180204D03*
Y182172D03*
Y186109D03*
Y188078D03*
X1962551Y180204D03*
Y182172D03*
Y186109D03*
Y188078D03*
G54D68*
X94000Y310400D03*
X882380Y355289D03*
X1319247Y266720D03*
X1324460Y260962D03*
X1329815Y255507D03*
X1318297Y255241D03*
X1323510Y272768D03*
X1328865Y266711D03*
X1470500Y163700D03*
X1476800Y234017D03*
X1484890Y268660D03*
X1478400Y267500D03*
X1500000Y353010D03*
X1528400Y502500D03*
X1590293Y51938D03*
X1626600Y356893D03*
X1729189Y150153D03*
X1740889Y151176D03*
X1751189Y123542D03*
X1936170Y233087D03*
X1935220Y226688D03*
X1959200Y574929D03*
G54D95*
X541260Y429470D03*
X540310Y443259D03*
G54D189*
X1816654Y594001D03*
Y590064D03*
Y592032D03*
Y595970D03*
Y597938D03*
G54D198*
X1874087Y487232D03*
X1961401Y184141D03*
G54D87*
X601747Y170876D03*
G54D96*
X632584Y147965D03*
X671037Y176163D03*
G54D69*
X64500Y355700D03*
X68000D03*
X667500Y254200D03*
X1504631Y601856D03*
X1466610Y604329D03*
G54D78*
X334927Y496030D03*
X347527D03*
X375817Y-13700D03*
X435503Y117880D03*
X448103D03*
X1025146Y-8361D03*
X1005695Y620380D03*
X1084925Y115500D03*
X1050525Y490900D03*
X1038025D03*
X1097525Y115500D03*
G54D97*
X622421Y126575D03*
G54D79*
X336577Y496030D03*
X349177D03*
X377467Y-13700D03*
X437153Y117880D03*
X449753D03*
X1026796Y-8361D03*
X1007345Y620380D03*
X1086575Y115500D03*
X1052175Y490900D03*
X1039675D03*
X1099175Y115500D03*
G54D199*
X1856950Y488500D03*
Y491650D03*
X1864950D03*
Y488500D03*
X1919780Y236286D03*
Y239436D03*
X1927780D03*
Y236286D03*
X1911755Y228753D03*
Y231903D03*
X1919755D03*
Y228753D03*
G54D88*
X580659Y334764D03*
G54D89*
X589349Y335730D03*
G54D98*
X649591Y138067D03*
X652282Y184964D03*
G54D99*
X634264Y197080D03*
M02*
